A!NET_NAME!REFDES!PIN_NUMBER!FUNC_LOGICAL_PATH!COMP_DEVICE_TYPE!FUNC_SCH_SIZE!FUNC_HAS_FIXED_SIZE!FUNC_DES!PIN_CDS_PINID!PIN_TERMINATION!PIN_TERM_IDENT!PIN_NET_SHORT!
J!K:/<user>/emsd/Crescent_City/baseboard_fab2/worklib/baseboard_fab2/physical/crescent_city_fab2_2v290_20151002_C_gridout2.brd!Fri Oct 02 10:47:54 2015!-30224.80!-14061.09!740148.33!322724.71!0.01!mils!BASEBOARD_FAB2!89.440157 mil!14!UP TO DATE!
S!GND!U1M6!3!!74CBTLV1G125_SMLF-IC,C88177-00A!!!!!!!!
S!P3V3_STBY!U1M6!5!!74CBTLV1G125_SMLF-IC,C88177-00A!!!!!!!!
S!JTAG_MCP_CPU0_TDO!U1M6!2!@baseboard_fab2_lib.baseboard_fab2(sch_1):page113_i127@mstr_ttl.\74cbtlv1g125\(chips)!74CBTLV1G125_SMLF-IC,C88177-00A!!!F4206!A!!!!
S!JTAG_MCP_CPU1_TDI!U1M6!4!@baseboard_fab2_lib.baseboard_fab2(sch_1):page113_i127@mstr_ttl.\74cbtlv1g125\(chips)!74CBTLV1G125_SMLF-IC,C88177-00A!!!F4206!B!!!!
S!FM_CPU0_AND_CPU1_MCP_PRES!U1M6!1!@baseboard_fab2_lib.baseboard_fab2(sch_1):page113_i127@mstr_ttl.\74cbtlv1g125\(chips)!74CBTLV1G125_SMLF-IC,C88177-00A!!!F4206!OE_N!!!!
S!GND!U4R1!3!!74CBTLV1G125_SMLF-IC,C88177-00A!!!!!!!!
S!P3V3_STBY!U4R1!5!!74CBTLV1G125_SMLF-IC,C88177-00A!!!!!!!!
S!P1V8_MCP_CPU0!U4R1!2!@baseboard_fab2_lib.baseboard_fab2(sch_1):page113_i206@mstr_ttl.\74cbtlv1g125\(chips)!74CBTLV1G125_SMLF-IC,C88177-00A!!!F4205!A!!!!
S!JTAG_MCP_CPU0_TDI_R!U4R1!4!@baseboard_fab2_lib.baseboard_fab2(sch_1):page113_i206@mstr_ttl.\74cbtlv1g125\(chips)!74CBTLV1G125_SMLF-IC,C88177-00A!!!F4205!B!!!!
S!FM_CPU0_PKGID1!U4R1!1!@baseboard_fab2_lib.baseboard_fab2(sch_1):page113_i206@mstr_ttl.\74cbtlv1g125\(chips)!74CBTLV1G125_SMLF-IC,C88177-00A!!!F4205!OE_N!!!!
S!GND!U6M1!3!!74CBTLV1G125_SMLF-IC,C88177-00A!!!!!!!!
S!P3V3_STBY!U6M1!5!!74CBTLV1G125_SMLF-IC,C88177-00A!!!!!!!!
S!P1V8_MCP_CPU1!U6M1!2!@baseboard_fab2_lib.baseboard_fab2(sch_1):page113_i190@mstr_ttl.\74cbtlv1g125\(chips)!74CBTLV1G125_SMLF-IC,C88177-00A!!!F4204!A!!!!
S!JTAG_MCP_CPU1_TDI_R!U6M1!4!@baseboard_fab2_lib.baseboard_fab2(sch_1):page113_i190@mstr_ttl.\74cbtlv1g125\(chips)!74CBTLV1G125_SMLF-IC,C88177-00A!!!F4204!B!!!!
S!FM_CPU1_PKGID1!U6M1!1!@baseboard_fab2_lib.baseboard_fab2(sch_1):page113_i190@mstr_ttl.\74cbtlv1g125\(chips)!74CBTLV1G125_SMLF-IC,C88177-00A!!!F4204!OE_N!!!!
S!GND!U7D1!3!!74CBTLV1G125_SMLF-IC,C88177-00A!!!!!!!!
S!P3V3_STBY!U7D1!5!!74CBTLV1G125_SMLF-IC,C88177-00A!!!!!!!!
S!XDP_PCH_PWR_DEBUG_N!U7D1!2!@baseboard_fab2_lib.baseboard_fab2(sch_1):page118_i142@mstr_ttl.\74cbtlv1g125\(chips)!74CBTLV1G125_SMLF-IC,C88177-00A!!!F4203!A!!!!
S!PWRGD_PVCCIO_CPU0!U7D1!1!@baseboard_fab2_lib.baseboard_fab2(sch_1):page118_i142@mstr_ttl.\74cbtlv1g125\(chips)!74CBTLV1G125_SMLF-IC,C88177-00A!!!F4203!OE_N!!!!
S!XDP_CPU_PWR_DEBUG_N!U7D1!4!@baseboard_fab2_lib.baseboard_fab2(sch_1):page118_i142@mstr_ttl.\74cbtlv1g125\(chips)!74CBTLV1G125_SMLF-IC,C88177-00A!!!F4203!B!!!!
S!GND!U1M5!3!!74CBTLV1G125_SMLF-IC,C88177-00A!!!!!!!!
S!P3V3_STBY!U1M5!5!!74CBTLV1G125_SMLF-IC,C88177-00A!!!!!!!!
S!P1V8_MCP_CPU0!U1M5!2!@baseboard_fab2_lib.baseboard_fab2(sch_1):page113_i196@mstr_ttl.\74cbtlv1g125\(chips)!74CBTLV1G125_SMLF-IC,C88177-00A!!!F4202!A!!!!
S!JTAG_MCP_TMS_R1!U1M5!4!@baseboard_fab2_lib.baseboard_fab2(sch_1):page113_i196@mstr_ttl.\74cbtlv1g125\(chips)!74CBTLV1G125_SMLF-IC,C88177-00A!!!F4202!B!!!!
S!FM_CPU0_OR_CPU1_MCP_PRES!U1M5!1!@baseboard_fab2_lib.baseboard_fab2(sch_1):page113_i196@mstr_ttl.\74cbtlv1g125\(chips)!74CBTLV1G125_SMLF-IC,C88177-00A!!!F4202!OE_N!!!!
S!GND!U9A5!3!!74CBTLV1G125_SMLF-IC,C88177-00A!!!!!!!!
S!P3V3_STBY!U9A5!5!!74CBTLV1G125_SMLF-IC,C88177-00A!!!!!!!!
S!JTAG_MCP_TCK_R!U9A5!2!@baseboard_fab2_lib.baseboard_fab2(sch_1):page113_i185@mstr_ttl.\74cbtlv1g125\(chips)!74CBTLV1G125_SMLF-IC,C88177-00A!!!F4201!A!!!!
S!GND!U9A5!4!@baseboard_fab2_lib.baseboard_fab2(sch_1):page113_i185@mstr_ttl.\74cbtlv1g125\(chips)!74CBTLV1G125_SMLF-IC,C88177-00A!!!F4201!B!!!!
S!FM_CPU0_OR_CPU1_MCP_PRES!U9A5!1!@baseboard_fab2_lib.baseboard_fab2(sch_1):page113_i185@mstr_ttl.\74cbtlv1g125\(chips)!74CBTLV1G125_SMLF-IC,C88177-00A!!!F4201!OE_N!!!!
S!GND!U1M4!3!!74CBTLV1G125_SMLF-IC,C88177-00A!!!!!!!!
S!P3V3_STBY!U1M4!5!!74CBTLV1G125_SMLF-IC,C88177-00A!!!!!!!!
S!XDP_CPU0_TDO!U1M4!2!@baseboard_fab2_lib.baseboard_fab2(sch_1):page112_i127@mstr_ttl.\74cbtlv1g125\(chips)!74CBTLV1G125_SMLF-IC,C88177-00A!!!F4200!A!!!!
S!XDP_CPU1_TDI!U1M4!4!@baseboard_fab2_lib.baseboard_fab2(sch_1):page112_i127@mstr_ttl.\74cbtlv1g125\(chips)!74CBTLV1G125_SMLF-IC,C88177-00A!!!F4200!B!!!!
S!FM_CPU1_SKTOCC_LVT3_N!U1M4!1!@baseboard_fab2_lib.baseboard_fab2(sch_1):page112_i127@mstr_ttl.\74cbtlv1g125\(chips)!74CBTLV1G125_SMLF-IC,C88177-00A!!!F4200!OE_N!!!!
S!JTAG_MCP_MUX_TDO!U1M2!4!@baseboard_fab2_lib.baseboard_fab2(sch_1):page113_i107@mstr_analog.nc7sb3157(chips)!NC7SB3157_SMLF-IC,C99406-001!!!F2005!A!!!!
S!JTAG_MCP_CPU1_TDO!U1M2!3!@baseboard_fab2_lib.baseboard_fab2(sch_1):page113_i107@mstr_analog.nc7sb3157(chips)!NC7SB3157_SMLF-IC,C99406-001!!!F2005!B0!!!!
S!JTAG_MCP_CPU0_TDO!U1M2!1!@baseboard_fab2_lib.baseboard_fab2(sch_1):page113_i107@mstr_analog.nc7sb3157(chips)!NC7SB3157_SMLF-IC,C99406-001!!!F2005!B1!!!!
S!GND!U1M2!2!@baseboard_fab2_lib.baseboard_fab2(sch_1):page113_i107@mstr_analog.nc7sb3157(chips)!NC7SB3157_SMLF-IC,C99406-001!!!F2005!GND!!!!
S!FM_CPU1_CD_PRES!U1M2!6!@baseboard_fab2_lib.baseboard_fab2(sch_1):page113_i107@mstr_analog.nc7sb3157(chips)!NC7SB3157_SMLF-IC,C99406-001!!!F2005!S!!!!
S!P3V3_STBY!U1M2!5!@baseboard_fab2_lib.baseboard_fab2(sch_1):page113_i107@mstr_analog.nc7sb3157(chips)!NC7SB3157_SMLF-IC,C99406-001!!!F2005!VCC!!!!
S!XDP_CPU_TDO!U1M7!4!@baseboard_fab2_lib.baseboard_fab2(sch_1):page112_i40@mstr_analog.nc7sb3157(chips)!NC7SB3157_SMLF-IC,C99406-001!!!F2004!A!!!!
S!XDP_CPU1_TDO!U1M7!3!@baseboard_fab2_lib.baseboard_fab2(sch_1):page112_i40@mstr_analog.nc7sb3157(chips)!NC7SB3157_SMLF-IC,C99406-001!!!F2004!B0!!!!
S!XDP_CPU0_TDO!U1M7!1!@baseboard_fab2_lib.baseboard_fab2(sch_1):page112_i40@mstr_analog.nc7sb3157(chips)!NC7SB3157_SMLF-IC,C99406-001!!!F2004!B1!!!!
S!GND!U1M7!2!@baseboard_fab2_lib.baseboard_fab2(sch_1):page112_i40@mstr_analog.nc7sb3157(chips)!NC7SB3157_SMLF-IC,C99406-001!!!F2004!GND!!!!
S!FM_CPU1_SKTOCC_LVT3_N!U1M7!6!@baseboard_fab2_lib.baseboard_fab2(sch_1):page112_i40@mstr_analog.nc7sb3157(chips)!NC7SB3157_SMLF-IC,C99406-001!!!F2004!S!!!!
S!P3V3_STBY!U1M7!5!@baseboard_fab2_lib.baseboard_fab2(sch_1):page112_i40@mstr_analog.nc7sb3157(chips)!NC7SB3157_SMLF-IC,C99406-001!!!F2004!VCC!!!!
S!JTAG_MCP_MUX_TDI!U2M1!4!@baseboard_fab2_lib.baseboard_fab2(sch_1):page113_i255@mstr_analog.nc7sb3157(chips)!NC7SB3157_SMLF-IC,C99406-001!!!F2003!A!!!!
S!JTAG_MCP_CPU1_TDI!U2M1!3!@baseboard_fab2_lib.baseboard_fab2(sch_1):page113_i255@mstr_analog.nc7sb3157(chips)!NC7SB3157_SMLF-IC,C99406-001!!!F2003!B0!!!!
S!JTAG_MCP_CPU0_TDI!U2M1!1!@baseboard_fab2_lib.baseboard_fab2(sch_1):page113_i255@mstr_analog.nc7sb3157(chips)!NC7SB3157_SMLF-IC,C99406-001!!!F2003!B1!!!!
S!GND!U2M1!2!@baseboard_fab2_lib.baseboard_fab2(sch_1):page113_i255@mstr_analog.nc7sb3157(chips)!NC7SB3157_SMLF-IC,C99406-001!!!F2003!GND!!!!
S!FM_CPU0_CD_PRES!U2M1!6!@baseboard_fab2_lib.baseboard_fab2(sch_1):page113_i255@mstr_analog.nc7sb3157(chips)!NC7SB3157_SMLF-IC,C99406-001!!!F2003!S!!!!
S!P3V3_STBY!U2M1!5!@baseboard_fab2_lib.baseboard_fab2(sch_1):page113_i255@mstr_analog.nc7sb3157(chips)!NC7SB3157_SMLF-IC,C99406-001!!!F2003!VCC!!!!
S!A_HSC_TEMP!Q1D3!1!@baseboard_fab2_lib.baseboard_fab2(sch_1):page199_i58@mstr_discrete.npn(chips)!NPN_SM-MMBT3904,IC,C52245-001!!!F1994!B!!!!
S!A_HSC_TEMP!Q1D3!3!@baseboard_fab2_lib.baseboard_fab2(sch_1):page199_i58@mstr_discrete.npn(chips)!NPN_SM-MMBT3904,IC,C52245-001!!!F1994!C!!!!
S!GND!Q1D3!2!@baseboard_fab2_lib.baseboard_fab2(sch_1):page199_i58@mstr_discrete.npn(chips)!NPN_SM-MMBT3904,IC,C52245-001!!!F1994!E!!!!
S!FM_UART_SEL_N!Q1L1!1!@baseboard_fab2_lib.baseboard_fab2(sch_1):page168_i9@mstr_discrete.npn(chips)!NPN_SM-MMBT3904,IC,C52245-001!!!F1993!B!!!!
S!FM_SOL_UART_CH_SEL!Q1L1!3!@baseboard_fab2_lib.baseboard_fab2(sch_1):page168_i9@mstr_discrete.npn(chips)!NPN_SM-MMBT3904,IC,C52245-001!!!F1993!C!!!!
S!GND!Q1L1!2!@baseboard_fab2_lib.baseboard_fab2(sch_1):page168_i9@mstr_discrete.npn(chips)!NPN_SM-MMBT3904,IC,C52245-001!!!F1993!E!!!!
S!FM_DB_UART_SEL4_N!Q1L3!1!@baseboard_fab2_lib.baseboard_fab2(sch_1):page168_i8@mstr_discrete.npn(chips)!NPN_SM-MMBT3904,IC,C52245-001!!!F1992!B!!!!
S!FM_DB_PRESENT!Q1L3!3!@baseboard_fab2_lib.baseboard_fab2(sch_1):page168_i8@mstr_discrete.npn(chips)!NPN_SM-MMBT3904,IC,C52245-001!!!F1992!C!!!!
S!GND!Q1L3!2!@baseboard_fab2_lib.baseboard_fab2(sch_1):page168_i8@mstr_discrete.npn(chips)!NPN_SM-MMBT3904,IC,C52245-001!!!F1992!E!!!!
S!H_CPU0_FAST_WAKE_B_N!Q2T1!1!@baseboard_fab2_lib.baseboard_fab2(sch_1):page157_i330@mstr_discrete.npn(chips)!NPN_SM-MMBT3904,IC,C52245-001!!!F1991!B!!!!
S!H_CPU0_FAST_WAKE!Q2T1!3!@baseboard_fab2_lib.baseboard_fab2(sch_1):page157_i330@mstr_discrete.npn(chips)!NPN_SM-MMBT3904,IC,C52245-001!!!F1991!C!!!!
S!GND!Q2T1!2!@baseboard_fab2_lib.baseboard_fab2(sch_1):page157_i330@mstr_discrete.npn(chips)!NPN_SM-MMBT3904,IC,C52245-001!!!F1991!E!!!!
S!FM_MATED_IN_D2_N!Q9T1!1!@baseboard_fab2_lib.baseboard_fab2(sch_1):page181_i181@mstr_discrete.npn(chips)!NPN_SM-MMBT3904,IC,C52245-001!!!F1990!B!!!!
S!FM_P12V_HOTSWAP0_EN!Q9T1!3!@baseboard_fab2_lib.baseboard_fab2(sch_1):page181_i181@mstr_discrete.npn(chips)!NPN_SM-MMBT3904,IC,C52245-001!!!F1990!C!!!!
S!GND!Q9T1!2!@baseboard_fab2_lib.baseboard_fab2(sch_1):page181_i181@mstr_discrete.npn(chips)!NPN_SM-MMBT3904,IC,C52245-001!!!F1990!E!!!!
S!GND!U2T2!3!!TTL1G32_A_SOT-74LVC1G32,IC,E60B!!!!!!!!
S!P3V3_STBY!U2T2!5!!TTL1G32_A_SOT-74LVC1G32,IC,E60B!!!!!!!!
S!FM_BACKUP_BIOS_SEL_N!U2T2!1!@baseboard_fab2_lib.baseboard_fab2(sch_1):page154_i100@mstr_ttl.ttl1g32_a(chips)!TTL1G32_A_SOT-74LVC1G32,IC,E60B!!!F23!A!!!!
S!SPI_SWITCH_CS0_N!U2T2!2!@baseboard_fab2_lib.baseboard_fab2(sch_1):page154_i100@mstr_ttl.ttl1g32_a(chips)!TTL1G32_A_SOT-74LVC1G32,IC,E60B!!!F23!B!!!!
S!SPI_CS0_SECONDARY_N!U2T2!4!@baseboard_fab2_lib.baseboard_fab2(sch_1):page154_i100@mstr_ttl.ttl1g32_a(chips)!TTL1G32_A_SOT-74LVC1G32,IC,E60B!!!F23!Y!!!!
S!GND!U2T3!3!!TTL1G32_A_SOT-74LVC1G32,IC,E60B!!!!!!!!
S!P3V3_STBY!U2T3!5!!TTL1G32_A_SOT-74LVC1G32,IC,E60B!!!!!!!!
S!FM_DUAL_BIOS_SEL_N!U2T3!1!@baseboard_fab2_lib.baseboard_fab2(sch_1):page154_i99@mstr_ttl.ttl1g32_a(chips)!TTL1G32_A_SOT-74LVC1G32,IC,E60B!!!F22!A!!!!
S!SPI_SWITCH_CS0_N!U2T3!2!@baseboard_fab2_lib.baseboard_fab2(sch_1):page154_i99@mstr_ttl.ttl1g32_a(chips)!TTL1G32_A_SOT-74LVC1G32,IC,E60B!!!F22!B!!!!
S!SPI_CS0_PRIMARY_N!U2T3!4!@baseboard_fab2_lib.baseboard_fab2(sch_1):page154_i99@mstr_ttl.ttl1g32_a(chips)!TTL1G32_A_SOT-74LVC1G32,IC,E60B!!!F22!Y!!!!
S!GND!U1L1!15!!TTL3126_QFNLF-74CBTLV3126,IC,DB!!!!!!!!
S!GND!U1L1!7!!TTL3126_QFNLF-74CBTLV3126,IC,DB!!!!!!!!
S!P3V3_STBY!U1L1!14!!TTL3126_QFNLF-74CBTLV3126,IC,DB!!!!!!!!
S!XDP_TRST_N!U1L1!2!@baseboard_fab2_lib.baseboard_fab2(sch_1):page112_i108(3)@mstr_ttl.ttl3126(chips)!TTL3126_QFNLF-74CBTLV3126,IC,DB!4!4!F12!A(3)!!!!
S!XDP_CPU_TRST_N!U1L1!3!@baseboard_fab2_lib.baseboard_fab2(sch_1):page112_i108(3)@mstr_ttl.ttl3126(chips)!TTL3126_QFNLF-74CBTLV3126,IC,DB!4!4!F12!B(3)!!!!
S!PWRGD_PVCCIN_CPU0!U1L1!1!@baseboard_fab2_lib.baseboard_fab2(sch_1):page112_i108(3)@mstr_ttl.ttl3126(chips)!TTL3126_QFNLF-74CBTLV3126,IC,DB!4!4!F12!OE(3)!!!!
S!XDP_TMS!U1L1!5!@baseboard_fab2_lib.baseboard_fab2(sch_1):page112_i108(2)@mstr_ttl.ttl3126(chips)!TTL3126_QFNLF-74CBTLV3126,IC,DB!4!4!F11!A(2)!!!!
S!XDP_CPU_TMS!U1L1!6!@baseboard_fab2_lib.baseboard_fab2(sch_1):page112_i108(2)@mstr_ttl.ttl3126(chips)!TTL3126_QFNLF-74CBTLV3126,IC,DB!4!4!F11!B(2)!!!!
S!PWRGD_PVCCIN_CPU0!U1L1!4!@baseboard_fab2_lib.baseboard_fab2(sch_1):page112_i108(2)@mstr_ttl.ttl3126(chips)!TTL3126_QFNLF-74CBTLV3126,IC,DB!4!4!F11!OE(2)!!!!
S!XDP_TDO!U1L1!9!@baseboard_fab2_lib.baseboard_fab2(sch_1):page112_i108(1)@mstr_ttl.ttl3126(chips)!TTL3126_QFNLF-74CBTLV3126,IC,DB!4!4!F10!A(1)!!!!
S!XDP_CPU_TDO!U1L1!8!@baseboard_fab2_lib.baseboard_fab2(sch_1):page112_i108(1)@mstr_ttl.ttl3126(chips)!TTL3126_QFNLF-74CBTLV3126,IC,DB!4!4!F10!B(1)!!!!
S!PWRGD_PVCCIN_CPU0!U1L1!10!@baseboard_fab2_lib.baseboard_fab2(sch_1):page112_i108(1)@mstr_ttl.ttl3126(chips)!TTL3126_QFNLF-74CBTLV3126,IC,DB!4!4!F10!OE(1)!!!!
S!XDP_TDI!U1L1!12!@baseboard_fab2_lib.baseboard_fab2(sch_1):page112_i108(0)@mstr_ttl.ttl3126(chips)!TTL3126_QFNLF-74CBTLV3126,IC,DB!4!4!F9!A(0)!!!!
S!XDP_CPU_TDI!U1L1!11!@baseboard_fab2_lib.baseboard_fab2(sch_1):page112_i108(0)@mstr_ttl.ttl3126(chips)!TTL3126_QFNLF-74CBTLV3126,IC,DB!4!4!F9!B(0)!!!!
S!PWRGD_PVCCIN_CPU0!U1L1!13!@baseboard_fab2_lib.baseboard_fab2(sch_1):page112_i108(0)@mstr_ttl.ttl3126(chips)!TTL3126_QFNLF-74CBTLV3126,IC,DB!4!4!F9!OE(0)!!!!
S!GND!U1L5!15!!TTL3126_QFNLF-74CBTLV3126,IC,DB!!!!!!!!
S!GND!U1L5!7!!TTL3126_QFNLF-74CBTLV3126,IC,DB!!!!!!!!
S!P3V3_STBY!U1L5!14!!TTL3126_QFNLF-74CBTLV3126,IC,DB!!!!!!!!
S!XDP_OBSFN_B1_MBP7_N!U1L5!2!@baseboard_fab2_lib.baseboard_fab2(sch_1):page112_i109(3)@mstr_ttl.ttl3126(chips)!TTL3126_QFNLF-74CBTLV3126,IC,DB!4!4!F8!A(3)!!!!
S!XDP_CPU_OBSFN_B1_MBP7_N!U1L5!3!@baseboard_fab2_lib.baseboard_fab2(sch_1):page112_i109(3)@mstr_ttl.ttl3126(chips)!TTL3126_QFNLF-74CBTLV3126,IC,DB!4!4!F8!B(3)!!!!
S!PWRGD_PVCCIN_CPU0!U1L5!1!@baseboard_fab2_lib.baseboard_fab2(sch_1):page112_i109(3)@mstr_ttl.ttl3126(chips)!TTL3126_QFNLF-74CBTLV3126,IC,DB!4!4!F8!OE(3)!!!!
S!XDP_OBSFN_B0_MBP6_N!U1L5!5!@baseboard_fab2_lib.baseboard_fab2(sch_1):page112_i109(2)@mstr_ttl.ttl3126(chips)!TTL3126_QFNLF-74CBTLV3126,IC,DB!4!4!F7!A(2)!!!!
S!XDP_CPU_OBSFN_B0_MBP6_N!U1L5!6!@baseboard_fab2_lib.baseboard_fab2(sch_1):page112_i109(2)@mstr_ttl.ttl3126(chips)!TTL3126_QFNLF-74CBTLV3126,IC,DB!4!4!F7!B(2)!!!!
S!PWRGD_PVCCIN_CPU0!U1L5!4!@baseboard_fab2_lib.baseboard_fab2(sch_1):page112_i109(2)@mstr_ttl.ttl3126(chips)!TTL3126_QFNLF-74CBTLV3126,IC,DB!4!4!F7!OE(2)!!!!
S!XDP_PRDY_N!U1L5!9!@baseboard_fab2_lib.baseboard_fab2(sch_1):page112_i109(1)@mstr_ttl.ttl3126(chips)!TTL3126_QFNLF-74CBTLV3126,IC,DB!4!4!F6!A(1)!!!!
S!XDP_CPU_PRDY_N!U1L5!8!@baseboard_fab2_lib.baseboard_fab2(sch_1):page112_i109(1)@mstr_ttl.ttl3126(chips)!TTL3126_QFNLF-74CBTLV3126,IC,DB!4!4!F6!B(1)!!!!
S!PWRGD_PVCCIN_CPU0!U1L5!10!@baseboard_fab2_lib.baseboard_fab2(sch_1):page112_i109(1)@mstr_ttl.ttl3126(chips)!TTL3126_QFNLF-74CBTLV3126,IC,DB!4!4!F6!OE(1)!!!!
S!XDP_PREQ_N!U1L5!12!@baseboard_fab2_lib.baseboard_fab2(sch_1):page112_i109(0)@mstr_ttl.ttl3126(chips)!TTL3126_QFNLF-74CBTLV3126,IC,DB!4!4!F5!A(0)!!!!
S!XDP_CPU_PREQ_N!U1L5!11!@baseboard_fab2_lib.baseboard_fab2(sch_1):page112_i109(0)@mstr_ttl.ttl3126(chips)!TTL3126_QFNLF-74CBTLV3126,IC,DB!4!4!F5!B(0)!!!!
S!PWRGD_PVCCIN_CPU0!U1L5!13!@baseboard_fab2_lib.baseboard_fab2(sch_1):page112_i109(0)@mstr_ttl.ttl3126(chips)!TTL3126_QFNLF-74CBTLV3126,IC,DB!4!4!F5!OE(0)!!!!
S!P1V8_PCH_STBY!R2L20!1!@baseboard_fab2_lib.baseboard_fab2(sch_1):page237_i81@mstr_discrete.res(chips)!RES_0402-63.4K,1.0%,1/16W,CHIPA!!!F364!A!!!!
S!VR_P1V8_PCH_STBY_FB!R2L20!2!@baseboard_fab2_lib.baseboard_fab2(sch_1):page237_i81@mstr_discrete.res(chips)!RES_0402-63.4K,1.0%,1/16W,CHIPA!!!F364!B!!!!
S!A_HSC_HIGH_EN!J1B4!1!@baseboard_fab2_lib.baseboard_fab2(sch_1):page199_i124@mstr_sconn.sconn3_d53458001(chips)!SCONN3_D53458001_SM-EMPTY,D534A!!!F136!IO1!!!!
S!A_HSC_OCP_SEL!J1B4!2!@baseboard_fab2_lib.baseboard_fab2(sch_1):page199_i124@mstr_sconn.sconn3_d53458001(chips)!SCONN3_D53458001_SM-EMPTY,D534A!!!F136!IO2!!!!
S!A_HSC_LOW_EN!J1B4!3!@baseboard_fab2_lib.baseboard_fab2(sch_1):page199_i124@mstr_sconn.sconn3_d53458001(chips)!SCONN3_D53458001_SM-EMPTY,D534A!!!F136!IO3!!!!
S!AGND_PVPP_KLM!EU4A3!5!@baseboard_fab2_lib.baseboard_fab2(sch_1):page234_i184@mstr_vreg.ncp3232l(chips)!NCP3232L_SM-IC,H86355-001!!!F2002!AGND!!!!
S!VR_PVPP_KLM_BOOT!EU4A3!36!@baseboard_fab2_lib.baseboard_fab2(sch_1):page234_i184@mstr_vreg.ncp3232l(chips)!NCP3232L_SM-IC,H86355-001!!!F2002!BST!!!!
S!VR_COMP_PVPP_KLM_3!EU4A3!3!@baseboard_fab2_lib.baseboard_fab2(sch_1):page234_i184@mstr_vreg.ncp3232l(chips)!NCP3232L_SM-IC,H86355-001!!!F2002!COMP!!!!
S!FM_PVPP_PVDDQ_CPU1_EN_KLM!EU4A3!40!@baseboard_fab2_lib.baseboard_fab2(sch_1):page234_i184@mstr_vreg.ncp3232l(chips)!NCP3232L_SM-IC,H86355-001!!!F2002!EN!!!!
S!VR_FB_PVPP_KLM!EU4A3!2!@baseboard_fab2_lib.baseboard_fab2(sch_1):page234_i184@mstr_vreg.ncp3232l(chips)!NCP3232L_SM-IC,H86355-001!!!F2002!FB!!!!
S!GND!EU4A3!41!@baseboard_fab2_lib.baseboard_fab2(sch_1):page234_i184@mstr_vreg.ncp3232l(chips)!NCP3232L_SM-IC,H86355-001!!!F2002!GND!!!!
S!VR_PVPP_KLM_ISET!EU4A3!4!@baseboard_fab2_lib.baseboard_fab2(sch_1):page234_i184@mstr_vreg.ncp3232l(chips)!NCP3232L_SM-IC,H86355-001!!!F2002!ISET!!!!
S!AGND_PVPP_KLM!EU4A3!6!@baseboard_fab2_lib.baseboard_fab2(sch_1):page234_i184@mstr_vreg.ncp3232l(chips)!NCP3232L_SM-IC,H86355-001!!!F2002!OTS!!!!
S!PWRGD_PVPP_KLM_R!EU4A3!7!@baseboard_fab2_lib.baseboard_fab2(sch_1):page234_i184@mstr_vreg.ncp3232l(chips)!NCP3232L_SM-IC,H86355-001!!!F2002!PG!!!!
S!GND!EU4A3!16!@baseboard_fab2_lib.baseboard_fab2(sch_1):page234_i184@mstr_vreg.ncp3232l(chips)!NCP3232L_SM-IC,H86355-001!!!F2002!PGND(0)!!!!
S!GND!EU4A3!26!@baseboard_fab2_lib.baseboard_fab2(sch_1):page234_i184@mstr_vreg.ncp3232l(chips)!NCP3232L_SM-IC,H86355-001!!!F2002!PGND(10)!!!!
S!GND!EU4A3!27!@baseboard_fab2_lib.baseboard_fab2(sch_1):page234_i184@mstr_vreg.ncp3232l(chips)!NCP3232L_SM-IC,H86355-001!!!F2002!PGND(11)!!!!
S!GND!EU4A3!28!@baseboard_fab2_lib.baseboard_fab2(sch_1):page234_i184@mstr_vreg.ncp3232l(chips)!NCP3232L_SM-IC,H86355-001!!!F2002!PGND(12)!!!!
S!GND!EU4A3!37!@baseboard_fab2_lib.baseboard_fab2(sch_1):page234_i184@mstr_vreg.ncp3232l(chips)!NCP3232L_SM-IC,H86355-001!!!F2002!PGND(13)!!!!
S!GND!EU4A3!17!@baseboard_fab2_lib.baseboard_fab2(sch_1):page234_i184@mstr_vreg.ncp3232l(chips)!NCP3232L_SM-IC,H86355-001!!!F2002!PGND(1)!!!!
S!GND!EU4A3!18!@baseboard_fab2_lib.baseboard_fab2(sch_1):page234_i184@mstr_vreg.ncp3232l(chips)!NCP3232L_SM-IC,H86355-001!!!F2002!PGND(2)!!!!
S!GND!EU4A3!19!@baseboard_fab2_lib.baseboard_fab2(sch_1):page234_i184@mstr_vreg.ncp3232l(chips)!NCP3232L_SM-IC,H86355-001!!!F2002!PGND(3)!!!!
S!GND!EU4A3!20!@baseboard_fab2_lib.baseboard_fab2(sch_1):page234_i184@mstr_vreg.ncp3232l(chips)!NCP3232L_SM-IC,H86355-001!!!F2002!PGND(4)!!!!
S!GND!EU4A3!21!@baseboard_fab2_lib.baseboard_fab2(sch_1):page234_i184@mstr_vreg.ncp3232l(chips)!NCP3232L_SM-IC,H86355-001!!!F2002!PGND(5)!!!!
S!GND!EU4A3!22!@baseboard_fab2_lib.baseboard_fab2(sch_1):page234_i184@mstr_vreg.ncp3232l(chips)!NCP3232L_SM-IC,H86355-001!!!F2002!PGND(6)!!!!
S!GND!EU4A3!23!@baseboard_fab2_lib.baseboard_fab2(sch_1):page234_i184@mstr_vreg.ncp3232l(chips)!NCP3232L_SM-IC,H86355-001!!!F2002!PGND(7)!!!!
S!GND!EU4A3!24!@baseboard_fab2_lib.baseboard_fab2(sch_1):page234_i184@mstr_vreg.ncp3232l(chips)!NCP3232L_SM-IC,H86355-001!!!F2002!PGND(8)!!!!
S!GND!EU4A3!25!@baseboard_fab2_lib.baseboard_fab2(sch_1):page234_i184@mstr_vreg.ncp3232l(chips)!NCP3232L_SM-IC,H86355-001!!!F2002!PGND(9)!!!!
S!VR_PVPP_KLM_SS!EU4A3!1!@baseboard_fab2_lib.baseboard_fab2(sch_1):page234_i184@mstr_vreg.ncp3232l(chips)!NCP3232L_SM-IC,H86355-001!!!F2002!SS!!!!
S!VR_VB_PVPP_KLM!EU4A3!38!@baseboard_fab2_lib.baseboard_fab2(sch_1):page234_i184@mstr_vreg.ncp3232l(chips)!NCP3232L_SM-IC,H86355-001!!!F2002!VB!!!!
S!VR_FET_SW_P12V_STBY_PVPP_KLM!EU4A3!39!@baseboard_fab2_lib.baseboard_fab2(sch_1):page234_i184@mstr_vreg.ncp3232l(chips)!NCP3232L_SM-IC,H86355-001!!!F2002!VCC!!!!
S!VR_FET_SW_P12V_STBY_PVPP_KLM!EU4A3!8!@baseboard_fab2_lib.baseboard_fab2(sch_1):page234_i184@mstr_vreg.ncp3232l(chips)!NCP3232L_SM-IC,H86355-001!!!F2002!VIN(0)!!!!
S!VR_FET_SW_P12V_STBY_PVPP_KLM!EU4A3!9!@baseboard_fab2_lib.baseboard_fab2(sch_1):page234_i184@mstr_vreg.ncp3232l(chips)!NCP3232L_SM-IC,H86355-001!!!F2002!VIN(1)!!!!
S!VR_FET_SW_P12V_STBY_PVPP_KLM!EU4A3!10!@baseboard_fab2_lib.baseboard_fab2(sch_1):page234_i184@mstr_vreg.ncp3232l(chips)!NCP3232L_SM-IC,H86355-001!!!F2002!VIN(2)!!!!
S!VR_FET_SW_P12V_STBY_PVPP_KLM!EU4A3!11!@baseboard_fab2_lib.baseboard_fab2(sch_1):page234_i184@mstr_vreg.ncp3232l(chips)!NCP3232L_SM-IC,H86355-001!!!F2002!VIN(3)!!!!
S!VR_FET_SW_P12V_STBY_PVPP_KLM!EU4A3!12!@baseboard_fab2_lib.baseboard_fab2(sch_1):page234_i184@mstr_vreg.ncp3232l(chips)!NCP3232L_SM-IC,H86355-001!!!F2002!VIN(4)!!!!
S!VR_FET_SW_P12V_STBY_PVPP_KLM!EU4A3!13!@baseboard_fab2_lib.baseboard_fab2(sch_1):page234_i184@mstr_vreg.ncp3232l(chips)!NCP3232L_SM-IC,H86355-001!!!F2002!VIN(5)!!!!
S!VR_FET_SW_P12V_STBY_PVPP_KLM!EU4A3!14!@baseboard_fab2_lib.baseboard_fab2(sch_1):page234_i184@mstr_vreg.ncp3232l(chips)!NCP3232L_SM-IC,H86355-001!!!F2002!VIN(6)!!!!
S!VR_FET_SW_P12V_STBY_PVPP_KLM!EU4A3!42!@baseboard_fab2_lib.baseboard_fab2(sch_1):page234_i184@mstr_vreg.ncp3232l(chips)!NCP3232L_SM-IC,H86355-001!!!F2002!VIN(7)!!!!
S!VR_PVPP_KLM_PHASE!EU4A3!35!@baseboard_fab2_lib.baseboard_fab2(sch_1):page234_i184@mstr_vreg.ncp3232l(chips)!NCP3232L_SM-IC,H86355-001!!!F2002!VSW!!!!
S!VR_PVPP_KLM_PHASE!EU4A3!15!@baseboard_fab2_lib.baseboard_fab2(sch_1):page234_i184@mstr_vreg.ncp3232l(chips)!NCP3232L_SM-IC,H86355-001!!!F2002!VSWH(0)!!!!
S!VR_PVPP_KLM_PHASE!EU4A3!29!@baseboard_fab2_lib.baseboard_fab2(sch_1):page234_i184@mstr_vreg.ncp3232l(chips)!NCP3232L_SM-IC,H86355-001!!!F2002!VSWH(1)!!!!
S!VR_PVPP_KLM_PHASE!EU4A3!30!@baseboard_fab2_lib.baseboard_fab2(sch_1):page234_i184@mstr_vreg.ncp3232l(chips)!NCP3232L_SM-IC,H86355-001!!!F2002!VSWH(2)!!!!
S!VR_PVPP_KLM_PHASE!EU4A3!31!@baseboard_fab2_lib.baseboard_fab2(sch_1):page234_i184@mstr_vreg.ncp3232l(chips)!NCP3232L_SM-IC,H86355-001!!!F2002!VSWH(3)!!!!
S!VR_PVPP_KLM_PHASE!EU4A3!32!@baseboard_fab2_lib.baseboard_fab2(sch_1):page234_i184@mstr_vreg.ncp3232l(chips)!NCP3232L_SM-IC,H86355-001!!!F2002!VSWH(4)!!!!
S!VR_PVPP_KLM_PHASE!EU4A3!33!@baseboard_fab2_lib.baseboard_fab2(sch_1):page234_i184@mstr_vreg.ncp3232l(chips)!NCP3232L_SM-IC,H86355-001!!!F2002!VSWH(5)!!!!
S!VR_PVPP_KLM_PHASE!EU4A3!34!@baseboard_fab2_lib.baseboard_fab2(sch_1):page234_i184@mstr_vreg.ncp3232l(chips)!NCP3232L_SM-IC,H86355-001!!!F2002!VSWH(6)!!!!
S!VR_PVPP_KLM_PHASE!EU4A3!43!@baseboard_fab2_lib.baseboard_fab2(sch_1):page234_i184@mstr_vreg.ncp3232l(chips)!NCP3232L_SM-IC,H86355-001!!!F2002!VSWH(7)!!!!
S!AGND_PVPP_GHJ!EU4G1!5!@baseboard_fab2_lib.baseboard_fab2(sch_1):page233_i225@mstr_vreg.ncp3232l(chips)!NCP3232L_SM-IC,H86355-001!!!F2001!AGND!!!!
S!VR_PVPP_GHJ_BOOT!EU4G1!36!@baseboard_fab2_lib.baseboard_fab2(sch_1):page233_i225@mstr_vreg.ncp3232l(chips)!NCP3232L_SM-IC,H86355-001!!!F2001!BST!!!!
S!VR_COMP_PVPP_GHJ_3!EU4G1!3!@baseboard_fab2_lib.baseboard_fab2(sch_1):page233_i225@mstr_vreg.ncp3232l(chips)!NCP3232L_SM-IC,H86355-001!!!F2001!COMP!!!!
S!FM_PVPP_PVDDQ_CPU1_EN_GHJ!EU4G1!40!@baseboard_fab2_lib.baseboard_fab2(sch_1):page233_i225@mstr_vreg.ncp3232l(chips)!NCP3232L_SM-IC,H86355-001!!!F2001!EN!!!!
S!VR_FB_PVPP_GHJ!EU4G1!2!@baseboard_fab2_lib.baseboard_fab2(sch_1):page233_i225@mstr_vreg.ncp3232l(chips)!NCP3232L_SM-IC,H86355-001!!!F2001!FB!!!!
S!GND!EU4G1!41!@baseboard_fab2_lib.baseboard_fab2(sch_1):page233_i225@mstr_vreg.ncp3232l(chips)!NCP3232L_SM-IC,H86355-001!!!F2001!GND!!!!
S!VR_PVPP_GHJ_ISET!EU4G1!4!@baseboard_fab2_lib.baseboard_fab2(sch_1):page233_i225@mstr_vreg.ncp3232l(chips)!NCP3232L_SM-IC,H86355-001!!!F2001!ISET!!!!
S!AGND_PVPP_GHJ!EU4G1!6!@baseboard_fab2_lib.baseboard_fab2(sch_1):page233_i225@mstr_vreg.ncp3232l(chips)!NCP3232L_SM-IC,H86355-001!!!F2001!OTS!!!!
S!PWRGD_PVPP_GHJ_R!EU4G1!7!@baseboard_fab2_lib.baseboard_fab2(sch_1):page233_i225@mstr_vreg.ncp3232l(chips)!NCP3232L_SM-IC,H86355-001!!!F2001!PG!!!!
S!GND!EU4G1!16!@baseboard_fab2_lib.baseboard_fab2(sch_1):page233_i225@mstr_vreg.ncp3232l(chips)!NCP3232L_SM-IC,H86355-001!!!F2001!PGND(0)!!!!
S!GND!EU4G1!26!@baseboard_fab2_lib.baseboard_fab2(sch_1):page233_i225@mstr_vreg.ncp3232l(chips)!NCP3232L_SM-IC,H86355-001!!!F2001!PGND(10)!!!!
S!GND!EU4G1!27!@baseboard_fab2_lib.baseboard_fab2(sch_1):page233_i225@mstr_vreg.ncp3232l(chips)!NCP3232L_SM-IC,H86355-001!!!F2001!PGND(11)!!!!
S!GND!EU4G1!28!@baseboard_fab2_lib.baseboard_fab2(sch_1):page233_i225@mstr_vreg.ncp3232l(chips)!NCP3232L_SM-IC,H86355-001!!!F2001!PGND(12)!!!!
S!GND!EU4G1!37!@baseboard_fab2_lib.baseboard_fab2(sch_1):page233_i225@mstr_vreg.ncp3232l(chips)!NCP3232L_SM-IC,H86355-001!!!F2001!PGND(13)!!!!
S!GND!EU4G1!17!@baseboard_fab2_lib.baseboard_fab2(sch_1):page233_i225@mstr_vreg.ncp3232l(chips)!NCP3232L_SM-IC,H86355-001!!!F2001!PGND(1)!!!!
S!GND!EU4G1!18!@baseboard_fab2_lib.baseboard_fab2(sch_1):page233_i225@mstr_vreg.ncp3232l(chips)!NCP3232L_SM-IC,H86355-001!!!F2001!PGND(2)!!!!
S!GND!EU4G1!19!@baseboard_fab2_lib.baseboard_fab2(sch_1):page233_i225@mstr_vreg.ncp3232l(chips)!NCP3232L_SM-IC,H86355-001!!!F2001!PGND(3)!!!!
S!GND!EU4G1!20!@baseboard_fab2_lib.baseboard_fab2(sch_1):page233_i225@mstr_vreg.ncp3232l(chips)!NCP3232L_SM-IC,H86355-001!!!F2001!PGND(4)!!!!
S!GND!EU4G1!21!@baseboard_fab2_lib.baseboard_fab2(sch_1):page233_i225@mstr_vreg.ncp3232l(chips)!NCP3232L_SM-IC,H86355-001!!!F2001!PGND(5)!!!!
S!GND!EU4G1!22!@baseboard_fab2_lib.baseboard_fab2(sch_1):page233_i225@mstr_vreg.ncp3232l(chips)!NCP3232L_SM-IC,H86355-001!!!F2001!PGND(6)!!!!
S!GND!EU4G1!23!@baseboard_fab2_lib.baseboard_fab2(sch_1):page233_i225@mstr_vreg.ncp3232l(chips)!NCP3232L_SM-IC,H86355-001!!!F2001!PGND(7)!!!!
S!GND!EU4G1!24!@baseboard_fab2_lib.baseboard_fab2(sch_1):page233_i225@mstr_vreg.ncp3232l(chips)!NCP3232L_SM-IC,H86355-001!!!F2001!PGND(8)!!!!
S!GND!EU4G1!25!@baseboard_fab2_lib.baseboard_fab2(sch_1):page233_i225@mstr_vreg.ncp3232l(chips)!NCP3232L_SM-IC,H86355-001!!!F2001!PGND(9)!!!!
S!VR_PVPP_GHJ_SS!EU4G1!1!@baseboard_fab2_lib.baseboard_fab2(sch_1):page233_i225@mstr_vreg.ncp3232l(chips)!NCP3232L_SM-IC,H86355-001!!!F2001!SS!!!!
S!VR_VB_PVPP_GHJ!EU4G1!38!@baseboard_fab2_lib.baseboard_fab2(sch_1):page233_i225@mstr_vreg.ncp3232l(chips)!NCP3232L_SM-IC,H86355-001!!!F2001!VB!!!!
S!VR_FET_SW_P12V_STBY_PVPP_GHJ!EU4G1!39!@baseboard_fab2_lib.baseboard_fab2(sch_1):page233_i225@mstr_vreg.ncp3232l(chips)!NCP3232L_SM-IC,H86355-001!!!F2001!VCC!!!!
S!VR_FET_SW_P12V_STBY_PVPP_GHJ!EU4G1!8!@baseboard_fab2_lib.baseboard_fab2(sch_1):page233_i225@mstr_vreg.ncp3232l(chips)!NCP3232L_SM-IC,H86355-001!!!F2001!VIN(0)!!!!
S!VR_FET_SW_P12V_STBY_PVPP_GHJ!EU4G1!9!@baseboard_fab2_lib.baseboard_fab2(sch_1):page233_i225@mstr_vreg.ncp3232l(chips)!NCP3232L_SM-IC,H86355-001!!!F2001!VIN(1)!!!!
S!VR_FET_SW_P12V_STBY_PVPP_GHJ!EU4G1!10!@baseboard_fab2_lib.baseboard_fab2(sch_1):page233_i225@mstr_vreg.ncp3232l(chips)!NCP3232L_SM-IC,H86355-001!!!F2001!VIN(2)!!!!
S!VR_FET_SW_P12V_STBY_PVPP_GHJ!EU4G1!11!@baseboard_fab2_lib.baseboard_fab2(sch_1):page233_i225@mstr_vreg.ncp3232l(chips)!NCP3232L_SM-IC,H86355-001!!!F2001!VIN(3)!!!!
S!VR_FET_SW_P12V_STBY_PVPP_GHJ!EU4G1!12!@baseboard_fab2_lib.baseboard_fab2(sch_1):page233_i225@mstr_vreg.ncp3232l(chips)!NCP3232L_SM-IC,H86355-001!!!F2001!VIN(4)!!!!
S!VR_FET_SW_P12V_STBY_PVPP_GHJ!EU4G1!13!@baseboard_fab2_lib.baseboard_fab2(sch_1):page233_i225@mstr_vreg.ncp3232l(chips)!NCP3232L_SM-IC,H86355-001!!!F2001!VIN(5)!!!!
S!VR_FET_SW_P12V_STBY_PVPP_GHJ!EU4G1!14!@baseboard_fab2_lib.baseboard_fab2(sch_1):page233_i225@mstr_vreg.ncp3232l(chips)!NCP3232L_SM-IC,H86355-001!!!F2001!VIN(6)!!!!
S!VR_FET_SW_P12V_STBY_PVPP_GHJ!EU4G1!42!@baseboard_fab2_lib.baseboard_fab2(sch_1):page233_i225@mstr_vreg.ncp3232l(chips)!NCP3232L_SM-IC,H86355-001!!!F2001!VIN(7)!!!!
S!VR_PVPP_GHJ_PHASE!EU4G1!35!@baseboard_fab2_lib.baseboard_fab2(sch_1):page233_i225@mstr_vreg.ncp3232l(chips)!NCP3232L_SM-IC,H86355-001!!!F2001!VSW!!!!
S!VR_PVPP_GHJ_PHASE!EU4G1!15!@baseboard_fab2_lib.baseboard_fab2(sch_1):page233_i225@mstr_vreg.ncp3232l(chips)!NCP3232L_SM-IC,H86355-001!!!F2001!VSWH(0)!!!!
S!VR_PVPP_GHJ_PHASE!EU4G1!29!@baseboard_fab2_lib.baseboard_fab2(sch_1):page233_i225@mstr_vreg.ncp3232l(chips)!NCP3232L_SM-IC,H86355-001!!!F2001!VSWH(1)!!!!
S!VR_PVPP_GHJ_PHASE!EU4G1!30!@baseboard_fab2_lib.baseboard_fab2(sch_1):page233_i225@mstr_vreg.ncp3232l(chips)!NCP3232L_SM-IC,H86355-001!!!F2001!VSWH(2)!!!!
S!VR_PVPP_GHJ_PHASE!EU4G1!31!@baseboard_fab2_lib.baseboard_fab2(sch_1):page233_i225@mstr_vreg.ncp3232l(chips)!NCP3232L_SM-IC,H86355-001!!!F2001!VSWH(3)!!!!
S!VR_PVPP_GHJ_PHASE!EU4G1!32!@baseboard_fab2_lib.baseboard_fab2(sch_1):page233_i225@mstr_vreg.ncp3232l(chips)!NCP3232L_SM-IC,H86355-001!!!F2001!VSWH(4)!!!!
S!VR_PVPP_GHJ_PHASE!EU4G1!33!@baseboard_fab2_lib.baseboard_fab2(sch_1):page233_i225@mstr_vreg.ncp3232l(chips)!NCP3232L_SM-IC,H86355-001!!!F2001!VSWH(5)!!!!
S!VR_PVPP_GHJ_PHASE!EU4G1!34!@baseboard_fab2_lib.baseboard_fab2(sch_1):page233_i225@mstr_vreg.ncp3232l(chips)!NCP3232L_SM-IC,H86355-001!!!F2001!VSWH(6)!!!!
S!VR_PVPP_GHJ_PHASE!EU4G1!43!@baseboard_fab2_lib.baseboard_fab2(sch_1):page233_i225@mstr_vreg.ncp3232l(chips)!NCP3232L_SM-IC,H86355-001!!!F2001!VSWH(7)!!!!
S!AGND_PVPP_DEF!EU7B1!5!@baseboard_fab2_lib.baseboard_fab2(sch_1):page232_i214@mstr_vreg.ncp3232l(chips)!NCP3232L_SM-IC,H86355-001!!!F2000!AGND!!!!
S!VR_PVPP_DEF_BOOT!EU7B1!36!@baseboard_fab2_lib.baseboard_fab2(sch_1):page232_i214@mstr_vreg.ncp3232l(chips)!NCP3232L_SM-IC,H86355-001!!!F2000!BST!!!!
S!VR_COMP_PVPP_DEF_3!EU7B1!3!@baseboard_fab2_lib.baseboard_fab2(sch_1):page232_i214@mstr_vreg.ncp3232l(chips)!NCP3232L_SM-IC,H86355-001!!!F2000!COMP!!!!
S!FM_PVPP_PVDDQ_CPU0_EN_DEF!EU7B1!40!@baseboard_fab2_lib.baseboard_fab2(sch_1):page232_i214@mstr_vreg.ncp3232l(chips)!NCP3232L_SM-IC,H86355-001!!!F2000!EN!!!!
S!VR_FB_PVPP_DEF!EU7B1!2!@baseboard_fab2_lib.baseboard_fab2(sch_1):page232_i214@mstr_vreg.ncp3232l(chips)!NCP3232L_SM-IC,H86355-001!!!F2000!FB!!!!
S!GND!EU7B1!41!@baseboard_fab2_lib.baseboard_fab2(sch_1):page232_i214@mstr_vreg.ncp3232l(chips)!NCP3232L_SM-IC,H86355-001!!!F2000!GND!!!!
S!VR_PVPP_DEF_ISET!EU7B1!4!@baseboard_fab2_lib.baseboard_fab2(sch_1):page232_i214@mstr_vreg.ncp3232l(chips)!NCP3232L_SM-IC,H86355-001!!!F2000!ISET!!!!
S!AGND_PVPP_DEF!EU7B1!6!@baseboard_fab2_lib.baseboard_fab2(sch_1):page232_i214@mstr_vreg.ncp3232l(chips)!NCP3232L_SM-IC,H86355-001!!!F2000!OTS!!!!
S!PWRGD_PVPP_DEF_R!EU7B1!7!@baseboard_fab2_lib.baseboard_fab2(sch_1):page232_i214@mstr_vreg.ncp3232l(chips)!NCP3232L_SM-IC,H86355-001!!!F2000!PG!!!!
S!GND!EU7B1!16!@baseboard_fab2_lib.baseboard_fab2(sch_1):page232_i214@mstr_vreg.ncp3232l(chips)!NCP3232L_SM-IC,H86355-001!!!F2000!PGND(0)!!!!
S!GND!EU7B1!26!@baseboard_fab2_lib.baseboard_fab2(sch_1):page232_i214@mstr_vreg.ncp3232l(chips)!NCP3232L_SM-IC,H86355-001!!!F2000!PGND(10)!!!!
S!GND!EU7B1!27!@baseboard_fab2_lib.baseboard_fab2(sch_1):page232_i214@mstr_vreg.ncp3232l(chips)!NCP3232L_SM-IC,H86355-001!!!F2000!PGND(11)!!!!
S!GND!EU7B1!28!@baseboard_fab2_lib.baseboard_fab2(sch_1):page232_i214@mstr_vreg.ncp3232l(chips)!NCP3232L_SM-IC,H86355-001!!!F2000!PGND(12)!!!!
S!GND!EU7B1!37!@baseboard_fab2_lib.baseboard_fab2(sch_1):page232_i214@mstr_vreg.ncp3232l(chips)!NCP3232L_SM-IC,H86355-001!!!F2000!PGND(13)!!!!
S!GND!EU7B1!17!@baseboard_fab2_lib.baseboard_fab2(sch_1):page232_i214@mstr_vreg.ncp3232l(chips)!NCP3232L_SM-IC,H86355-001!!!F2000!PGND(1)!!!!
S!GND!EU7B1!18!@baseboard_fab2_lib.baseboard_fab2(sch_1):page232_i214@mstr_vreg.ncp3232l(chips)!NCP3232L_SM-IC,H86355-001!!!F2000!PGND(2)!!!!
S!GND!EU7B1!19!@baseboard_fab2_lib.baseboard_fab2(sch_1):page232_i214@mstr_vreg.ncp3232l(chips)!NCP3232L_SM-IC,H86355-001!!!F2000!PGND(3)!!!!
S!GND!EU7B1!20!@baseboard_fab2_lib.baseboard_fab2(sch_1):page232_i214@mstr_vreg.ncp3232l(chips)!NCP3232L_SM-IC,H86355-001!!!F2000!PGND(4)!!!!
S!GND!EU7B1!21!@baseboard_fab2_lib.baseboard_fab2(sch_1):page232_i214@mstr_vreg.ncp3232l(chips)!NCP3232L_SM-IC,H86355-001!!!F2000!PGND(5)!!!!
S!GND!EU7B1!22!@baseboard_fab2_lib.baseboard_fab2(sch_1):page232_i214@mstr_vreg.ncp3232l(chips)!NCP3232L_SM-IC,H86355-001!!!F2000!PGND(6)!!!!
S!GND!EU7B1!23!@baseboard_fab2_lib.baseboard_fab2(sch_1):page232_i214@mstr_vreg.ncp3232l(chips)!NCP3232L_SM-IC,H86355-001!!!F2000!PGND(7)!!!!
S!GND!EU7B1!24!@baseboard_fab2_lib.baseboard_fab2(sch_1):page232_i214@mstr_vreg.ncp3232l(chips)!NCP3232L_SM-IC,H86355-001!!!F2000!PGND(8)!!!!
S!GND!EU7B1!25!@baseboard_fab2_lib.baseboard_fab2(sch_1):page232_i214@mstr_vreg.ncp3232l(chips)!NCP3232L_SM-IC,H86355-001!!!F2000!PGND(9)!!!!
S!VR_PVPP_DEF_SS!EU7B1!1!@baseboard_fab2_lib.baseboard_fab2(sch_1):page232_i214@mstr_vreg.ncp3232l(chips)!NCP3232L_SM-IC,H86355-001!!!F2000!SS!!!!
S!VR_VB_PVPP_DEF!EU7B1!38!@baseboard_fab2_lib.baseboard_fab2(sch_1):page232_i214@mstr_vreg.ncp3232l(chips)!NCP3232L_SM-IC,H86355-001!!!F2000!VB!!!!
S!VR_FET_SW_P12V_STBY_PVPP_DEF!EU7B1!39!@baseboard_fab2_lib.baseboard_fab2(sch_1):page232_i214@mstr_vreg.ncp3232l(chips)!NCP3232L_SM-IC,H86355-001!!!F2000!VCC!!!!
S!VR_FET_SW_P12V_STBY_PVPP_DEF!EU7B1!8!@baseboard_fab2_lib.baseboard_fab2(sch_1):page232_i214@mstr_vreg.ncp3232l(chips)!NCP3232L_SM-IC,H86355-001!!!F2000!VIN(0)!!!!
S!VR_FET_SW_P12V_STBY_PVPP_DEF!EU7B1!9!@baseboard_fab2_lib.baseboard_fab2(sch_1):page232_i214@mstr_vreg.ncp3232l(chips)!NCP3232L_SM-IC,H86355-001!!!F2000!VIN(1)!!!!
S!VR_FET_SW_P12V_STBY_PVPP_DEF!EU7B1!10!@baseboard_fab2_lib.baseboard_fab2(sch_1):page232_i214@mstr_vreg.ncp3232l(chips)!NCP3232L_SM-IC,H86355-001!!!F2000!VIN(2)!!!!
S!VR_FET_SW_P12V_STBY_PVPP_DEF!EU7B1!11!@baseboard_fab2_lib.baseboard_fab2(sch_1):page232_i214@mstr_vreg.ncp3232l(chips)!NCP3232L_SM-IC,H86355-001!!!F2000!VIN(3)!!!!
S!VR_FET_SW_P12V_STBY_PVPP_DEF!EU7B1!12!@baseboard_fab2_lib.baseboard_fab2(sch_1):page232_i214@mstr_vreg.ncp3232l(chips)!NCP3232L_SM-IC,H86355-001!!!F2000!VIN(4)!!!!
S!VR_FET_SW_P12V_STBY_PVPP_DEF!EU7B1!13!@baseboard_fab2_lib.baseboard_fab2(sch_1):page232_i214@mstr_vreg.ncp3232l(chips)!NCP3232L_SM-IC,H86355-001!!!F2000!VIN(5)!!!!
S!VR_FET_SW_P12V_STBY_PVPP_DEF!EU7B1!14!@baseboard_fab2_lib.baseboard_fab2(sch_1):page232_i214@mstr_vreg.ncp3232l(chips)!NCP3232L_SM-IC,H86355-001!!!F2000!VIN(6)!!!!
S!VR_FET_SW_P12V_STBY_PVPP_DEF!EU7B1!42!@baseboard_fab2_lib.baseboard_fab2(sch_1):page232_i214@mstr_vreg.ncp3232l(chips)!NCP3232L_SM-IC,H86355-001!!!F2000!VIN(7)!!!!
S!VR_PVPP_DEF_PHASE!EU7B1!35!@baseboard_fab2_lib.baseboard_fab2(sch_1):page232_i214@mstr_vreg.ncp3232l(chips)!NCP3232L_SM-IC,H86355-001!!!F2000!VSW!!!!
S!VR_PVPP_DEF_PHASE!EU7B1!15!@baseboard_fab2_lib.baseboard_fab2(sch_1):page232_i214@mstr_vreg.ncp3232l(chips)!NCP3232L_SM-IC,H86355-001!!!F2000!VSWH(0)!!!!
S!VR_PVPP_DEF_PHASE!EU7B1!29!@baseboard_fab2_lib.baseboard_fab2(sch_1):page232_i214@mstr_vreg.ncp3232l(chips)!NCP3232L_SM-IC,H86355-001!!!F2000!VSWH(1)!!!!
S!VR_PVPP_DEF_PHASE!EU7B1!30!@baseboard_fab2_lib.baseboard_fab2(sch_1):page232_i214@mstr_vreg.ncp3232l(chips)!NCP3232L_SM-IC,H86355-001!!!F2000!VSWH(2)!!!!
S!VR_PVPP_DEF_PHASE!EU7B1!31!@baseboard_fab2_lib.baseboard_fab2(sch_1):page232_i214@mstr_vreg.ncp3232l(chips)!NCP3232L_SM-IC,H86355-001!!!F2000!VSWH(3)!!!!
S!VR_PVPP_DEF_PHASE!EU7B1!32!@baseboard_fab2_lib.baseboard_fab2(sch_1):page232_i214@mstr_vreg.ncp3232l(chips)!NCP3232L_SM-IC,H86355-001!!!F2000!VSWH(4)!!!!
S!VR_PVPP_DEF_PHASE!EU7B1!33!@baseboard_fab2_lib.baseboard_fab2(sch_1):page232_i214@mstr_vreg.ncp3232l(chips)!NCP3232L_SM-IC,H86355-001!!!F2000!VSWH(5)!!!!
S!VR_PVPP_DEF_PHASE!EU7B1!34!@baseboard_fab2_lib.baseboard_fab2(sch_1):page232_i214@mstr_vreg.ncp3232l(chips)!NCP3232L_SM-IC,H86355-001!!!F2000!VSWH(6)!!!!
S!VR_PVPP_DEF_PHASE!EU7B1!43!@baseboard_fab2_lib.baseboard_fab2(sch_1):page232_i214@mstr_vreg.ncp3232l(chips)!NCP3232L_SM-IC,H86355-001!!!F2000!VSWH(7)!!!!
S!AGND_PVPP_ABC!EU7F1!5!@baseboard_fab2_lib.baseboard_fab2(sch_1):page231_i193@mstr_vreg.ncp3232l(chips)!NCP3232L_SM-IC,H86355-001!!!F1999!AGND!!!!
S!VR_PVPP_ABC_BOOT!EU7F1!36!@baseboard_fab2_lib.baseboard_fab2(sch_1):page231_i193@mstr_vreg.ncp3232l(chips)!NCP3232L_SM-IC,H86355-001!!!F1999!BST!!!!
S!VR_COMP_PVPP_ABC_3!EU7F1!3!@baseboard_fab2_lib.baseboard_fab2(sch_1):page231_i193@mstr_vreg.ncp3232l(chips)!NCP3232L_SM-IC,H86355-001!!!F1999!COMP!!!!
S!FM_PVPP_PVDDQ_CPU0_EN_ABC!EU7F1!40!@baseboard_fab2_lib.baseboard_fab2(sch_1):page231_i193@mstr_vreg.ncp3232l(chips)!NCP3232L_SM-IC,H86355-001!!!F1999!EN!!!!
S!VR_FB_PVPP_ABC!EU7F1!2!@baseboard_fab2_lib.baseboard_fab2(sch_1):page231_i193@mstr_vreg.ncp3232l(chips)!NCP3232L_SM-IC,H86355-001!!!F1999!FB!!!!
S!GND!EU7F1!41!@baseboard_fab2_lib.baseboard_fab2(sch_1):page231_i193@mstr_vreg.ncp3232l(chips)!NCP3232L_SM-IC,H86355-001!!!F1999!GND!!!!
S!VR_PVPP_ABC_ISET!EU7F1!4!@baseboard_fab2_lib.baseboard_fab2(sch_1):page231_i193@mstr_vreg.ncp3232l(chips)!NCP3232L_SM-IC,H86355-001!!!F1999!ISET!!!!
S!AGND_PVPP_ABC!EU7F1!6!@baseboard_fab2_lib.baseboard_fab2(sch_1):page231_i193@mstr_vreg.ncp3232l(chips)!NCP3232L_SM-IC,H86355-001!!!F1999!OTS!!!!
S!PWRGD_PVPP_ABC_R!EU7F1!7!@baseboard_fab2_lib.baseboard_fab2(sch_1):page231_i193@mstr_vreg.ncp3232l(chips)!NCP3232L_SM-IC,H86355-001!!!F1999!PG!!!!
S!GND!EU7F1!16!@baseboard_fab2_lib.baseboard_fab2(sch_1):page231_i193@mstr_vreg.ncp3232l(chips)!NCP3232L_SM-IC,H86355-001!!!F1999!PGND(0)!!!!
S!GND!EU7F1!26!@baseboard_fab2_lib.baseboard_fab2(sch_1):page231_i193@mstr_vreg.ncp3232l(chips)!NCP3232L_SM-IC,H86355-001!!!F1999!PGND(10)!!!!
S!GND!EU7F1!27!@baseboard_fab2_lib.baseboard_fab2(sch_1):page231_i193@mstr_vreg.ncp3232l(chips)!NCP3232L_SM-IC,H86355-001!!!F1999!PGND(11)!!!!
S!GND!EU7F1!28!@baseboard_fab2_lib.baseboard_fab2(sch_1):page231_i193@mstr_vreg.ncp3232l(chips)!NCP3232L_SM-IC,H86355-001!!!F1999!PGND(12)!!!!
S!GND!EU7F1!37!@baseboard_fab2_lib.baseboard_fab2(sch_1):page231_i193@mstr_vreg.ncp3232l(chips)!NCP3232L_SM-IC,H86355-001!!!F1999!PGND(13)!!!!
S!GND!EU7F1!17!@baseboard_fab2_lib.baseboard_fab2(sch_1):page231_i193@mstr_vreg.ncp3232l(chips)!NCP3232L_SM-IC,H86355-001!!!F1999!PGND(1)!!!!
S!GND!EU7F1!18!@baseboard_fab2_lib.baseboard_fab2(sch_1):page231_i193@mstr_vreg.ncp3232l(chips)!NCP3232L_SM-IC,H86355-001!!!F1999!PGND(2)!!!!
S!GND!EU7F1!19!@baseboard_fab2_lib.baseboard_fab2(sch_1):page231_i193@mstr_vreg.ncp3232l(chips)!NCP3232L_SM-IC,H86355-001!!!F1999!PGND(3)!!!!
S!GND!EU7F1!20!@baseboard_fab2_lib.baseboard_fab2(sch_1):page231_i193@mstr_vreg.ncp3232l(chips)!NCP3232L_SM-IC,H86355-001!!!F1999!PGND(4)!!!!
S!GND!EU7F1!21!@baseboard_fab2_lib.baseboard_fab2(sch_1):page231_i193@mstr_vreg.ncp3232l(chips)!NCP3232L_SM-IC,H86355-001!!!F1999!PGND(5)!!!!
S!GND!EU7F1!22!@baseboard_fab2_lib.baseboard_fab2(sch_1):page231_i193@mstr_vreg.ncp3232l(chips)!NCP3232L_SM-IC,H86355-001!!!F1999!PGND(6)!!!!
S!GND!EU7F1!23!@baseboard_fab2_lib.baseboard_fab2(sch_1):page231_i193@mstr_vreg.ncp3232l(chips)!NCP3232L_SM-IC,H86355-001!!!F1999!PGND(7)!!!!
S!GND!EU7F1!24!@baseboard_fab2_lib.baseboard_fab2(sch_1):page231_i193@mstr_vreg.ncp3232l(chips)!NCP3232L_SM-IC,H86355-001!!!F1999!PGND(8)!!!!
S!GND!EU7F1!25!@baseboard_fab2_lib.baseboard_fab2(sch_1):page231_i193@mstr_vreg.ncp3232l(chips)!NCP3232L_SM-IC,H86355-001!!!F1999!PGND(9)!!!!
S!VR_PVPP_ABC_SS!EU7F1!1!@baseboard_fab2_lib.baseboard_fab2(sch_1):page231_i193@mstr_vreg.ncp3232l(chips)!NCP3232L_SM-IC,H86355-001!!!F1999!SS!!!!
S!VR_VB_PVPP_ABC!EU7F1!38!@baseboard_fab2_lib.baseboard_fab2(sch_1):page231_i193@mstr_vreg.ncp3232l(chips)!NCP3232L_SM-IC,H86355-001!!!F1999!VB!!!!
S!VR_FET_SW_P12V_STBY_PVPP_ABC!EU7F1!39!@baseboard_fab2_lib.baseboard_fab2(sch_1):page231_i193@mstr_vreg.ncp3232l(chips)!NCP3232L_SM-IC,H86355-001!!!F1999!VCC!!!!
S!VR_FET_SW_P12V_STBY_PVPP_ABC!EU7F1!8!@baseboard_fab2_lib.baseboard_fab2(sch_1):page231_i193@mstr_vreg.ncp3232l(chips)!NCP3232L_SM-IC,H86355-001!!!F1999!VIN(0)!!!!
S!VR_FET_SW_P12V_STBY_PVPP_ABC!EU7F1!9!@baseboard_fab2_lib.baseboard_fab2(sch_1):page231_i193@mstr_vreg.ncp3232l(chips)!NCP3232L_SM-IC,H86355-001!!!F1999!VIN(1)!!!!
S!VR_FET_SW_P12V_STBY_PVPP_ABC!EU7F1!10!@baseboard_fab2_lib.baseboard_fab2(sch_1):page231_i193@mstr_vreg.ncp3232l(chips)!NCP3232L_SM-IC,H86355-001!!!F1999!VIN(2)!!!!
S!VR_FET_SW_P12V_STBY_PVPP_ABC!EU7F1!11!@baseboard_fab2_lib.baseboard_fab2(sch_1):page231_i193@mstr_vreg.ncp3232l(chips)!NCP3232L_SM-IC,H86355-001!!!F1999!VIN(3)!!!!
S!VR_FET_SW_P12V_STBY_PVPP_ABC!EU7F1!12!@baseboard_fab2_lib.baseboard_fab2(sch_1):page231_i193@mstr_vreg.ncp3232l(chips)!NCP3232L_SM-IC,H86355-001!!!F1999!VIN(4)!!!!
S!VR_FET_SW_P12V_STBY_PVPP_ABC!EU7F1!13!@baseboard_fab2_lib.baseboard_fab2(sch_1):page231_i193@mstr_vreg.ncp3232l(chips)!NCP3232L_SM-IC,H86355-001!!!F1999!VIN(5)!!!!
S!VR_FET_SW_P12V_STBY_PVPP_ABC!EU7F1!14!@baseboard_fab2_lib.baseboard_fab2(sch_1):page231_i193@mstr_vreg.ncp3232l(chips)!NCP3232L_SM-IC,H86355-001!!!F1999!VIN(6)!!!!
S!VR_FET_SW_P12V_STBY_PVPP_ABC!EU7F1!42!@baseboard_fab2_lib.baseboard_fab2(sch_1):page231_i193@mstr_vreg.ncp3232l(chips)!NCP3232L_SM-IC,H86355-001!!!F1999!VIN(7)!!!!
S!VR_PVPP_ABC_PHASE!EU7F1!35!@baseboard_fab2_lib.baseboard_fab2(sch_1):page231_i193@mstr_vreg.ncp3232l(chips)!NCP3232L_SM-IC,H86355-001!!!F1999!VSW!!!!
S!VR_PVPP_ABC_PHASE!EU7F1!15!@baseboard_fab2_lib.baseboard_fab2(sch_1):page231_i193@mstr_vreg.ncp3232l(chips)!NCP3232L_SM-IC,H86355-001!!!F1999!VSWH(0)!!!!
S!VR_PVPP_ABC_PHASE!EU7F1!29!@baseboard_fab2_lib.baseboard_fab2(sch_1):page231_i193@mstr_vreg.ncp3232l(chips)!NCP3232L_SM-IC,H86355-001!!!F1999!VSWH(1)!!!!
S!VR_PVPP_ABC_PHASE!EU7F1!30!@baseboard_fab2_lib.baseboard_fab2(sch_1):page231_i193@mstr_vreg.ncp3232l(chips)!NCP3232L_SM-IC,H86355-001!!!F1999!VSWH(2)!!!!
S!VR_PVPP_ABC_PHASE!EU7F1!31!@baseboard_fab2_lib.baseboard_fab2(sch_1):page231_i193@mstr_vreg.ncp3232l(chips)!NCP3232L_SM-IC,H86355-001!!!F1999!VSWH(3)!!!!
S!VR_PVPP_ABC_PHASE!EU7F1!32!@baseboard_fab2_lib.baseboard_fab2(sch_1):page231_i193@mstr_vreg.ncp3232l(chips)!NCP3232L_SM-IC,H86355-001!!!F1999!VSWH(4)!!!!
S!VR_PVPP_ABC_PHASE!EU7F1!33!@baseboard_fab2_lib.baseboard_fab2(sch_1):page231_i193@mstr_vreg.ncp3232l(chips)!NCP3232L_SM-IC,H86355-001!!!F1999!VSWH(5)!!!!
S!VR_PVPP_ABC_PHASE!EU7F1!34!@baseboard_fab2_lib.baseboard_fab2(sch_1):page231_i193@mstr_vreg.ncp3232l(chips)!NCP3232L_SM-IC,H86355-001!!!F1999!VSWH(6)!!!!
S!VR_PVPP_ABC_PHASE!EU7F1!43!@baseboard_fab2_lib.baseboard_fab2(sch_1):page231_i193@mstr_vreg.ncp3232l(chips)!NCP3232L_SM-IC,H86355-001!!!F1999!VSWH(7)!!!!
S!P12V_STBY!J4B2!A1!@baseboard_fab2_lib.baseboard_fab2(sch_1):page193_i46@mstr_sconn.sconn120_h61426002(chips)!SCONN120_H61426002_SM-CONN,H61A!!!F239!IOA1!!!!
S!GND!J4B2!A10!@baseboard_fab2_lib.baseboard_fab2(sch_1):page193_i46@mstr_sconn.sconn120_h61426002(chips)!SCONN120_H61426002_SM-CONN,H61A!!!F239!IOA10!!!!
S!P3V3_STBY!J4B2!A11!@baseboard_fab2_lib.baseboard_fab2(sch_1):page193_i46@mstr_sconn.sconn120_h61426002(chips)!SCONN120_H61426002_SM-CONN,H61A!!!F239!IOA11!!!!
S!GND!J4B2!A12!@baseboard_fab2_lib.baseboard_fab2(sch_1):page193_i46@mstr_sconn.sconn120_h61426002(chips)!SCONN120_H61426002_SM-CONN,H61A!!!F239!IOA12!!!!
S!P5V_STBY!J4B2!A13!@baseboard_fab2_lib.baseboard_fab2(sch_1):page193_i46@mstr_sconn.sconn120_h61426002(chips)!SCONN120_H61426002_SM-CONN,H61A!!!F239!IOA13!!!!
S!GND!J4B2!A14!@baseboard_fab2_lib.baseboard_fab2(sch_1):page193_i46@mstr_sconn.sconn120_h61426002(chips)!SCONN120_H61426002_SM-CONN,H61A!!!F239!IOA14!!!!
S!FM_P1V8MCP_CPU1_EN!J4B2!A15!@baseboard_fab2_lib.baseboard_fab2(sch_1):page193_i46@mstr_sconn.sconn120_h61426002(chips)!SCONN120_H61426002_SM-CONN,H61A!!!F239!IOA15!!!!
S!FM_PVCCIOMCP_CPU1_EN!J4B2!A16!@baseboard_fab2_lib.baseboard_fab2(sch_1):page193_i46@mstr_sconn.sconn120_h61426002(chips)!SCONN120_H61426002_SM-CONN,H61A!!!F239!IOA16!!!!
S!GND!J4B2!A17!@baseboard_fab2_lib.baseboard_fab2(sch_1):page193_i46@mstr_sconn.sconn120_h61426002(chips)!SCONN120_H61426002_SM-CONN,H61A!!!F239!IOA17!!!!
S!SMB_VR_STBY_LVC3_SCL!J4B2!A18!@baseboard_fab2_lib.baseboard_fab2(sch_1):page193_i46@mstr_sconn.sconn120_h61426002(chips)!SCONN120_H61426002_SM-CONN,H61A!!!F239!IOA18!!!!
S!SVID_ALERT0_CPU1_R_N!J4B2!A19!@baseboard_fab2_lib.baseboard_fab2(sch_1):page193_i46@mstr_sconn.sconn120_h61426002(chips)!SCONN120_H61426002_SM-CONN,H61A!!!F239!IOA19!!!!
S!P12V_STBY!J4B2!A2!@baseboard_fab2_lib.baseboard_fab2(sch_1):page193_i46@mstr_sconn.sconn120_h61426002(chips)!SCONN120_H61426002_SM-CONN,H61A!!!F239!IOA2!!!!
S!SVID_CLK0_CPU1_R!J4B2!A20!@baseboard_fab2_lib.baseboard_fab2(sch_1):page193_i46@mstr_sconn.sconn120_h61426002(chips)!SCONN120_H61426002_SM-CONN,H61A!!!F239!IOA20!!!!
S!P12V_STBY!J4B2!A3!@baseboard_fab2_lib.baseboard_fab2(sch_1):page193_i46@mstr_sconn.sconn120_h61426002(chips)!SCONN120_H61426002_SM-CONN,H61A!!!F239!IOA3!!!!
S!P12V_STBY!J4B2!A4!@baseboard_fab2_lib.baseboard_fab2(sch_1):page193_i46@mstr_sconn.sconn120_h61426002(chips)!SCONN120_H61426002_SM-CONN,H61A!!!F239!IOA4!!!!
S!P12V_STBY!J4B2!A5!@baseboard_fab2_lib.baseboard_fab2(sch_1):page193_i46@mstr_sconn.sconn120_h61426002(chips)!SCONN120_H61426002_SM-CONN,H61A!!!F239!IOA5!!!!
S!P12V_STBY!J4B2!A6!@baseboard_fab2_lib.baseboard_fab2(sch_1):page193_i46@mstr_sconn.sconn120_h61426002(chips)!SCONN120_H61426002_SM-CONN,H61A!!!F239!IOA6!!!!
S!P12V_STBY!J4B2!A7!@baseboard_fab2_lib.baseboard_fab2(sch_1):page193_i46@mstr_sconn.sconn120_h61426002(chips)!SCONN120_H61426002_SM-CONN,H61A!!!F239!IOA7!!!!
S!P12V_STBY!J4B2!A8!@baseboard_fab2_lib.baseboard_fab2(sch_1):page193_i46@mstr_sconn.sconn120_h61426002(chips)!SCONN120_H61426002_SM-CONN,H61A!!!F239!IOA8!!!!
S!GND!J4B2!A9!@baseboard_fab2_lib.baseboard_fab2(sch_1):page193_i46@mstr_sconn.sconn120_h61426002(chips)!SCONN120_H61426002_SM-CONN,H61A!!!F239!IOA9!!!!
S!P12V_STBY!J4B2!B1!@baseboard_fab2_lib.baseboard_fab2(sch_1):page193_i46@mstr_sconn.sconn120_h61426002(chips)!SCONN120_H61426002_SM-CONN,H61A!!!F239!IOB1!!!!
S!GND!J4B2!B10!@baseboard_fab2_lib.baseboard_fab2(sch_1):page193_i46@mstr_sconn.sconn120_h61426002(chips)!SCONN120_H61426002_SM-CONN,H61A!!!F239!IOB10!!!!
S!P3V3_STBY!J4B2!B11!@baseboard_fab2_lib.baseboard_fab2(sch_1):page193_i46@mstr_sconn.sconn120_h61426002(chips)!SCONN120_H61426002_SM-CONN,H61A!!!F239!IOB11!!!!
S!GND!J4B2!B12!@baseboard_fab2_lib.baseboard_fab2(sch_1):page193_i46@mstr_sconn.sconn120_h61426002(chips)!SCONN120_H61426002_SM-CONN,H61A!!!F239!IOB12!!!!
S!P5V_STBY!J4B2!B13!@baseboard_fab2_lib.baseboard_fab2(sch_1):page193_i46@mstr_sconn.sconn120_h61426002(chips)!SCONN120_H61426002_SM-CONN,H61A!!!F239!IOB13!!!!
S!GND!J4B2!B14!@baseboard_fab2_lib.baseboard_fab2(sch_1):page193_i46@mstr_sconn.sconn120_h61426002(chips)!SCONN120_H61426002_SM-CONN,H61A!!!F239!IOB14!!!!
S!PWRGD_P1V8MCP_CPU1!J4B2!B15!@baseboard_fab2_lib.baseboard_fab2(sch_1):page193_i46@mstr_sconn.sconn120_h61426002(chips)!SCONN120_H61426002_SM-CONN,H61A!!!F239!IOB15!!!!
S!PWRGD_PVCCIOMCP_CPU1!J4B2!B16!@baseboard_fab2_lib.baseboard_fab2(sch_1):page193_i46@mstr_sconn.sconn120_h61426002(chips)!SCONN120_H61426002_SM-CONN,H61A!!!F239!IOB16!!!!
S!GND!J4B2!B17!@baseboard_fab2_lib.baseboard_fab2(sch_1):page193_i46@mstr_sconn.sconn120_h61426002(chips)!SCONN120_H61426002_SM-CONN,H61A!!!F239!IOB17!!!!
S!SMB_VR_STBY_LVC3_SDA!J4B2!B18!@baseboard_fab2_lib.baseboard_fab2(sch_1):page193_i46@mstr_sconn.sconn120_h61426002(chips)!SCONN120_H61426002_SM-CONN,H61A!!!F239!IOB18!!!!
S!SVID_ALERT1_CPU1_R_N!J4B2!B19!@baseboard_fab2_lib.baseboard_fab2(sch_1):page193_i46@mstr_sconn.sconn120_h61426002(chips)!SCONN120_H61426002_SM-CONN,H61A!!!F239!IOB19!!!!
S!P12V_STBY!J4B2!B2!@baseboard_fab2_lib.baseboard_fab2(sch_1):page193_i46@mstr_sconn.sconn120_h61426002(chips)!SCONN120_H61426002_SM-CONN,H61A!!!F239!IOB2!!!!
S!SVID_DIO0_CPU1_R!J4B2!B20!@baseboard_fab2_lib.baseboard_fab2(sch_1):page193_i46@mstr_sconn.sconn120_h61426002(chips)!SCONN120_H61426002_SM-CONN,H61A!!!F239!IOB20!!!!
S!P12V_STBY!J4B2!B3!@baseboard_fab2_lib.baseboard_fab2(sch_1):page193_i46@mstr_sconn.sconn120_h61426002(chips)!SCONN120_H61426002_SM-CONN,H61A!!!F239!IOB3!!!!
S!P12V_STBY!J4B2!B4!@baseboard_fab2_lib.baseboard_fab2(sch_1):page193_i46@mstr_sconn.sconn120_h61426002(chips)!SCONN120_H61426002_SM-CONN,H61A!!!F239!IOB4!!!!
S!P12V_STBY!J4B2!B5!@baseboard_fab2_lib.baseboard_fab2(sch_1):page193_i46@mstr_sconn.sconn120_h61426002(chips)!SCONN120_H61426002_SM-CONN,H61A!!!F239!IOB5!!!!
S!P12V_STBY!J4B2!B6!@baseboard_fab2_lib.baseboard_fab2(sch_1):page193_i46@mstr_sconn.sconn120_h61426002(chips)!SCONN120_H61426002_SM-CONN,H61A!!!F239!IOB6!!!!
S!P12V_STBY!J4B2!B7!@baseboard_fab2_lib.baseboard_fab2(sch_1):page193_i46@mstr_sconn.sconn120_h61426002(chips)!SCONN120_H61426002_SM-CONN,H61A!!!F239!IOB7!!!!
S!P12V_STBY!J4B2!B8!@baseboard_fab2_lib.baseboard_fab2(sch_1):page193_i46@mstr_sconn.sconn120_h61426002(chips)!SCONN120_H61426002_SM-CONN,H61A!!!F239!IOB8!!!!
S!GND!J4B2!B9!@baseboard_fab2_lib.baseboard_fab2(sch_1):page193_i46@mstr_sconn.sconn120_h61426002(chips)!SCONN120_H61426002_SM-CONN,H61A!!!F239!IOB9!!!!
S!GND!J4B2!C1!@baseboard_fab2_lib.baseboard_fab2(sch_1):page193_i46@mstr_sconn.sconn120_h61426002(chips)!SCONN120_H61426002_SM-CONN,H61A!!!F239!IOC1!!!!
S!GND!J4B2!C10!@baseboard_fab2_lib.baseboard_fab2(sch_1):page193_i46@mstr_sconn.sconn120_h61426002(chips)!SCONN120_H61426002_SM-CONN,H61A!!!F239!IOC10!!!!
S!P3V3_STBY!J4B2!C11!@baseboard_fab2_lib.baseboard_fab2(sch_1):page193_i46@mstr_sconn.sconn120_h61426002(chips)!SCONN120_H61426002_SM-CONN,H61A!!!F239!IOC11!!!!
S!GND!J4B2!C12!@baseboard_fab2_lib.baseboard_fab2(sch_1):page193_i46@mstr_sconn.sconn120_h61426002(chips)!SCONN120_H61426002_SM-CONN,H61A!!!F239!IOC12!!!!
S!P5V_STBY!J4B2!C13!@baseboard_fab2_lib.baseboard_fab2(sch_1):page193_i46@mstr_sconn.sconn120_h61426002(chips)!SCONN120_H61426002_SM-CONN,H61A!!!F239!IOC13!!!!
S!GND!J4B2!C14!@baseboard_fab2_lib.baseboard_fab2(sch_1):page193_i46@mstr_sconn.sconn120_h61426002(chips)!SCONN120_H61426002_SM-CONN,H61A!!!F239!IOC14!!!!
S!GND!J4B2!C15!@baseboard_fab2_lib.baseboard_fab2(sch_1):page193_i46@mstr_sconn.sconn120_h61426002(chips)!SCONN120_H61426002_SM-CONN,H61A!!!F239!IOC15!!!!
S!GND!J4B2!C16!@baseboard_fab2_lib.baseboard_fab2(sch_1):page193_i46@mstr_sconn.sconn120_h61426002(chips)!SCONN120_H61426002_SM-CONN,H61A!!!F239!IOC16!!!!
S!PVCCIOMCP_CPU1!J4B2!C17!@baseboard_fab2_lib.baseboard_fab2(sch_1):page193_i46@mstr_sconn.sconn120_h61426002(chips)!SCONN120_H61426002_SM-CONN,H61A!!!F239!IOC17!!!!
S!PVCCIOMCP_CPU1!J4B2!C18!@baseboard_fab2_lib.baseboard_fab2(sch_1):page193_i46@mstr_sconn.sconn120_h61426002(chips)!SCONN120_H61426002_SM-CONN,H61A!!!F239!IOC18!!!!
S!PVCCIOMCP_CPU1!J4B2!C19!@baseboard_fab2_lib.baseboard_fab2(sch_1):page193_i46@mstr_sconn.sconn120_h61426002(chips)!SCONN120_H61426002_SM-CONN,H61A!!!F239!IOC19!!!!
S!GND!J4B2!C2!@baseboard_fab2_lib.baseboard_fab2(sch_1):page193_i46@mstr_sconn.sconn120_h61426002(chips)!SCONN120_H61426002_SM-CONN,H61A!!!F239!IOC2!!!!
S!FM_PVCCMCP_CPU1_EN!J4B2!C20!@baseboard_fab2_lib.baseboard_fab2(sch_1):page193_i46@mstr_sconn.sconn120_h61426002(chips)!SCONN120_H61426002_SM-CONN,H61A!!!F239!IOC20!!!!
S!GND!J4B2!C3!@baseboard_fab2_lib.baseboard_fab2(sch_1):page193_i46@mstr_sconn.sconn120_h61426002(chips)!SCONN120_H61426002_SM-CONN,H61A!!!F239!IOC3!!!!
S!GND!J4B2!C4!@baseboard_fab2_lib.baseboard_fab2(sch_1):page193_i46@mstr_sconn.sconn120_h61426002(chips)!SCONN120_H61426002_SM-CONN,H61A!!!F239!IOC4!!!!
S!GND!J4B2!C5!@baseboard_fab2_lib.baseboard_fab2(sch_1):page193_i46@mstr_sconn.sconn120_h61426002(chips)!SCONN120_H61426002_SM-CONN,H61A!!!F239!IOC5!!!!
S!GND!J4B2!C6!@baseboard_fab2_lib.baseboard_fab2(sch_1):page193_i46@mstr_sconn.sconn120_h61426002(chips)!SCONN120_H61426002_SM-CONN,H61A!!!F239!IOC6!!!!
S!GND!J4B2!C7!@baseboard_fab2_lib.baseboard_fab2(sch_1):page193_i46@mstr_sconn.sconn120_h61426002(chips)!SCONN120_H61426002_SM-CONN,H61A!!!F239!IOC7!!!!
S!GND!J4B2!C8!@baseboard_fab2_lib.baseboard_fab2(sch_1):page193_i46@mstr_sconn.sconn120_h61426002(chips)!SCONN120_H61426002_SM-CONN,H61A!!!F239!IOC8!!!!
S!GND!J4B2!C9!@baseboard_fab2_lib.baseboard_fab2(sch_1):page193_i46@mstr_sconn.sconn120_h61426002(chips)!SCONN120_H61426002_SM-CONN,H61A!!!F239!IOC9!!!!
S!P3V3!J4B2!D1!@baseboard_fab2_lib.baseboard_fab2(sch_1):page193_i46@mstr_sconn.sconn120_h61426002(chips)!SCONN120_H61426002_SM-CONN,H61A!!!F239!IOD1!!!!
S!GND!J4B2!D10!@baseboard_fab2_lib.baseboard_fab2(sch_1):page193_i46@mstr_sconn.sconn120_h61426002(chips)!SCONN120_H61426002_SM-CONN,H61A!!!F239!IOD10!!!!
S!GND!J4B2!D11!@baseboard_fab2_lib.baseboard_fab2(sch_1):page193_i46@mstr_sconn.sconn120_h61426002(chips)!SCONN120_H61426002_SM-CONN,H61A!!!F239!IOD11!!!!
S!GND!J4B2!D12!@baseboard_fab2_lib.baseboard_fab2(sch_1):page193_i46@mstr_sconn.sconn120_h61426002(chips)!SCONN120_H61426002_SM-CONN,H61A!!!F239!IOD12!!!!
S!GND!J4B2!D13!@baseboard_fab2_lib.baseboard_fab2(sch_1):page193_i46@mstr_sconn.sconn120_h61426002(chips)!SCONN120_H61426002_SM-CONN,H61A!!!F239!IOD13!!!!
S!GND!J4B2!D14!@baseboard_fab2_lib.baseboard_fab2(sch_1):page193_i46@mstr_sconn.sconn120_h61426002(chips)!SCONN120_H61426002_SM-CONN,H61A!!!F239!IOD14!!!!
S!PVCCIOMCP_CPU1!J4B2!D15!@baseboard_fab2_lib.baseboard_fab2(sch_1):page193_i46@mstr_sconn.sconn120_h61426002(chips)!SCONN120_H61426002_SM-CONN,H61A!!!F239!IOD15!!!!
S!PVCCIOMCP_CPU1!J4B2!D16!@baseboard_fab2_lib.baseboard_fab2(sch_1):page193_i46@mstr_sconn.sconn120_h61426002(chips)!SCONN120_H61426002_SM-CONN,H61A!!!F239!IOD16!!!!
S!PVCCIOMCP_CPU1!J4B2!D17!@baseboard_fab2_lib.baseboard_fab2(sch_1):page193_i46@mstr_sconn.sconn120_h61426002(chips)!SCONN120_H61426002_SM-CONN,H61A!!!F239!IOD17!!!!
S!PVCCIOMCP_CPU1!J4B2!D18!@baseboard_fab2_lib.baseboard_fab2(sch_1):page193_i46@mstr_sconn.sconn120_h61426002(chips)!SCONN120_H61426002_SM-CONN,H61A!!!F239!IOD18!!!!
S!PVCCIOMCP_CPU1!J4B2!D19!@baseboard_fab2_lib.baseboard_fab2(sch_1):page193_i46@mstr_sconn.sconn120_h61426002(chips)!SCONN120_H61426002_SM-CONN,H61A!!!F239!IOD19!!!!
S!GND!J4B2!D2!@baseboard_fab2_lib.baseboard_fab2(sch_1):page193_i46@mstr_sconn.sconn120_h61426002(chips)!SCONN120_H61426002_SM-CONN,H61A!!!F239!IOD2!!!!
S!PWRGD_PVCCMCP_CPU1!J4B2!D20!@baseboard_fab2_lib.baseboard_fab2(sch_1):page193_i46@mstr_sconn.sconn120_h61426002(chips)!SCONN120_H61426002_SM-CONN,H61A!!!F239!IOD20!!!!
S!GND!J4B2!D3!@baseboard_fab2_lib.baseboard_fab2(sch_1):page193_i46@mstr_sconn.sconn120_h61426002(chips)!SCONN120_H61426002_SM-CONN,H61A!!!F239!IOD3!!!!
S!GND!J4B2!D4!@baseboard_fab2_lib.baseboard_fab2(sch_1):page193_i46@mstr_sconn.sconn120_h61426002(chips)!SCONN120_H61426002_SM-CONN,H61A!!!F239!IOD4!!!!
S!GND!J4B2!D5!@baseboard_fab2_lib.baseboard_fab2(sch_1):page193_i46@mstr_sconn.sconn120_h61426002(chips)!SCONN120_H61426002_SM-CONN,H61A!!!F239!IOD5!!!!
S!GND!J4B2!D6!@baseboard_fab2_lib.baseboard_fab2(sch_1):page193_i46@mstr_sconn.sconn120_h61426002(chips)!SCONN120_H61426002_SM-CONN,H61A!!!F239!IOD6!!!!
S!GND!J4B2!D7!@baseboard_fab2_lib.baseboard_fab2(sch_1):page193_i46@mstr_sconn.sconn120_h61426002(chips)!SCONN120_H61426002_SM-CONN,H61A!!!F239!IOD7!!!!
S!GND!J4B2!D8!@baseboard_fab2_lib.baseboard_fab2(sch_1):page193_i46@mstr_sconn.sconn120_h61426002(chips)!SCONN120_H61426002_SM-CONN,H61A!!!F239!IOD8!!!!
S!GND!J4B2!D9!@baseboard_fab2_lib.baseboard_fab2(sch_1):page193_i46@mstr_sconn.sconn120_h61426002(chips)!SCONN120_H61426002_SM-CONN,H61A!!!F239!IOD9!!!!
S!FM_CPU1_VRM_322M_156M_OSC_EN!J4B2!E1!@baseboard_fab2_lib.baseboard_fab2(sch_1):page193_i46@mstr_sconn.sconn120_h61426002(chips)!SCONN120_H61426002_SM-CONN,H61A!!!F239!IOE1!!!!
S!VR_PVCCIOMCP_CPU1_XADDR1!J4B2!E10!@baseboard_fab2_lib.baseboard_fab2(sch_1):page193_i46@mstr_sconn.sconn120_h61426002(chips)!SCONN120_H61426002_SM-CONN,H61A!!!F239!IOE10!!!!
S!GND!J4B2!E11!@baseboard_fab2_lib.baseboard_fab2(sch_1):page193_i46@mstr_sconn.sconn120_h61426002(chips)!SCONN120_H61426002_SM-CONN,H61A!!!F239!IOE11!!!!
S!GND!J4B2!E12!@baseboard_fab2_lib.baseboard_fab2(sch_1):page193_i46@mstr_sconn.sconn120_h61426002(chips)!SCONN120_H61426002_SM-CONN,H61A!!!F239!IOE12!!!!
S!GND!J4B2!E13!@baseboard_fab2_lib.baseboard_fab2(sch_1):page193_i46@mstr_sconn.sconn120_h61426002(chips)!SCONN120_H61426002_SM-CONN,H61A!!!F239!IOE13!!!!
S!GND!J4B2!E14!@baseboard_fab2_lib.baseboard_fab2(sch_1):page193_i46@mstr_sconn.sconn120_h61426002(chips)!SCONN120_H61426002_SM-CONN,H61A!!!F239!IOE14!!!!
S!PVCCIOMCP_CPU1!J4B2!E15!@baseboard_fab2_lib.baseboard_fab2(sch_1):page193_i46@mstr_sconn.sconn120_h61426002(chips)!SCONN120_H61426002_SM-CONN,H61A!!!F239!IOE15!!!!
S!PVCCIOMCP_CPU1!J4B2!E16!@baseboard_fab2_lib.baseboard_fab2(sch_1):page193_i46@mstr_sconn.sconn120_h61426002(chips)!SCONN120_H61426002_SM-CONN,H61A!!!F239!IOE16!!!!
S!PVCCIOMCP_CPU1!J4B2!E17!@baseboard_fab2_lib.baseboard_fab2(sch_1):page193_i46@mstr_sconn.sconn120_h61426002(chips)!SCONN120_H61426002_SM-CONN,H61A!!!F239!IOE17!!!!
S!PVCCIOMCP_CPU1!J4B2!E18!@baseboard_fab2_lib.baseboard_fab2(sch_1):page193_i46@mstr_sconn.sconn120_h61426002(chips)!SCONN120_H61426002_SM-CONN,H61A!!!F239!IOE18!!!!
S!PVCCIOMCP_CPU1!J4B2!E19!@baseboard_fab2_lib.baseboard_fab2(sch_1):page193_i46@mstr_sconn.sconn120_h61426002(chips)!SCONN120_H61426002_SM-CONN,H61A!!!F239!IOE19!!!!
S!GND!J4B2!E2!@baseboard_fab2_lib.baseboard_fab2(sch_1):page193_i46@mstr_sconn.sconn120_h61426002(chips)!SCONN120_H61426002_SM-CONN,H61A!!!F239!IOE2!!!!
S!SVID_CLK1_CPU1_R!J4B2!E20!@baseboard_fab2_lib.baseboard_fab2(sch_1):page193_i46@mstr_sconn.sconn120_h61426002(chips)!SCONN120_H61426002_SM-CONN,H61A!!!F239!IOE20!!!!
S!GND!J4B2!E3!@baseboard_fab2_lib.baseboard_fab2(sch_1):page193_i46@mstr_sconn.sconn120_h61426002(chips)!SCONN120_H61426002_SM-CONN,H61A!!!F239!IOE3!!!!
S!GND!J4B2!E4!@baseboard_fab2_lib.baseboard_fab2(sch_1):page193_i46@mstr_sconn.sconn120_h61426002(chips)!SCONN120_H61426002_SM-CONN,H61A!!!F239!IOE4!!!!
S!GND!J4B2!E5!@baseboard_fab2_lib.baseboard_fab2(sch_1):page193_i46@mstr_sconn.sconn120_h61426002(chips)!SCONN120_H61426002_SM-CONN,H61A!!!F239!IOE5!!!!
S!GND!J4B2!E6!@baseboard_fab2_lib.baseboard_fab2(sch_1):page193_i46@mstr_sconn.sconn120_h61426002(chips)!SCONN120_H61426002_SM-CONN,H61A!!!F239!IOE6!!!!
S!GND!J4B2!E7!@baseboard_fab2_lib.baseboard_fab2(sch_1):page193_i46@mstr_sconn.sconn120_h61426002(chips)!SCONN120_H61426002_SM-CONN,H61A!!!F239!IOE7!!!!
S!VSENSE_PVCCIOMCP_CPU1_SKT_VSEN!J4B2!E8!@baseboard_fab2_lib.baseboard_fab2(sch_1):page193_i46@mstr_sconn.sconn120_h61426002(chips)!SCONN120_H61426002_SM-CONN,H61A!!!F239!IOE8!!!!
S!GND!J4B2!E9!@baseboard_fab2_lib.baseboard_fab2(sch_1):page193_i46@mstr_sconn.sconn120_h61426002(chips)!SCONN120_H61426002_SM-CONN,H61A!!!F239!IOE9!!!!
S!PVCCIO_CPU1!J4B2!F1!@baseboard_fab2_lib.baseboard_fab2(sch_1):page193_i46@mstr_sconn.sconn120_h61426002(chips)!SCONN120_H61426002_SM-CONN,H61A!!!F239!IOF1!!!!
S!VR_PVCCMCP_CPU1_XADDR2!J4B2!F10!@baseboard_fab2_lib.baseboard_fab2(sch_1):page193_i46@mstr_sconn.sconn120_h61426002(chips)!SCONN120_H61426002_SM-CONN,H61A!!!F239!IOF10!!!!
S!GND!J4B2!F11!@baseboard_fab2_lib.baseboard_fab2(sch_1):page193_i46@mstr_sconn.sconn120_h61426002(chips)!SCONN120_H61426002_SM-CONN,H61A!!!F239!IOF11!!!!
S!GND!J4B2!F12!@baseboard_fab2_lib.baseboard_fab2(sch_1):page193_i46@mstr_sconn.sconn120_h61426002(chips)!SCONN120_H61426002_SM-CONN,H61A!!!F239!IOF12!!!!
S!GND!J4B2!F13!@baseboard_fab2_lib.baseboard_fab2(sch_1):page193_i46@mstr_sconn.sconn120_h61426002(chips)!SCONN120_H61426002_SM-CONN,H61A!!!F239!IOF13!!!!
S!GND!J4B2!F14!@baseboard_fab2_lib.baseboard_fab2(sch_1):page193_i46@mstr_sconn.sconn120_h61426002(chips)!SCONN120_H61426002_SM-CONN,H61A!!!F239!IOF14!!!!
S!PVCCIOMCP_CPU1!J4B2!F15!@baseboard_fab2_lib.baseboard_fab2(sch_1):page193_i46@mstr_sconn.sconn120_h61426002(chips)!SCONN120_H61426002_SM-CONN,H61A!!!F239!IOF15!!!!
S!PVCCIOMCP_CPU1!J4B2!F16!@baseboard_fab2_lib.baseboard_fab2(sch_1):page193_i46@mstr_sconn.sconn120_h61426002(chips)!SCONN120_H61426002_SM-CONN,H61A!!!F239!IOF16!!!!
S!PVCCIOMCP_CPU1!J4B2!F17!@baseboard_fab2_lib.baseboard_fab2(sch_1):page193_i46@mstr_sconn.sconn120_h61426002(chips)!SCONN120_H61426002_SM-CONN,H61A!!!F239!IOF17!!!!
S!PVCCIOMCP_CPU1!J4B2!F18!@baseboard_fab2_lib.baseboard_fab2(sch_1):page193_i46@mstr_sconn.sconn120_h61426002(chips)!SCONN120_H61426002_SM-CONN,H61A!!!F239!IOF18!!!!
S!PVCCIOMCP_CPU1!J4B2!F19!@baseboard_fab2_lib.baseboard_fab2(sch_1):page193_i46@mstr_sconn.sconn120_h61426002(chips)!SCONN120_H61426002_SM-CONN,H61A!!!F239!IOF19!!!!
S!GND!J4B2!F2!@baseboard_fab2_lib.baseboard_fab2(sch_1):page193_i46@mstr_sconn.sconn120_h61426002(chips)!SCONN120_H61426002_SM-CONN,H61A!!!F239!IOF2!!!!
S!SVID_DIO1_CPU1_R!J4B2!F20!@baseboard_fab2_lib.baseboard_fab2(sch_1):page193_i46@mstr_sconn.sconn120_h61426002(chips)!SCONN120_H61426002_SM-CONN,H61A!!!F239!IOF20!!!!
S!GND!J4B2!F3!@baseboard_fab2_lib.baseboard_fab2(sch_1):page193_i46@mstr_sconn.sconn120_h61426002(chips)!SCONN120_H61426002_SM-CONN,H61A!!!F239!IOF3!!!!
S!GND!J4B2!F4!@baseboard_fab2_lib.baseboard_fab2(sch_1):page193_i46@mstr_sconn.sconn120_h61426002(chips)!SCONN120_H61426002_SM-CONN,H61A!!!F239!IOF4!!!!
S!GND!J4B2!F5!@baseboard_fab2_lib.baseboard_fab2(sch_1):page193_i46@mstr_sconn.sconn120_h61426002(chips)!SCONN120_H61426002_SM-CONN,H61A!!!F239!IOF5!!!!
S!GND!J4B2!F6!@baseboard_fab2_lib.baseboard_fab2(sch_1):page193_i46@mstr_sconn.sconn120_h61426002(chips)!SCONN120_H61426002_SM-CONN,H61A!!!F239!IOF6!!!!
S!GND!J4B2!F7!@baseboard_fab2_lib.baseboard_fab2(sch_1):page193_i46@mstr_sconn.sconn120_h61426002(chips)!SCONN120_H61426002_SM-CONN,H61A!!!F239!IOF7!!!!
S!VSENSE_PVCCIOMCP_CPU1_SKT_VRTN!J4B2!F8!@baseboard_fab2_lib.baseboard_fab2(sch_1):page193_i46@mstr_sconn.sconn120_h61426002(chips)!SCONN120_H61426002_SM-CONN,H61A!!!F239!IOF8!!!!
S!GND!J4B2!F9!@baseboard_fab2_lib.baseboard_fab2(sch_1):page193_i46@mstr_sconn.sconn120_h61426002(chips)!SCONN120_H61426002_SM-CONN,H61A!!!F239!IOF9!!!!
S!PVCCMCP_CPU1!J4E1!A1!@baseboard_fab2_lib.baseboard_fab2(sch_1):page193_i45@mstr_sconn.sconn120_h61426002(chips)!SCONN120_H61426002_SM-CONN,H61A!!!F238!IOA1!!!!
S!PVCCMCP_CPU1!J4E1!A10!@baseboard_fab2_lib.baseboard_fab2(sch_1):page193_i45@mstr_sconn.sconn120_h61426002(chips)!SCONN120_H61426002_SM-CONN,H61A!!!F238!IOA10!!!!
S!PVCCMCP_CPU1!J4E1!A11!@baseboard_fab2_lib.baseboard_fab2(sch_1):page193_i45@mstr_sconn.sconn120_h61426002(chips)!SCONN120_H61426002_SM-CONN,H61A!!!F238!IOA11!!!!
S!PVCCMCP_CPU1!J4E1!A12!@baseboard_fab2_lib.baseboard_fab2(sch_1):page193_i45@mstr_sconn.sconn120_h61426002(chips)!SCONN120_H61426002_SM-CONN,H61A!!!F238!IOA12!!!!
S!PVCCMCP_CPU1!J4E1!A13!@baseboard_fab2_lib.baseboard_fab2(sch_1):page193_i45@mstr_sconn.sconn120_h61426002(chips)!SCONN120_H61426002_SM-CONN,H61A!!!F238!IOA13!!!!
S!PVCCMCP_CPU1!J4E1!A14!@baseboard_fab2_lib.baseboard_fab2(sch_1):page193_i45@mstr_sconn.sconn120_h61426002(chips)!SCONN120_H61426002_SM-CONN,H61A!!!F238!IOA14!!!!
S!PVCCMCP_CPU1!J4E1!A15!@baseboard_fab2_lib.baseboard_fab2(sch_1):page193_i45@mstr_sconn.sconn120_h61426002(chips)!SCONN120_H61426002_SM-CONN,H61A!!!F238!IOA15!!!!
S!PVCCMCP_CPU1!J4E1!A16!@baseboard_fab2_lib.baseboard_fab2(sch_1):page193_i45@mstr_sconn.sconn120_h61426002(chips)!SCONN120_H61426002_SM-CONN,H61A!!!F238!IOA16!!!!
S!PVCCMCP_CPU1!J4E1!A17!@baseboard_fab2_lib.baseboard_fab2(sch_1):page193_i45@mstr_sconn.sconn120_h61426002(chips)!SCONN120_H61426002_SM-CONN,H61A!!!F238!IOA17!!!!
S!PVCCMCP_CPU1!J4E1!A18!@baseboard_fab2_lib.baseboard_fab2(sch_1):page193_i45@mstr_sconn.sconn120_h61426002(chips)!SCONN120_H61426002_SM-CONN,H61A!!!F238!IOA18!!!!
S!GND!J4E1!A19!@baseboard_fab2_lib.baseboard_fab2(sch_1):page193_i45@mstr_sconn.sconn120_h61426002(chips)!SCONN120_H61426002_SM-CONN,H61A!!!F238!IOA19!!!!
S!PVCCMCP_CPU1!J4E1!A2!@baseboard_fab2_lib.baseboard_fab2(sch_1):page193_i45@mstr_sconn.sconn120_h61426002(chips)!SCONN120_H61426002_SM-CONN,H61A!!!F238!IOA2!!!!
S!GND!J4E1!A20!@baseboard_fab2_lib.baseboard_fab2(sch_1):page193_i45@mstr_sconn.sconn120_h61426002(chips)!SCONN120_H61426002_SM-CONN,H61A!!!F238!IOA20!!!!
S!PVCCMCP_CPU1!J4E1!A3!@baseboard_fab2_lib.baseboard_fab2(sch_1):page193_i45@mstr_sconn.sconn120_h61426002(chips)!SCONN120_H61426002_SM-CONN,H61A!!!F238!IOA3!!!!
S!VSENSE_PVCCMCP_CPU1_SKT_VSEN!J4E1!A4!@baseboard_fab2_lib.baseboard_fab2(sch_1):page193_i45@mstr_sconn.sconn120_h61426002(chips)!SCONN120_H61426002_SM-CONN,H61A!!!F238!IOA4!!!!
S!PVCCMCP_CPU1!J4E1!A5!@baseboard_fab2_lib.baseboard_fab2(sch_1):page193_i45@mstr_sconn.sconn120_h61426002(chips)!SCONN120_H61426002_SM-CONN,H61A!!!F238!IOA5!!!!
S!PVCCMCP_CPU1!J4E1!A6!@baseboard_fab2_lib.baseboard_fab2(sch_1):page193_i45@mstr_sconn.sconn120_h61426002(chips)!SCONN120_H61426002_SM-CONN,H61A!!!F238!IOA6!!!!
S!PVCCMCP_CPU1!J4E1!A7!@baseboard_fab2_lib.baseboard_fab2(sch_1):page193_i45@mstr_sconn.sconn120_h61426002(chips)!SCONN120_H61426002_SM-CONN,H61A!!!F238!IOA7!!!!
S!PVCCMCP_CPU1!J4E1!A8!@baseboard_fab2_lib.baseboard_fab2(sch_1):page193_i45@mstr_sconn.sconn120_h61426002(chips)!SCONN120_H61426002_SM-CONN,H61A!!!F238!IOA8!!!!
S!PVCCMCP_CPU1!J4E1!A9!@baseboard_fab2_lib.baseboard_fab2(sch_1):page193_i45@mstr_sconn.sconn120_h61426002(chips)!SCONN120_H61426002_SM-CONN,H61A!!!F238!IOA9!!!!
S!PVCCMCP_CPU1!J4E1!B1!@baseboard_fab2_lib.baseboard_fab2(sch_1):page193_i45@mstr_sconn.sconn120_h61426002(chips)!SCONN120_H61426002_SM-CONN,H61A!!!F238!IOB1!!!!
S!PVCCMCP_CPU1!J4E1!B10!@baseboard_fab2_lib.baseboard_fab2(sch_1):page193_i45@mstr_sconn.sconn120_h61426002(chips)!SCONN120_H61426002_SM-CONN,H61A!!!F238!IOB10!!!!
S!PVCCMCP_CPU1!J4E1!B11!@baseboard_fab2_lib.baseboard_fab2(sch_1):page193_i45@mstr_sconn.sconn120_h61426002(chips)!SCONN120_H61426002_SM-CONN,H61A!!!F238!IOB11!!!!
S!PVCCMCP_CPU1!J4E1!B12!@baseboard_fab2_lib.baseboard_fab2(sch_1):page193_i45@mstr_sconn.sconn120_h61426002(chips)!SCONN120_H61426002_SM-CONN,H61A!!!F238!IOB12!!!!
S!PVCCMCP_CPU1!J4E1!B13!@baseboard_fab2_lib.baseboard_fab2(sch_1):page193_i45@mstr_sconn.sconn120_h61426002(chips)!SCONN120_H61426002_SM-CONN,H61A!!!F238!IOB13!!!!
S!PVCCMCP_CPU1!J4E1!B14!@baseboard_fab2_lib.baseboard_fab2(sch_1):page193_i45@mstr_sconn.sconn120_h61426002(chips)!SCONN120_H61426002_SM-CONN,H61A!!!F238!IOB14!!!!
S!PVCCMCP_CPU1!J4E1!B15!@baseboard_fab2_lib.baseboard_fab2(sch_1):page193_i45@mstr_sconn.sconn120_h61426002(chips)!SCONN120_H61426002_SM-CONN,H61A!!!F238!IOB15!!!!
S!PVCCMCP_CPU1!J4E1!B16!@baseboard_fab2_lib.baseboard_fab2(sch_1):page193_i45@mstr_sconn.sconn120_h61426002(chips)!SCONN120_H61426002_SM-CONN,H61A!!!F238!IOB16!!!!
S!PVCCMCP_CPU1!J4E1!B17!@baseboard_fab2_lib.baseboard_fab2(sch_1):page193_i45@mstr_sconn.sconn120_h61426002(chips)!SCONN120_H61426002_SM-CONN,H61A!!!F238!IOB17!!!!
S!PVCCMCP_CPU1!J4E1!B18!@baseboard_fab2_lib.baseboard_fab2(sch_1):page193_i45@mstr_sconn.sconn120_h61426002(chips)!SCONN120_H61426002_SM-CONN,H61A!!!F238!IOB18!!!!
S!GND!J4E1!B19!@baseboard_fab2_lib.baseboard_fab2(sch_1):page193_i45@mstr_sconn.sconn120_h61426002(chips)!SCONN120_H61426002_SM-CONN,H61A!!!F238!IOB19!!!!
S!PVCCMCP_CPU1!J4E1!B2!@baseboard_fab2_lib.baseboard_fab2(sch_1):page193_i45@mstr_sconn.sconn120_h61426002(chips)!SCONN120_H61426002_SM-CONN,H61A!!!F238!IOB2!!!!
S!GND!J4E1!B20!@baseboard_fab2_lib.baseboard_fab2(sch_1):page193_i45@mstr_sconn.sconn120_h61426002(chips)!SCONN120_H61426002_SM-CONN,H61A!!!F238!IOB20!!!!
S!PVCCMCP_CPU1!J4E1!B3!@baseboard_fab2_lib.baseboard_fab2(sch_1):page193_i45@mstr_sconn.sconn120_h61426002(chips)!SCONN120_H61426002_SM-CONN,H61A!!!F238!IOB3!!!!
S!VSENSE_PVCCMCP_CPU1_SKT_VRTN!J4E1!B4!@baseboard_fab2_lib.baseboard_fab2(sch_1):page193_i45@mstr_sconn.sconn120_h61426002(chips)!SCONN120_H61426002_SM-CONN,H61A!!!F238!IOB4!!!!
S!PVCCMCP_CPU1!J4E1!B5!@baseboard_fab2_lib.baseboard_fab2(sch_1):page193_i45@mstr_sconn.sconn120_h61426002(chips)!SCONN120_H61426002_SM-CONN,H61A!!!F238!IOB5!!!!
S!PVCCMCP_CPU1!J4E1!B6!@baseboard_fab2_lib.baseboard_fab2(sch_1):page193_i45@mstr_sconn.sconn120_h61426002(chips)!SCONN120_H61426002_SM-CONN,H61A!!!F238!IOB6!!!!
S!PVCCMCP_CPU1!J4E1!B7!@baseboard_fab2_lib.baseboard_fab2(sch_1):page193_i45@mstr_sconn.sconn120_h61426002(chips)!SCONN120_H61426002_SM-CONN,H61A!!!F238!IOB7!!!!
S!PVCCMCP_CPU1!J4E1!B8!@baseboard_fab2_lib.baseboard_fab2(sch_1):page193_i45@mstr_sconn.sconn120_h61426002(chips)!SCONN120_H61426002_SM-CONN,H61A!!!F238!IOB8!!!!
S!PVCCMCP_CPU1!J4E1!B9!@baseboard_fab2_lib.baseboard_fab2(sch_1):page193_i45@mstr_sconn.sconn120_h61426002(chips)!SCONN120_H61426002_SM-CONN,H61A!!!F238!IOB9!!!!
S!PVCCMCP_CPU1!J4E1!C1!@baseboard_fab2_lib.baseboard_fab2(sch_1):page193_i45@mstr_sconn.sconn120_h61426002(chips)!SCONN120_H61426002_SM-CONN,H61A!!!F238!IOC1!!!!
S!PVCCMCP_CPU1!J4E1!C10!@baseboard_fab2_lib.baseboard_fab2(sch_1):page193_i45@mstr_sconn.sconn120_h61426002(chips)!SCONN120_H61426002_SM-CONN,H61A!!!F238!IOC10!!!!
S!PVCCMCP_CPU1!J4E1!C11!@baseboard_fab2_lib.baseboard_fab2(sch_1):page193_i45@mstr_sconn.sconn120_h61426002(chips)!SCONN120_H61426002_SM-CONN,H61A!!!F238!IOC11!!!!
S!PVCCMCP_CPU1!J4E1!C12!@baseboard_fab2_lib.baseboard_fab2(sch_1):page193_i45@mstr_sconn.sconn120_h61426002(chips)!SCONN120_H61426002_SM-CONN,H61A!!!F238!IOC12!!!!
S!PVCCMCP_CPU1!J4E1!C13!@baseboard_fab2_lib.baseboard_fab2(sch_1):page193_i45@mstr_sconn.sconn120_h61426002(chips)!SCONN120_H61426002_SM-CONN,H61A!!!F238!IOC13!!!!
S!PVCCMCP_CPU1!J4E1!C14!@baseboard_fab2_lib.baseboard_fab2(sch_1):page193_i45@mstr_sconn.sconn120_h61426002(chips)!SCONN120_H61426002_SM-CONN,H61A!!!F238!IOC14!!!!
S!PVCCMCP_CPU1!J4E1!C15!@baseboard_fab2_lib.baseboard_fab2(sch_1):page193_i45@mstr_sconn.sconn120_h61426002(chips)!SCONN120_H61426002_SM-CONN,H61A!!!F238!IOC15!!!!
S!PVCCMCP_CPU1!J4E1!C16!@baseboard_fab2_lib.baseboard_fab2(sch_1):page193_i45@mstr_sconn.sconn120_h61426002(chips)!SCONN120_H61426002_SM-CONN,H61A!!!F238!IOC16!!!!
S!PVCCMCP_CPU1!J4E1!C17!@baseboard_fab2_lib.baseboard_fab2(sch_1):page193_i45@mstr_sconn.sconn120_h61426002(chips)!SCONN120_H61426002_SM-CONN,H61A!!!F238!IOC17!!!!
S!PVCCMCP_CPU1!J4E1!C18!@baseboard_fab2_lib.baseboard_fab2(sch_1):page193_i45@mstr_sconn.sconn120_h61426002(chips)!SCONN120_H61426002_SM-CONN,H61A!!!F238!IOC18!!!!
S!GND!J4E1!C19!@baseboard_fab2_lib.baseboard_fab2(sch_1):page193_i45@mstr_sconn.sconn120_h61426002(chips)!SCONN120_H61426002_SM-CONN,H61A!!!F238!IOC19!!!!
S!PVCCMCP_CPU1!J4E1!C2!@baseboard_fab2_lib.baseboard_fab2(sch_1):page193_i45@mstr_sconn.sconn120_h61426002(chips)!SCONN120_H61426002_SM-CONN,H61A!!!F238!IOC2!!!!
S!GND!J4E1!C20!@baseboard_fab2_lib.baseboard_fab2(sch_1):page193_i45@mstr_sconn.sconn120_h61426002(chips)!SCONN120_H61426002_SM-CONN,H61A!!!F238!IOC20!!!!
S!PVCCMCP_CPU1!J4E1!C3!@baseboard_fab2_lib.baseboard_fab2(sch_1):page193_i45@mstr_sconn.sconn120_h61426002(chips)!SCONN120_H61426002_SM-CONN,H61A!!!F238!IOC3!!!!
S!PVCCMCP_CPU1!J4E1!C4!@baseboard_fab2_lib.baseboard_fab2(sch_1):page193_i45@mstr_sconn.sconn120_h61426002(chips)!SCONN120_H61426002_SM-CONN,H61A!!!F238!IOC4!!!!
S!PVCCMCP_CPU1!J4E1!C5!@baseboard_fab2_lib.baseboard_fab2(sch_1):page193_i45@mstr_sconn.sconn120_h61426002(chips)!SCONN120_H61426002_SM-CONN,H61A!!!F238!IOC5!!!!
S!PVCCMCP_CPU1!J4E1!C6!@baseboard_fab2_lib.baseboard_fab2(sch_1):page193_i45@mstr_sconn.sconn120_h61426002(chips)!SCONN120_H61426002_SM-CONN,H61A!!!F238!IOC6!!!!
S!PVCCMCP_CPU1!J4E1!C7!@baseboard_fab2_lib.baseboard_fab2(sch_1):page193_i45@mstr_sconn.sconn120_h61426002(chips)!SCONN120_H61426002_SM-CONN,H61A!!!F238!IOC7!!!!
S!PVCCMCP_CPU1!J4E1!C8!@baseboard_fab2_lib.baseboard_fab2(sch_1):page193_i45@mstr_sconn.sconn120_h61426002(chips)!SCONN120_H61426002_SM-CONN,H61A!!!F238!IOC8!!!!
S!PVCCMCP_CPU1!J4E1!C9!@baseboard_fab2_lib.baseboard_fab2(sch_1):page193_i45@mstr_sconn.sconn120_h61426002(chips)!SCONN120_H61426002_SM-CONN,H61A!!!F238!IOC9!!!!
S!VSENSE_P1V8MCP_CPU1_SKT_VSEN!J4E1!D1!@baseboard_fab2_lib.baseboard_fab2(sch_1):page193_i45@mstr_sconn.sconn120_h61426002(chips)!SCONN120_H61426002_SM-CONN,H61A!!!F238!IOD1!!!!
S!GND!J4E1!D10!@baseboard_fab2_lib.baseboard_fab2(sch_1):page193_i45@mstr_sconn.sconn120_h61426002(chips)!SCONN120_H61426002_SM-CONN,H61A!!!F238!IOD10!!!!
S!GND!J4E1!D11!@baseboard_fab2_lib.baseboard_fab2(sch_1):page193_i45@mstr_sconn.sconn120_h61426002(chips)!SCONN120_H61426002_SM-CONN,H61A!!!F238!IOD11!!!!
S!GND!J4E1!D12!@baseboard_fab2_lib.baseboard_fab2(sch_1):page193_i45@mstr_sconn.sconn120_h61426002(chips)!SCONN120_H61426002_SM-CONN,H61A!!!F238!IOD12!!!!
S!GND!J4E1!D13!@baseboard_fab2_lib.baseboard_fab2(sch_1):page193_i45@mstr_sconn.sconn120_h61426002(chips)!SCONN120_H61426002_SM-CONN,H61A!!!F238!IOD13!!!!
S!GND!J4E1!D14!@baseboard_fab2_lib.baseboard_fab2(sch_1):page193_i45@mstr_sconn.sconn120_h61426002(chips)!SCONN120_H61426002_SM-CONN,H61A!!!F238!IOD14!!!!
S!GND!J4E1!D15!@baseboard_fab2_lib.baseboard_fab2(sch_1):page193_i45@mstr_sconn.sconn120_h61426002(chips)!SCONN120_H61426002_SM-CONN,H61A!!!F238!IOD15!!!!
S!GND!J4E1!D16!@baseboard_fab2_lib.baseboard_fab2(sch_1):page193_i45@mstr_sconn.sconn120_h61426002(chips)!SCONN120_H61426002_SM-CONN,H61A!!!F238!IOD16!!!!
S!GND!J4E1!D17!@baseboard_fab2_lib.baseboard_fab2(sch_1):page193_i45@mstr_sconn.sconn120_h61426002(chips)!SCONN120_H61426002_SM-CONN,H61A!!!F238!IOD17!!!!
S!GND!J4E1!D18!@baseboard_fab2_lib.baseboard_fab2(sch_1):page193_i45@mstr_sconn.sconn120_h61426002(chips)!SCONN120_H61426002_SM-CONN,H61A!!!F238!IOD18!!!!
S!GND!J4E1!D19!@baseboard_fab2_lib.baseboard_fab2(sch_1):page193_i45@mstr_sconn.sconn120_h61426002(chips)!SCONN120_H61426002_SM-CONN,H61A!!!F238!IOD19!!!!
S!VSENSE_P1V8MCP_CPU1_SKT_VRTN!J4E1!D2!@baseboard_fab2_lib.baseboard_fab2(sch_1):page193_i45@mstr_sconn.sconn120_h61426002(chips)!SCONN120_H61426002_SM-CONN,H61A!!!F238!IOD2!!!!
S!GND!J4E1!D20!@baseboard_fab2_lib.baseboard_fab2(sch_1):page193_i45@mstr_sconn.sconn120_h61426002(chips)!SCONN120_H61426002_SM-CONN,H61A!!!F238!IOD20!!!!
S!GND!J4E1!D3!@baseboard_fab2_lib.baseboard_fab2(sch_1):page193_i45@mstr_sconn.sconn120_h61426002(chips)!SCONN120_H61426002_SM-CONN,H61A!!!F238!IOD3!!!!
S!GND!J4E1!D4!@baseboard_fab2_lib.baseboard_fab2(sch_1):page193_i45@mstr_sconn.sconn120_h61426002(chips)!SCONN120_H61426002_SM-CONN,H61A!!!F238!IOD4!!!!
S!GND!J4E1!D5!@baseboard_fab2_lib.baseboard_fab2(sch_1):page193_i45@mstr_sconn.sconn120_h61426002(chips)!SCONN120_H61426002_SM-CONN,H61A!!!F238!IOD5!!!!
S!GND!J4E1!D6!@baseboard_fab2_lib.baseboard_fab2(sch_1):page193_i45@mstr_sconn.sconn120_h61426002(chips)!SCONN120_H61426002_SM-CONN,H61A!!!F238!IOD6!!!!
S!GND!J4E1!D7!@baseboard_fab2_lib.baseboard_fab2(sch_1):page193_i45@mstr_sconn.sconn120_h61426002(chips)!SCONN120_H61426002_SM-CONN,H61A!!!F238!IOD7!!!!
S!GND!J4E1!D8!@baseboard_fab2_lib.baseboard_fab2(sch_1):page193_i45@mstr_sconn.sconn120_h61426002(chips)!SCONN120_H61426002_SM-CONN,H61A!!!F238!IOD8!!!!
S!GND!J4E1!D9!@baseboard_fab2_lib.baseboard_fab2(sch_1):page193_i45@mstr_sconn.sconn120_h61426002(chips)!SCONN120_H61426002_SM-CONN,H61A!!!F238!IOD9!!!!
S!P1V8_MCP_CPU1!J4E1!E1!@baseboard_fab2_lib.baseboard_fab2(sch_1):page193_i45@mstr_sconn.sconn120_h61426002(chips)!SCONN120_H61426002_SM-CONN,H61A!!!F238!IOE1!!!!
S!GND!J4E1!E10!@baseboard_fab2_lib.baseboard_fab2(sch_1):page193_i45@mstr_sconn.sconn120_h61426002(chips)!SCONN120_H61426002_SM-CONN,H61A!!!F238!IOE10!!!!
S!GND!J4E1!E11!@baseboard_fab2_lib.baseboard_fab2(sch_1):page193_i45@mstr_sconn.sconn120_h61426002(chips)!SCONN120_H61426002_SM-CONN,H61A!!!F238!IOE11!!!!
S!GND!J4E1!E12!@baseboard_fab2_lib.baseboard_fab2(sch_1):page193_i45@mstr_sconn.sconn120_h61426002(chips)!SCONN120_H61426002_SM-CONN,H61A!!!F238!IOE12!!!!
S!GND!J4E1!E13!@baseboard_fab2_lib.baseboard_fab2(sch_1):page193_i45@mstr_sconn.sconn120_h61426002(chips)!SCONN120_H61426002_SM-CONN,H61A!!!F238!IOE13!!!!
S!GND!J4E1!E14!@baseboard_fab2_lib.baseboard_fab2(sch_1):page193_i45@mstr_sconn.sconn120_h61426002(chips)!SCONN120_H61426002_SM-CONN,H61A!!!F238!IOE14!!!!
S!GND!J4E1!E15!@baseboard_fab2_lib.baseboard_fab2(sch_1):page193_i45@mstr_sconn.sconn120_h61426002(chips)!SCONN120_H61426002_SM-CONN,H61A!!!F238!IOE15!!!!
S!GND!J4E1!E16!@baseboard_fab2_lib.baseboard_fab2(sch_1):page193_i45@mstr_sconn.sconn120_h61426002(chips)!SCONN120_H61426002_SM-CONN,H61A!!!F238!IOE16!!!!
S!GND!J4E1!E17!@baseboard_fab2_lib.baseboard_fab2(sch_1):page193_i45@mstr_sconn.sconn120_h61426002(chips)!SCONN120_H61426002_SM-CONN,H61A!!!F238!IOE17!!!!
S!GND!J4E1!E18!@baseboard_fab2_lib.baseboard_fab2(sch_1):page193_i45@mstr_sconn.sconn120_h61426002(chips)!SCONN120_H61426002_SM-CONN,H61A!!!F238!IOE18!!!!
S!GND!J4E1!E19!@baseboard_fab2_lib.baseboard_fab2(sch_1):page193_i45@mstr_sconn.sconn120_h61426002(chips)!SCONN120_H61426002_SM-CONN,H61A!!!F238!IOE19!!!!
S!P1V8_MCP_CPU1!J4E1!E2!@baseboard_fab2_lib.baseboard_fab2(sch_1):page193_i45@mstr_sconn.sconn120_h61426002(chips)!SCONN120_H61426002_SM-CONN,H61A!!!F238!IOE2!!!!
S!GND!J4E1!E20!@baseboard_fab2_lib.baseboard_fab2(sch_1):page193_i45@mstr_sconn.sconn120_h61426002(chips)!SCONN120_H61426002_SM-CONN,H61A!!!F238!IOE20!!!!
S!GND!J4E1!E3!@baseboard_fab2_lib.baseboard_fab2(sch_1):page193_i45@mstr_sconn.sconn120_h61426002(chips)!SCONN120_H61426002_SM-CONN,H61A!!!F238!IOE3!!!!
S!GND!J4E1!E4!@baseboard_fab2_lib.baseboard_fab2(sch_1):page193_i45@mstr_sconn.sconn120_h61426002(chips)!SCONN120_H61426002_SM-CONN,H61A!!!F238!IOE4!!!!
S!CLK_322M_156M_CPU1_OSC_VRM_DP!J4E1!E5!@baseboard_fab2_lib.baseboard_fab2(sch_1):page193_i45@mstr_sconn.sconn120_h61426002(chips)!SCONN120_H61426002_SM-CONN,H61A!!!F238!IOE5!!!!
S!GND!J4E1!E6!@baseboard_fab2_lib.baseboard_fab2(sch_1):page193_i45@mstr_sconn.sconn120_h61426002(chips)!SCONN120_H61426002_SM-CONN,H61A!!!F238!IOE6!!!!
S!GND!J4E1!E7!@baseboard_fab2_lib.baseboard_fab2(sch_1):page193_i45@mstr_sconn.sconn120_h61426002(chips)!SCONN120_H61426002_SM-CONN,H61A!!!F238!IOE7!!!!
S!GND!J4E1!E8!@baseboard_fab2_lib.baseboard_fab2(sch_1):page193_i45@mstr_sconn.sconn120_h61426002(chips)!SCONN120_H61426002_SM-CONN,H61A!!!F238!IOE8!!!!
S!GND!J4E1!E9!@baseboard_fab2_lib.baseboard_fab2(sch_1):page193_i45@mstr_sconn.sconn120_h61426002(chips)!SCONN120_H61426002_SM-CONN,H61A!!!F238!IOE9!!!!
S!P1V8_MCP_CPU1!J4E1!F1!@baseboard_fab2_lib.baseboard_fab2(sch_1):page193_i45@mstr_sconn.sconn120_h61426002(chips)!SCONN120_H61426002_SM-CONN,H61A!!!F238!IOF1!!!!
S!GND!J4E1!F10!@baseboard_fab2_lib.baseboard_fab2(sch_1):page193_i45@mstr_sconn.sconn120_h61426002(chips)!SCONN120_H61426002_SM-CONN,H61A!!!F238!IOF10!!!!
S!GND!J4E1!F11!@baseboard_fab2_lib.baseboard_fab2(sch_1):page193_i45@mstr_sconn.sconn120_h61426002(chips)!SCONN120_H61426002_SM-CONN,H61A!!!F238!IOF11!!!!
S!GND!J4E1!F12!@baseboard_fab2_lib.baseboard_fab2(sch_1):page193_i45@mstr_sconn.sconn120_h61426002(chips)!SCONN120_H61426002_SM-CONN,H61A!!!F238!IOF12!!!!
S!GND!J4E1!F13!@baseboard_fab2_lib.baseboard_fab2(sch_1):page193_i45@mstr_sconn.sconn120_h61426002(chips)!SCONN120_H61426002_SM-CONN,H61A!!!F238!IOF13!!!!
S!GND!J4E1!F14!@baseboard_fab2_lib.baseboard_fab2(sch_1):page193_i45@mstr_sconn.sconn120_h61426002(chips)!SCONN120_H61426002_SM-CONN,H61A!!!F238!IOF14!!!!
S!GND!J4E1!F15!@baseboard_fab2_lib.baseboard_fab2(sch_1):page193_i45@mstr_sconn.sconn120_h61426002(chips)!SCONN120_H61426002_SM-CONN,H61A!!!F238!IOF15!!!!
S!GND!J4E1!F16!@baseboard_fab2_lib.baseboard_fab2(sch_1):page193_i45@mstr_sconn.sconn120_h61426002(chips)!SCONN120_H61426002_SM-CONN,H61A!!!F238!IOF16!!!!
S!GND!J4E1!F17!@baseboard_fab2_lib.baseboard_fab2(sch_1):page193_i45@mstr_sconn.sconn120_h61426002(chips)!SCONN120_H61426002_SM-CONN,H61A!!!F238!IOF17!!!!
S!GND!J4E1!F18!@baseboard_fab2_lib.baseboard_fab2(sch_1):page193_i45@mstr_sconn.sconn120_h61426002(chips)!SCONN120_H61426002_SM-CONN,H61A!!!F238!IOF18!!!!
S!GND!J4E1!F19!@baseboard_fab2_lib.baseboard_fab2(sch_1):page193_i45@mstr_sconn.sconn120_h61426002(chips)!SCONN120_H61426002_SM-CONN,H61A!!!F238!IOF19!!!!
S!P1V8_MCP_CPU1!J4E1!F2!@baseboard_fab2_lib.baseboard_fab2(sch_1):page193_i45@mstr_sconn.sconn120_h61426002(chips)!SCONN120_H61426002_SM-CONN,H61A!!!F238!IOF2!!!!
S!GND!J4E1!F20!@baseboard_fab2_lib.baseboard_fab2(sch_1):page193_i45@mstr_sconn.sconn120_h61426002(chips)!SCONN120_H61426002_SM-CONN,H61A!!!F238!IOF20!!!!
S!GND!J4E1!F3!@baseboard_fab2_lib.baseboard_fab2(sch_1):page193_i45@mstr_sconn.sconn120_h61426002(chips)!SCONN120_H61426002_SM-CONN,H61A!!!F238!IOF3!!!!
S!GND!J4E1!F4!@baseboard_fab2_lib.baseboard_fab2(sch_1):page193_i45@mstr_sconn.sconn120_h61426002(chips)!SCONN120_H61426002_SM-CONN,H61A!!!F238!IOF4!!!!
S!CLK_322M_156M_CPU1_OSC_VRM_DN!J4E1!F5!@baseboard_fab2_lib.baseboard_fab2(sch_1):page193_i45@mstr_sconn.sconn120_h61426002(chips)!SCONN120_H61426002_SM-CONN,H61A!!!F238!IOF5!!!!
S!GND!J4E1!F6!@baseboard_fab2_lib.baseboard_fab2(sch_1):page193_i45@mstr_sconn.sconn120_h61426002(chips)!SCONN120_H61426002_SM-CONN,H61A!!!F238!IOF6!!!!
S!GND!J4E1!F7!@baseboard_fab2_lib.baseboard_fab2(sch_1):page193_i45@mstr_sconn.sconn120_h61426002(chips)!SCONN120_H61426002_SM-CONN,H61A!!!F238!IOF7!!!!
S!GND!J4E1!F8!@baseboard_fab2_lib.baseboard_fab2(sch_1):page193_i45@mstr_sconn.sconn120_h61426002(chips)!SCONN120_H61426002_SM-CONN,H61A!!!F238!IOF8!!!!
S!GND!J4E1!F9!@baseboard_fab2_lib.baseboard_fab2(sch_1):page193_i45@mstr_sconn.sconn120_h61426002(chips)!SCONN120_H61426002_SM-CONN,H61A!!!F238!IOF9!!!!
S!P12V_STBY!J6B1!A1!@baseboard_fab2_lib.baseboard_fab2(sch_1):page194_i56@mstr_sconn.sconn120_h61426002(chips)!SCONN120_H61426002_SM-CONN,H61A!!!F237!IOA1!!!!
S!GND!J6B1!A10!@baseboard_fab2_lib.baseboard_fab2(sch_1):page194_i56@mstr_sconn.sconn120_h61426002(chips)!SCONN120_H61426002_SM-CONN,H61A!!!F237!IOA10!!!!
S!P3V3_STBY!J6B1!A11!@baseboard_fab2_lib.baseboard_fab2(sch_1):page194_i56@mstr_sconn.sconn120_h61426002(chips)!SCONN120_H61426002_SM-CONN,H61A!!!F237!IOA11!!!!
S!GND!J6B1!A12!@baseboard_fab2_lib.baseboard_fab2(sch_1):page194_i56@mstr_sconn.sconn120_h61426002(chips)!SCONN120_H61426002_SM-CONN,H61A!!!F237!IOA12!!!!
S!P5V_STBY!J6B1!A13!@baseboard_fab2_lib.baseboard_fab2(sch_1):page194_i56@mstr_sconn.sconn120_h61426002(chips)!SCONN120_H61426002_SM-CONN,H61A!!!F237!IOA13!!!!
S!GND!J6B1!A14!@baseboard_fab2_lib.baseboard_fab2(sch_1):page194_i56@mstr_sconn.sconn120_h61426002(chips)!SCONN120_H61426002_SM-CONN,H61A!!!F237!IOA14!!!!
S!FM_P1V8MCP_CPU0_EN!J6B1!A15!@baseboard_fab2_lib.baseboard_fab2(sch_1):page194_i56@mstr_sconn.sconn120_h61426002(chips)!SCONN120_H61426002_SM-CONN,H61A!!!F237!IOA15!!!!
S!FM_PVCCIOMCP_CPU0_EN!J6B1!A16!@baseboard_fab2_lib.baseboard_fab2(sch_1):page194_i56@mstr_sconn.sconn120_h61426002(chips)!SCONN120_H61426002_SM-CONN,H61A!!!F237!IOA16!!!!
S!GND!J6B1!A17!@baseboard_fab2_lib.baseboard_fab2(sch_1):page194_i56@mstr_sconn.sconn120_h61426002(chips)!SCONN120_H61426002_SM-CONN,H61A!!!F237!IOA17!!!!
S!SMB_VR_STBY_LVC3_SCL!J6B1!A18!@baseboard_fab2_lib.baseboard_fab2(sch_1):page194_i56@mstr_sconn.sconn120_h61426002(chips)!SCONN120_H61426002_SM-CONN,H61A!!!F237!IOA18!!!!
S!SVID_ALERT0_CPU0_R_N!J6B1!A19!@baseboard_fab2_lib.baseboard_fab2(sch_1):page194_i56@mstr_sconn.sconn120_h61426002(chips)!SCONN120_H61426002_SM-CONN,H61A!!!F237!IOA19!!!!
S!P12V_STBY!J6B1!A2!@baseboard_fab2_lib.baseboard_fab2(sch_1):page194_i56@mstr_sconn.sconn120_h61426002(chips)!SCONN120_H61426002_SM-CONN,H61A!!!F237!IOA2!!!!
S!SVID_CLK0_CPU0_R!J6B1!A20!@baseboard_fab2_lib.baseboard_fab2(sch_1):page194_i56@mstr_sconn.sconn120_h61426002(chips)!SCONN120_H61426002_SM-CONN,H61A!!!F237!IOA20!!!!
S!P12V_STBY!J6B1!A3!@baseboard_fab2_lib.baseboard_fab2(sch_1):page194_i56@mstr_sconn.sconn120_h61426002(chips)!SCONN120_H61426002_SM-CONN,H61A!!!F237!IOA3!!!!
S!P12V_STBY!J6B1!A4!@baseboard_fab2_lib.baseboard_fab2(sch_1):page194_i56@mstr_sconn.sconn120_h61426002(chips)!SCONN120_H61426002_SM-CONN,H61A!!!F237!IOA4!!!!
S!P12V_STBY!J6B1!A5!@baseboard_fab2_lib.baseboard_fab2(sch_1):page194_i56@mstr_sconn.sconn120_h61426002(chips)!SCONN120_H61426002_SM-CONN,H61A!!!F237!IOA5!!!!
S!P12V_STBY!J6B1!A6!@baseboard_fab2_lib.baseboard_fab2(sch_1):page194_i56@mstr_sconn.sconn120_h61426002(chips)!SCONN120_H61426002_SM-CONN,H61A!!!F237!IOA6!!!!
S!P12V_STBY!J6B1!A7!@baseboard_fab2_lib.baseboard_fab2(sch_1):page194_i56@mstr_sconn.sconn120_h61426002(chips)!SCONN120_H61426002_SM-CONN,H61A!!!F237!IOA7!!!!
S!P12V_STBY!J6B1!A8!@baseboard_fab2_lib.baseboard_fab2(sch_1):page194_i56@mstr_sconn.sconn120_h61426002(chips)!SCONN120_H61426002_SM-CONN,H61A!!!F237!IOA8!!!!
S!GND!J6B1!A9!@baseboard_fab2_lib.baseboard_fab2(sch_1):page194_i56@mstr_sconn.sconn120_h61426002(chips)!SCONN120_H61426002_SM-CONN,H61A!!!F237!IOA9!!!!
S!P12V_STBY!J6B1!B1!@baseboard_fab2_lib.baseboard_fab2(sch_1):page194_i56@mstr_sconn.sconn120_h61426002(chips)!SCONN120_H61426002_SM-CONN,H61A!!!F237!IOB1!!!!
S!GND!J6B1!B10!@baseboard_fab2_lib.baseboard_fab2(sch_1):page194_i56@mstr_sconn.sconn120_h61426002(chips)!SCONN120_H61426002_SM-CONN,H61A!!!F237!IOB10!!!!
S!P3V3_STBY!J6B1!B11!@baseboard_fab2_lib.baseboard_fab2(sch_1):page194_i56@mstr_sconn.sconn120_h61426002(chips)!SCONN120_H61426002_SM-CONN,H61A!!!F237!IOB11!!!!
S!GND!J6B1!B12!@baseboard_fab2_lib.baseboard_fab2(sch_1):page194_i56@mstr_sconn.sconn120_h61426002(chips)!SCONN120_H61426002_SM-CONN,H61A!!!F237!IOB12!!!!
S!P5V_STBY!J6B1!B13!@baseboard_fab2_lib.baseboard_fab2(sch_1):page194_i56@mstr_sconn.sconn120_h61426002(chips)!SCONN120_H61426002_SM-CONN,H61A!!!F237!IOB13!!!!
S!GND!J6B1!B14!@baseboard_fab2_lib.baseboard_fab2(sch_1):page194_i56@mstr_sconn.sconn120_h61426002(chips)!SCONN120_H61426002_SM-CONN,H61A!!!F237!IOB14!!!!
S!PWRGD_P1V8MCP_CPU0!J6B1!B15!@baseboard_fab2_lib.baseboard_fab2(sch_1):page194_i56@mstr_sconn.sconn120_h61426002(chips)!SCONN120_H61426002_SM-CONN,H61A!!!F237!IOB15!!!!
S!PWRGD_PVCCIOMCP_CPU0!J6B1!B16!@baseboard_fab2_lib.baseboard_fab2(sch_1):page194_i56@mstr_sconn.sconn120_h61426002(chips)!SCONN120_H61426002_SM-CONN,H61A!!!F237!IOB16!!!!
S!GND!J6B1!B17!@baseboard_fab2_lib.baseboard_fab2(sch_1):page194_i56@mstr_sconn.sconn120_h61426002(chips)!SCONN120_H61426002_SM-CONN,H61A!!!F237!IOB17!!!!
S!SMB_VR_STBY_LVC3_SDA!J6B1!B18!@baseboard_fab2_lib.baseboard_fab2(sch_1):page194_i56@mstr_sconn.sconn120_h61426002(chips)!SCONN120_H61426002_SM-CONN,H61A!!!F237!IOB18!!!!
S!SVID_ALERT1_CPU0_R_N!J6B1!B19!@baseboard_fab2_lib.baseboard_fab2(sch_1):page194_i56@mstr_sconn.sconn120_h61426002(chips)!SCONN120_H61426002_SM-CONN,H61A!!!F237!IOB19!!!!
S!P12V_STBY!J6B1!B2!@baseboard_fab2_lib.baseboard_fab2(sch_1):page194_i56@mstr_sconn.sconn120_h61426002(chips)!SCONN120_H61426002_SM-CONN,H61A!!!F237!IOB2!!!!
S!SVID_DIO0_CPU0_R!J6B1!B20!@baseboard_fab2_lib.baseboard_fab2(sch_1):page194_i56@mstr_sconn.sconn120_h61426002(chips)!SCONN120_H61426002_SM-CONN,H61A!!!F237!IOB20!!!!
S!P12V_STBY!J6B1!B3!@baseboard_fab2_lib.baseboard_fab2(sch_1):page194_i56@mstr_sconn.sconn120_h61426002(chips)!SCONN120_H61426002_SM-CONN,H61A!!!F237!IOB3!!!!
S!P12V_STBY!J6B1!B4!@baseboard_fab2_lib.baseboard_fab2(sch_1):page194_i56@mstr_sconn.sconn120_h61426002(chips)!SCONN120_H61426002_SM-CONN,H61A!!!F237!IOB4!!!!
S!P12V_STBY!J6B1!B5!@baseboard_fab2_lib.baseboard_fab2(sch_1):page194_i56@mstr_sconn.sconn120_h61426002(chips)!SCONN120_H61426002_SM-CONN,H61A!!!F237!IOB5!!!!
S!P12V_STBY!J6B1!B6!@baseboard_fab2_lib.baseboard_fab2(sch_1):page194_i56@mstr_sconn.sconn120_h61426002(chips)!SCONN120_H61426002_SM-CONN,H61A!!!F237!IOB6!!!!
S!P12V_STBY!J6B1!B7!@baseboard_fab2_lib.baseboard_fab2(sch_1):page194_i56@mstr_sconn.sconn120_h61426002(chips)!SCONN120_H61426002_SM-CONN,H61A!!!F237!IOB7!!!!
S!P12V_STBY!J6B1!B8!@baseboard_fab2_lib.baseboard_fab2(sch_1):page194_i56@mstr_sconn.sconn120_h61426002(chips)!SCONN120_H61426002_SM-CONN,H61A!!!F237!IOB8!!!!
S!GND!J6B1!B9!@baseboard_fab2_lib.baseboard_fab2(sch_1):page194_i56@mstr_sconn.sconn120_h61426002(chips)!SCONN120_H61426002_SM-CONN,H61A!!!F237!IOB9!!!!
S!GND!J6B1!C1!@baseboard_fab2_lib.baseboard_fab2(sch_1):page194_i56@mstr_sconn.sconn120_h61426002(chips)!SCONN120_H61426002_SM-CONN,H61A!!!F237!IOC1!!!!
S!GND!J6B1!C10!@baseboard_fab2_lib.baseboard_fab2(sch_1):page194_i56@mstr_sconn.sconn120_h61426002(chips)!SCONN120_H61426002_SM-CONN,H61A!!!F237!IOC10!!!!
S!P3V3_STBY!J6B1!C11!@baseboard_fab2_lib.baseboard_fab2(sch_1):page194_i56@mstr_sconn.sconn120_h61426002(chips)!SCONN120_H61426002_SM-CONN,H61A!!!F237!IOC11!!!!
S!GND!J6B1!C12!@baseboard_fab2_lib.baseboard_fab2(sch_1):page194_i56@mstr_sconn.sconn120_h61426002(chips)!SCONN120_H61426002_SM-CONN,H61A!!!F237!IOC12!!!!
S!P5V_STBY!J6B1!C13!@baseboard_fab2_lib.baseboard_fab2(sch_1):page194_i56@mstr_sconn.sconn120_h61426002(chips)!SCONN120_H61426002_SM-CONN,H61A!!!F237!IOC13!!!!
S!GND!J6B1!C14!@baseboard_fab2_lib.baseboard_fab2(sch_1):page194_i56@mstr_sconn.sconn120_h61426002(chips)!SCONN120_H61426002_SM-CONN,H61A!!!F237!IOC14!!!!
S!GND!J6B1!C15!@baseboard_fab2_lib.baseboard_fab2(sch_1):page194_i56@mstr_sconn.sconn120_h61426002(chips)!SCONN120_H61426002_SM-CONN,H61A!!!F237!IOC15!!!!
S!GND!J6B1!C16!@baseboard_fab2_lib.baseboard_fab2(sch_1):page194_i56@mstr_sconn.sconn120_h61426002(chips)!SCONN120_H61426002_SM-CONN,H61A!!!F237!IOC16!!!!
S!PVCCIOMCP_CPU0!J6B1!C17!@baseboard_fab2_lib.baseboard_fab2(sch_1):page194_i56@mstr_sconn.sconn120_h61426002(chips)!SCONN120_H61426002_SM-CONN,H61A!!!F237!IOC17!!!!
S!PVCCIOMCP_CPU0!J6B1!C18!@baseboard_fab2_lib.baseboard_fab2(sch_1):page194_i56@mstr_sconn.sconn120_h61426002(chips)!SCONN120_H61426002_SM-CONN,H61A!!!F237!IOC18!!!!
S!PVCCIOMCP_CPU0!J6B1!C19!@baseboard_fab2_lib.baseboard_fab2(sch_1):page194_i56@mstr_sconn.sconn120_h61426002(chips)!SCONN120_H61426002_SM-CONN,H61A!!!F237!IOC19!!!!
S!GND!J6B1!C2!@baseboard_fab2_lib.baseboard_fab2(sch_1):page194_i56@mstr_sconn.sconn120_h61426002(chips)!SCONN120_H61426002_SM-CONN,H61A!!!F237!IOC2!!!!
S!FM_PVCCMCP_CPU0_EN!J6B1!C20!@baseboard_fab2_lib.baseboard_fab2(sch_1):page194_i56@mstr_sconn.sconn120_h61426002(chips)!SCONN120_H61426002_SM-CONN,H61A!!!F237!IOC20!!!!
S!GND!J6B1!C3!@baseboard_fab2_lib.baseboard_fab2(sch_1):page194_i56@mstr_sconn.sconn120_h61426002(chips)!SCONN120_H61426002_SM-CONN,H61A!!!F237!IOC3!!!!
S!GND!J6B1!C4!@baseboard_fab2_lib.baseboard_fab2(sch_1):page194_i56@mstr_sconn.sconn120_h61426002(chips)!SCONN120_H61426002_SM-CONN,H61A!!!F237!IOC4!!!!
S!GND!J6B1!C5!@baseboard_fab2_lib.baseboard_fab2(sch_1):page194_i56@mstr_sconn.sconn120_h61426002(chips)!SCONN120_H61426002_SM-CONN,H61A!!!F237!IOC5!!!!
S!GND!J6B1!C6!@baseboard_fab2_lib.baseboard_fab2(sch_1):page194_i56@mstr_sconn.sconn120_h61426002(chips)!SCONN120_H61426002_SM-CONN,H61A!!!F237!IOC6!!!!
S!GND!J6B1!C7!@baseboard_fab2_lib.baseboard_fab2(sch_1):page194_i56@mstr_sconn.sconn120_h61426002(chips)!SCONN120_H61426002_SM-CONN,H61A!!!F237!IOC7!!!!
S!GND!J6B1!C8!@baseboard_fab2_lib.baseboard_fab2(sch_1):page194_i56@mstr_sconn.sconn120_h61426002(chips)!SCONN120_H61426002_SM-CONN,H61A!!!F237!IOC8!!!!
S!GND!J6B1!C9!@baseboard_fab2_lib.baseboard_fab2(sch_1):page194_i56@mstr_sconn.sconn120_h61426002(chips)!SCONN120_H61426002_SM-CONN,H61A!!!F237!IOC9!!!!
S!P3V3!J6B1!D1!@baseboard_fab2_lib.baseboard_fab2(sch_1):page194_i56@mstr_sconn.sconn120_h61426002(chips)!SCONN120_H61426002_SM-CONN,H61A!!!F237!IOD1!!!!
S!GND!J6B1!D10!@baseboard_fab2_lib.baseboard_fab2(sch_1):page194_i56@mstr_sconn.sconn120_h61426002(chips)!SCONN120_H61426002_SM-CONN,H61A!!!F237!IOD10!!!!
S!GND!J6B1!D11!@baseboard_fab2_lib.baseboard_fab2(sch_1):page194_i56@mstr_sconn.sconn120_h61426002(chips)!SCONN120_H61426002_SM-CONN,H61A!!!F237!IOD11!!!!
S!GND!J6B1!D12!@baseboard_fab2_lib.baseboard_fab2(sch_1):page194_i56@mstr_sconn.sconn120_h61426002(chips)!SCONN120_H61426002_SM-CONN,H61A!!!F237!IOD12!!!!
S!GND!J6B1!D13!@baseboard_fab2_lib.baseboard_fab2(sch_1):page194_i56@mstr_sconn.sconn120_h61426002(chips)!SCONN120_H61426002_SM-CONN,H61A!!!F237!IOD13!!!!
S!GND!J6B1!D14!@baseboard_fab2_lib.baseboard_fab2(sch_1):page194_i56@mstr_sconn.sconn120_h61426002(chips)!SCONN120_H61426002_SM-CONN,H61A!!!F237!IOD14!!!!
S!PVCCIOMCP_CPU0!J6B1!D15!@baseboard_fab2_lib.baseboard_fab2(sch_1):page194_i56@mstr_sconn.sconn120_h61426002(chips)!SCONN120_H61426002_SM-CONN,H61A!!!F237!IOD15!!!!
S!PVCCIOMCP_CPU0!J6B1!D16!@baseboard_fab2_lib.baseboard_fab2(sch_1):page194_i56@mstr_sconn.sconn120_h61426002(chips)!SCONN120_H61426002_SM-CONN,H61A!!!F237!IOD16!!!!
S!PVCCIOMCP_CPU0!J6B1!D17!@baseboard_fab2_lib.baseboard_fab2(sch_1):page194_i56@mstr_sconn.sconn120_h61426002(chips)!SCONN120_H61426002_SM-CONN,H61A!!!F237!IOD17!!!!
S!PVCCIOMCP_CPU0!J6B1!D18!@baseboard_fab2_lib.baseboard_fab2(sch_1):page194_i56@mstr_sconn.sconn120_h61426002(chips)!SCONN120_H61426002_SM-CONN,H61A!!!F237!IOD18!!!!
S!PVCCIOMCP_CPU0!J6B1!D19!@baseboard_fab2_lib.baseboard_fab2(sch_1):page194_i56@mstr_sconn.sconn120_h61426002(chips)!SCONN120_H61426002_SM-CONN,H61A!!!F237!IOD19!!!!
S!GND!J6B1!D2!@baseboard_fab2_lib.baseboard_fab2(sch_1):page194_i56@mstr_sconn.sconn120_h61426002(chips)!SCONN120_H61426002_SM-CONN,H61A!!!F237!IOD2!!!!
S!PWRGD_PVCCMCP_CPU0!J6B1!D20!@baseboard_fab2_lib.baseboard_fab2(sch_1):page194_i56@mstr_sconn.sconn120_h61426002(chips)!SCONN120_H61426002_SM-CONN,H61A!!!F237!IOD20!!!!
S!GND!J6B1!D3!@baseboard_fab2_lib.baseboard_fab2(sch_1):page194_i56@mstr_sconn.sconn120_h61426002(chips)!SCONN120_H61426002_SM-CONN,H61A!!!F237!IOD3!!!!
S!GND!J6B1!D4!@baseboard_fab2_lib.baseboard_fab2(sch_1):page194_i56@mstr_sconn.sconn120_h61426002(chips)!SCONN120_H61426002_SM-CONN,H61A!!!F237!IOD4!!!!
S!GND!J6B1!D5!@baseboard_fab2_lib.baseboard_fab2(sch_1):page194_i56@mstr_sconn.sconn120_h61426002(chips)!SCONN120_H61426002_SM-CONN,H61A!!!F237!IOD5!!!!
S!GND!J6B1!D6!@baseboard_fab2_lib.baseboard_fab2(sch_1):page194_i56@mstr_sconn.sconn120_h61426002(chips)!SCONN120_H61426002_SM-CONN,H61A!!!F237!IOD6!!!!
S!GND!J6B1!D7!@baseboard_fab2_lib.baseboard_fab2(sch_1):page194_i56@mstr_sconn.sconn120_h61426002(chips)!SCONN120_H61426002_SM-CONN,H61A!!!F237!IOD7!!!!
S!GND!J6B1!D8!@baseboard_fab2_lib.baseboard_fab2(sch_1):page194_i56@mstr_sconn.sconn120_h61426002(chips)!SCONN120_H61426002_SM-CONN,H61A!!!F237!IOD8!!!!
S!GND!J6B1!D9!@baseboard_fab2_lib.baseboard_fab2(sch_1):page194_i56@mstr_sconn.sconn120_h61426002(chips)!SCONN120_H61426002_SM-CONN,H61A!!!F237!IOD9!!!!
S!FM_CPU0_VRM_322M_156M_OSC_EN!J6B1!E1!@baseboard_fab2_lib.baseboard_fab2(sch_1):page194_i56@mstr_sconn.sconn120_h61426002(chips)!SCONN120_H61426002_SM-CONN,H61A!!!F237!IOE1!!!!
S!VR_PVCCIOMCP_CPU0_XADDR1!J6B1!E10!@baseboard_fab2_lib.baseboard_fab2(sch_1):page194_i56@mstr_sconn.sconn120_h61426002(chips)!SCONN120_H61426002_SM-CONN,H61A!!!F237!IOE10!!!!
S!GND!J6B1!E11!@baseboard_fab2_lib.baseboard_fab2(sch_1):page194_i56@mstr_sconn.sconn120_h61426002(chips)!SCONN120_H61426002_SM-CONN,H61A!!!F237!IOE11!!!!
S!GND!J6B1!E12!@baseboard_fab2_lib.baseboard_fab2(sch_1):page194_i56@mstr_sconn.sconn120_h61426002(chips)!SCONN120_H61426002_SM-CONN,H61A!!!F237!IOE12!!!!
S!GND!J6B1!E13!@baseboard_fab2_lib.baseboard_fab2(sch_1):page194_i56@mstr_sconn.sconn120_h61426002(chips)!SCONN120_H61426002_SM-CONN,H61A!!!F237!IOE13!!!!
S!GND!J6B1!E14!@baseboard_fab2_lib.baseboard_fab2(sch_1):page194_i56@mstr_sconn.sconn120_h61426002(chips)!SCONN120_H61426002_SM-CONN,H61A!!!F237!IOE14!!!!
S!PVCCIOMCP_CPU0!J6B1!E15!@baseboard_fab2_lib.baseboard_fab2(sch_1):page194_i56@mstr_sconn.sconn120_h61426002(chips)!SCONN120_H61426002_SM-CONN,H61A!!!F237!IOE15!!!!
S!PVCCIOMCP_CPU0!J6B1!E16!@baseboard_fab2_lib.baseboard_fab2(sch_1):page194_i56@mstr_sconn.sconn120_h61426002(chips)!SCONN120_H61426002_SM-CONN,H61A!!!F237!IOE16!!!!
S!PVCCIOMCP_CPU0!J6B1!E17!@baseboard_fab2_lib.baseboard_fab2(sch_1):page194_i56@mstr_sconn.sconn120_h61426002(chips)!SCONN120_H61426002_SM-CONN,H61A!!!F237!IOE17!!!!
S!PVCCIOMCP_CPU0!J6B1!E18!@baseboard_fab2_lib.baseboard_fab2(sch_1):page194_i56@mstr_sconn.sconn120_h61426002(chips)!SCONN120_H61426002_SM-CONN,H61A!!!F237!IOE18!!!!
S!PVCCIOMCP_CPU0!J6B1!E19!@baseboard_fab2_lib.baseboard_fab2(sch_1):page194_i56@mstr_sconn.sconn120_h61426002(chips)!SCONN120_H61426002_SM-CONN,H61A!!!F237!IOE19!!!!
S!GND!J6B1!E2!@baseboard_fab2_lib.baseboard_fab2(sch_1):page194_i56@mstr_sconn.sconn120_h61426002(chips)!SCONN120_H61426002_SM-CONN,H61A!!!F237!IOE2!!!!
S!SVID_CLK1_CPU0_R!J6B1!E20!@baseboard_fab2_lib.baseboard_fab2(sch_1):page194_i56@mstr_sconn.sconn120_h61426002(chips)!SCONN120_H61426002_SM-CONN,H61A!!!F237!IOE20!!!!
S!GND!J6B1!E3!@baseboard_fab2_lib.baseboard_fab2(sch_1):page194_i56@mstr_sconn.sconn120_h61426002(chips)!SCONN120_H61426002_SM-CONN,H61A!!!F237!IOE3!!!!
S!GND!J6B1!E4!@baseboard_fab2_lib.baseboard_fab2(sch_1):page194_i56@mstr_sconn.sconn120_h61426002(chips)!SCONN120_H61426002_SM-CONN,H61A!!!F237!IOE4!!!!
S!GND!J6B1!E5!@baseboard_fab2_lib.baseboard_fab2(sch_1):page194_i56@mstr_sconn.sconn120_h61426002(chips)!SCONN120_H61426002_SM-CONN,H61A!!!F237!IOE5!!!!
S!GND!J6B1!E6!@baseboard_fab2_lib.baseboard_fab2(sch_1):page194_i56@mstr_sconn.sconn120_h61426002(chips)!SCONN120_H61426002_SM-CONN,H61A!!!F237!IOE6!!!!
S!GND!J6B1!E7!@baseboard_fab2_lib.baseboard_fab2(sch_1):page194_i56@mstr_sconn.sconn120_h61426002(chips)!SCONN120_H61426002_SM-CONN,H61A!!!F237!IOE7!!!!
S!VSENSE_PVCCIOMCP_CPU0_SKT_VSEN!J6B1!E8!@baseboard_fab2_lib.baseboard_fab2(sch_1):page194_i56@mstr_sconn.sconn120_h61426002(chips)!SCONN120_H61426002_SM-CONN,H61A!!!F237!IOE8!!!!
S!GND!J6B1!E9!@baseboard_fab2_lib.baseboard_fab2(sch_1):page194_i56@mstr_sconn.sconn120_h61426002(chips)!SCONN120_H61426002_SM-CONN,H61A!!!F237!IOE9!!!!
S!PVCCIO_CPU0!J6B1!F1!@baseboard_fab2_lib.baseboard_fab2(sch_1):page194_i56@mstr_sconn.sconn120_h61426002(chips)!SCONN120_H61426002_SM-CONN,H61A!!!F237!IOF1!!!!
S!VR_PVCCMCP_CPU0_XADDR2!J6B1!F10!@baseboard_fab2_lib.baseboard_fab2(sch_1):page194_i56@mstr_sconn.sconn120_h61426002(chips)!SCONN120_H61426002_SM-CONN,H61A!!!F237!IOF10!!!!
S!GND!J6B1!F11!@baseboard_fab2_lib.baseboard_fab2(sch_1):page194_i56@mstr_sconn.sconn120_h61426002(chips)!SCONN120_H61426002_SM-CONN,H61A!!!F237!IOF11!!!!
S!GND!J6B1!F12!@baseboard_fab2_lib.baseboard_fab2(sch_1):page194_i56@mstr_sconn.sconn120_h61426002(chips)!SCONN120_H61426002_SM-CONN,H61A!!!F237!IOF12!!!!
S!GND!J6B1!F13!@baseboard_fab2_lib.baseboard_fab2(sch_1):page194_i56@mstr_sconn.sconn120_h61426002(chips)!SCONN120_H61426002_SM-CONN,H61A!!!F237!IOF13!!!!
S!GND!J6B1!F14!@baseboard_fab2_lib.baseboard_fab2(sch_1):page194_i56@mstr_sconn.sconn120_h61426002(chips)!SCONN120_H61426002_SM-CONN,H61A!!!F237!IOF14!!!!
S!PVCCIOMCP_CPU0!J6B1!F15!@baseboard_fab2_lib.baseboard_fab2(sch_1):page194_i56@mstr_sconn.sconn120_h61426002(chips)!SCONN120_H61426002_SM-CONN,H61A!!!F237!IOF15!!!!
S!PVCCIOMCP_CPU0!J6B1!F16!@baseboard_fab2_lib.baseboard_fab2(sch_1):page194_i56@mstr_sconn.sconn120_h61426002(chips)!SCONN120_H61426002_SM-CONN,H61A!!!F237!IOF16!!!!
S!PVCCIOMCP_CPU0!J6B1!F17!@baseboard_fab2_lib.baseboard_fab2(sch_1):page194_i56@mstr_sconn.sconn120_h61426002(chips)!SCONN120_H61426002_SM-CONN,H61A!!!F237!IOF17!!!!
S!PVCCIOMCP_CPU0!J6B1!F18!@baseboard_fab2_lib.baseboard_fab2(sch_1):page194_i56@mstr_sconn.sconn120_h61426002(chips)!SCONN120_H61426002_SM-CONN,H61A!!!F237!IOF18!!!!
S!PVCCIOMCP_CPU0!J6B1!F19!@baseboard_fab2_lib.baseboard_fab2(sch_1):page194_i56@mstr_sconn.sconn120_h61426002(chips)!SCONN120_H61426002_SM-CONN,H61A!!!F237!IOF19!!!!
S!GND!J6B1!F2!@baseboard_fab2_lib.baseboard_fab2(sch_1):page194_i56@mstr_sconn.sconn120_h61426002(chips)!SCONN120_H61426002_SM-CONN,H61A!!!F237!IOF2!!!!
S!SVID_DIO1_CPU0_R!J6B1!F20!@baseboard_fab2_lib.baseboard_fab2(sch_1):page194_i56@mstr_sconn.sconn120_h61426002(chips)!SCONN120_H61426002_SM-CONN,H61A!!!F237!IOF20!!!!
S!GND!J6B1!F3!@baseboard_fab2_lib.baseboard_fab2(sch_1):page194_i56@mstr_sconn.sconn120_h61426002(chips)!SCONN120_H61426002_SM-CONN,H61A!!!F237!IOF3!!!!
S!GND!J6B1!F4!@baseboard_fab2_lib.baseboard_fab2(sch_1):page194_i56@mstr_sconn.sconn120_h61426002(chips)!SCONN120_H61426002_SM-CONN,H61A!!!F237!IOF4!!!!
S!GND!J6B1!F5!@baseboard_fab2_lib.baseboard_fab2(sch_1):page194_i56@mstr_sconn.sconn120_h61426002(chips)!SCONN120_H61426002_SM-CONN,H61A!!!F237!IOF5!!!!
S!GND!J6B1!F6!@baseboard_fab2_lib.baseboard_fab2(sch_1):page194_i56@mstr_sconn.sconn120_h61426002(chips)!SCONN120_H61426002_SM-CONN,H61A!!!F237!IOF6!!!!
S!GND!J6B1!F7!@baseboard_fab2_lib.baseboard_fab2(sch_1):page194_i56@mstr_sconn.sconn120_h61426002(chips)!SCONN120_H61426002_SM-CONN,H61A!!!F237!IOF7!!!!
S!VSENSE_PVCCIOMCP_CPU0_SKT_VRTN!J6B1!F8!@baseboard_fab2_lib.baseboard_fab2(sch_1):page194_i56@mstr_sconn.sconn120_h61426002(chips)!SCONN120_H61426002_SM-CONN,H61A!!!F237!IOF8!!!!
S!GND!J6B1!F9!@baseboard_fab2_lib.baseboard_fab2(sch_1):page194_i56@mstr_sconn.sconn120_h61426002(chips)!SCONN120_H61426002_SM-CONN,H61A!!!F237!IOF9!!!!
S!PVCCMCP_CPU0!J6E1!A1!@baseboard_fab2_lib.baseboard_fab2(sch_1):page194_i55@mstr_sconn.sconn120_h61426002(chips)!SCONN120_H61426002_SM-CONN,H61A!!!F236!IOA1!!!!
S!PVCCMCP_CPU0!J6E1!A10!@baseboard_fab2_lib.baseboard_fab2(sch_1):page194_i55@mstr_sconn.sconn120_h61426002(chips)!SCONN120_H61426002_SM-CONN,H61A!!!F236!IOA10!!!!
S!PVCCMCP_CPU0!J6E1!A11!@baseboard_fab2_lib.baseboard_fab2(sch_1):page194_i55@mstr_sconn.sconn120_h61426002(chips)!SCONN120_H61426002_SM-CONN,H61A!!!F236!IOA11!!!!
S!PVCCMCP_CPU0!J6E1!A12!@baseboard_fab2_lib.baseboard_fab2(sch_1):page194_i55@mstr_sconn.sconn120_h61426002(chips)!SCONN120_H61426002_SM-CONN,H61A!!!F236!IOA12!!!!
S!PVCCMCP_CPU0!J6E1!A13!@baseboard_fab2_lib.baseboard_fab2(sch_1):page194_i55@mstr_sconn.sconn120_h61426002(chips)!SCONN120_H61426002_SM-CONN,H61A!!!F236!IOA13!!!!
S!PVCCMCP_CPU0!J6E1!A14!@baseboard_fab2_lib.baseboard_fab2(sch_1):page194_i55@mstr_sconn.sconn120_h61426002(chips)!SCONN120_H61426002_SM-CONN,H61A!!!F236!IOA14!!!!
S!PVCCMCP_CPU0!J6E1!A15!@baseboard_fab2_lib.baseboard_fab2(sch_1):page194_i55@mstr_sconn.sconn120_h61426002(chips)!SCONN120_H61426002_SM-CONN,H61A!!!F236!IOA15!!!!
S!PVCCMCP_CPU0!J6E1!A16!@baseboard_fab2_lib.baseboard_fab2(sch_1):page194_i55@mstr_sconn.sconn120_h61426002(chips)!SCONN120_H61426002_SM-CONN,H61A!!!F236!IOA16!!!!
S!PVCCMCP_CPU0!J6E1!A17!@baseboard_fab2_lib.baseboard_fab2(sch_1):page194_i55@mstr_sconn.sconn120_h61426002(chips)!SCONN120_H61426002_SM-CONN,H61A!!!F236!IOA17!!!!
S!PVCCMCP_CPU0!J6E1!A18!@baseboard_fab2_lib.baseboard_fab2(sch_1):page194_i55@mstr_sconn.sconn120_h61426002(chips)!SCONN120_H61426002_SM-CONN,H61A!!!F236!IOA18!!!!
S!GND!J6E1!A19!@baseboard_fab2_lib.baseboard_fab2(sch_1):page194_i55@mstr_sconn.sconn120_h61426002(chips)!SCONN120_H61426002_SM-CONN,H61A!!!F236!IOA19!!!!
S!PVCCMCP_CPU0!J6E1!A2!@baseboard_fab2_lib.baseboard_fab2(sch_1):page194_i55@mstr_sconn.sconn120_h61426002(chips)!SCONN120_H61426002_SM-CONN,H61A!!!F236!IOA2!!!!
S!GND!J6E1!A20!@baseboard_fab2_lib.baseboard_fab2(sch_1):page194_i55@mstr_sconn.sconn120_h61426002(chips)!SCONN120_H61426002_SM-CONN,H61A!!!F236!IOA20!!!!
S!PVCCMCP_CPU0!J6E1!A3!@baseboard_fab2_lib.baseboard_fab2(sch_1):page194_i55@mstr_sconn.sconn120_h61426002(chips)!SCONN120_H61426002_SM-CONN,H61A!!!F236!IOA3!!!!
S!VSENSE_PVCCMCP_CPU0_SKT_VSEN!J6E1!A4!@baseboard_fab2_lib.baseboard_fab2(sch_1):page194_i55@mstr_sconn.sconn120_h61426002(chips)!SCONN120_H61426002_SM-CONN,H61A!!!F236!IOA4!!!!
S!PVCCMCP_CPU0!J6E1!A5!@baseboard_fab2_lib.baseboard_fab2(sch_1):page194_i55@mstr_sconn.sconn120_h61426002(chips)!SCONN120_H61426002_SM-CONN,H61A!!!F236!IOA5!!!!
S!PVCCMCP_CPU0!J6E1!A6!@baseboard_fab2_lib.baseboard_fab2(sch_1):page194_i55@mstr_sconn.sconn120_h61426002(chips)!SCONN120_H61426002_SM-CONN,H61A!!!F236!IOA6!!!!
S!PVCCMCP_CPU0!J6E1!A7!@baseboard_fab2_lib.baseboard_fab2(sch_1):page194_i55@mstr_sconn.sconn120_h61426002(chips)!SCONN120_H61426002_SM-CONN,H61A!!!F236!IOA7!!!!
S!PVCCMCP_CPU0!J6E1!A8!@baseboard_fab2_lib.baseboard_fab2(sch_1):page194_i55@mstr_sconn.sconn120_h61426002(chips)!SCONN120_H61426002_SM-CONN,H61A!!!F236!IOA8!!!!
S!PVCCMCP_CPU0!J6E1!A9!@baseboard_fab2_lib.baseboard_fab2(sch_1):page194_i55@mstr_sconn.sconn120_h61426002(chips)!SCONN120_H61426002_SM-CONN,H61A!!!F236!IOA9!!!!
S!PVCCMCP_CPU0!J6E1!B1!@baseboard_fab2_lib.baseboard_fab2(sch_1):page194_i55@mstr_sconn.sconn120_h61426002(chips)!SCONN120_H61426002_SM-CONN,H61A!!!F236!IOB1!!!!
S!PVCCMCP_CPU0!J6E1!B10!@baseboard_fab2_lib.baseboard_fab2(sch_1):page194_i55@mstr_sconn.sconn120_h61426002(chips)!SCONN120_H61426002_SM-CONN,H61A!!!F236!IOB10!!!!
S!PVCCMCP_CPU0!J6E1!B11!@baseboard_fab2_lib.baseboard_fab2(sch_1):page194_i55@mstr_sconn.sconn120_h61426002(chips)!SCONN120_H61426002_SM-CONN,H61A!!!F236!IOB11!!!!
S!PVCCMCP_CPU0!J6E1!B12!@baseboard_fab2_lib.baseboard_fab2(sch_1):page194_i55@mstr_sconn.sconn120_h61426002(chips)!SCONN120_H61426002_SM-CONN,H61A!!!F236!IOB12!!!!
S!PVCCMCP_CPU0!J6E1!B13!@baseboard_fab2_lib.baseboard_fab2(sch_1):page194_i55@mstr_sconn.sconn120_h61426002(chips)!SCONN120_H61426002_SM-CONN,H61A!!!F236!IOB13!!!!
S!PVCCMCP_CPU0!J6E1!B14!@baseboard_fab2_lib.baseboard_fab2(sch_1):page194_i55@mstr_sconn.sconn120_h61426002(chips)!SCONN120_H61426002_SM-CONN,H61A!!!F236!IOB14!!!!
S!PVCCMCP_CPU0!J6E1!B15!@baseboard_fab2_lib.baseboard_fab2(sch_1):page194_i55@mstr_sconn.sconn120_h61426002(chips)!SCONN120_H61426002_SM-CONN,H61A!!!F236!IOB15!!!!
S!PVCCMCP_CPU0!J6E1!B16!@baseboard_fab2_lib.baseboard_fab2(sch_1):page194_i55@mstr_sconn.sconn120_h61426002(chips)!SCONN120_H61426002_SM-CONN,H61A!!!F236!IOB16!!!!
S!PVCCMCP_CPU0!J6E1!B17!@baseboard_fab2_lib.baseboard_fab2(sch_1):page194_i55@mstr_sconn.sconn120_h61426002(chips)!SCONN120_H61426002_SM-CONN,H61A!!!F236!IOB17!!!!
S!PVCCMCP_CPU0!J6E1!B18!@baseboard_fab2_lib.baseboard_fab2(sch_1):page194_i55@mstr_sconn.sconn120_h61426002(chips)!SCONN120_H61426002_SM-CONN,H61A!!!F236!IOB18!!!!
S!GND!J6E1!B19!@baseboard_fab2_lib.baseboard_fab2(sch_1):page194_i55@mstr_sconn.sconn120_h61426002(chips)!SCONN120_H61426002_SM-CONN,H61A!!!F236!IOB19!!!!
S!PVCCMCP_CPU0!J6E1!B2!@baseboard_fab2_lib.baseboard_fab2(sch_1):page194_i55@mstr_sconn.sconn120_h61426002(chips)!SCONN120_H61426002_SM-CONN,H61A!!!F236!IOB2!!!!
S!GND!J6E1!B20!@baseboard_fab2_lib.baseboard_fab2(sch_1):page194_i55@mstr_sconn.sconn120_h61426002(chips)!SCONN120_H61426002_SM-CONN,H61A!!!F236!IOB20!!!!
S!PVCCMCP_CPU0!J6E1!B3!@baseboard_fab2_lib.baseboard_fab2(sch_1):page194_i55@mstr_sconn.sconn120_h61426002(chips)!SCONN120_H61426002_SM-CONN,H61A!!!F236!IOB3!!!!
S!VSENSE_PVCCMCP_CPU0_SKT_VRTN!J6E1!B4!@baseboard_fab2_lib.baseboard_fab2(sch_1):page194_i55@mstr_sconn.sconn120_h61426002(chips)!SCONN120_H61426002_SM-CONN,H61A!!!F236!IOB4!!!!
S!PVCCMCP_CPU0!J6E1!B5!@baseboard_fab2_lib.baseboard_fab2(sch_1):page194_i55@mstr_sconn.sconn120_h61426002(chips)!SCONN120_H61426002_SM-CONN,H61A!!!F236!IOB5!!!!
S!PVCCMCP_CPU0!J6E1!B6!@baseboard_fab2_lib.baseboard_fab2(sch_1):page194_i55@mstr_sconn.sconn120_h61426002(chips)!SCONN120_H61426002_SM-CONN,H61A!!!F236!IOB6!!!!
S!PVCCMCP_CPU0!J6E1!B7!@baseboard_fab2_lib.baseboard_fab2(sch_1):page194_i55@mstr_sconn.sconn120_h61426002(chips)!SCONN120_H61426002_SM-CONN,H61A!!!F236!IOB7!!!!
S!PVCCMCP_CPU0!J6E1!B8!@baseboard_fab2_lib.baseboard_fab2(sch_1):page194_i55@mstr_sconn.sconn120_h61426002(chips)!SCONN120_H61426002_SM-CONN,H61A!!!F236!IOB8!!!!
S!PVCCMCP_CPU0!J6E1!B9!@baseboard_fab2_lib.baseboard_fab2(sch_1):page194_i55@mstr_sconn.sconn120_h61426002(chips)!SCONN120_H61426002_SM-CONN,H61A!!!F236!IOB9!!!!
S!PVCCMCP_CPU0!J6E1!C1!@baseboard_fab2_lib.baseboard_fab2(sch_1):page194_i55@mstr_sconn.sconn120_h61426002(chips)!SCONN120_H61426002_SM-CONN,H61A!!!F236!IOC1!!!!
S!PVCCMCP_CPU0!J6E1!C10!@baseboard_fab2_lib.baseboard_fab2(sch_1):page194_i55@mstr_sconn.sconn120_h61426002(chips)!SCONN120_H61426002_SM-CONN,H61A!!!F236!IOC10!!!!
S!PVCCMCP_CPU0!J6E1!C11!@baseboard_fab2_lib.baseboard_fab2(sch_1):page194_i55@mstr_sconn.sconn120_h61426002(chips)!SCONN120_H61426002_SM-CONN,H61A!!!F236!IOC11!!!!
S!PVCCMCP_CPU0!J6E1!C12!@baseboard_fab2_lib.baseboard_fab2(sch_1):page194_i55@mstr_sconn.sconn120_h61426002(chips)!SCONN120_H61426002_SM-CONN,H61A!!!F236!IOC12!!!!
S!PVCCMCP_CPU0!J6E1!C13!@baseboard_fab2_lib.baseboard_fab2(sch_1):page194_i55@mstr_sconn.sconn120_h61426002(chips)!SCONN120_H61426002_SM-CONN,H61A!!!F236!IOC13!!!!
S!PVCCMCP_CPU0!J6E1!C14!@baseboard_fab2_lib.baseboard_fab2(sch_1):page194_i55@mstr_sconn.sconn120_h61426002(chips)!SCONN120_H61426002_SM-CONN,H61A!!!F236!IOC14!!!!
S!PVCCMCP_CPU0!J6E1!C15!@baseboard_fab2_lib.baseboard_fab2(sch_1):page194_i55@mstr_sconn.sconn120_h61426002(chips)!SCONN120_H61426002_SM-CONN,H61A!!!F236!IOC15!!!!
S!PVCCMCP_CPU0!J6E1!C16!@baseboard_fab2_lib.baseboard_fab2(sch_1):page194_i55@mstr_sconn.sconn120_h61426002(chips)!SCONN120_H61426002_SM-CONN,H61A!!!F236!IOC16!!!!
S!PVCCMCP_CPU0!J6E1!C17!@baseboard_fab2_lib.baseboard_fab2(sch_1):page194_i55@mstr_sconn.sconn120_h61426002(chips)!SCONN120_H61426002_SM-CONN,H61A!!!F236!IOC17!!!!
S!PVCCMCP_CPU0!J6E1!C18!@baseboard_fab2_lib.baseboard_fab2(sch_1):page194_i55@mstr_sconn.sconn120_h61426002(chips)!SCONN120_H61426002_SM-CONN,H61A!!!F236!IOC18!!!!
S!GND!J6E1!C19!@baseboard_fab2_lib.baseboard_fab2(sch_1):page194_i55@mstr_sconn.sconn120_h61426002(chips)!SCONN120_H61426002_SM-CONN,H61A!!!F236!IOC19!!!!
S!PVCCMCP_CPU0!J6E1!C2!@baseboard_fab2_lib.baseboard_fab2(sch_1):page194_i55@mstr_sconn.sconn120_h61426002(chips)!SCONN120_H61426002_SM-CONN,H61A!!!F236!IOC2!!!!
S!GND!J6E1!C20!@baseboard_fab2_lib.baseboard_fab2(sch_1):page194_i55@mstr_sconn.sconn120_h61426002(chips)!SCONN120_H61426002_SM-CONN,H61A!!!F236!IOC20!!!!
S!PVCCMCP_CPU0!J6E1!C3!@baseboard_fab2_lib.baseboard_fab2(sch_1):page194_i55@mstr_sconn.sconn120_h61426002(chips)!SCONN120_H61426002_SM-CONN,H61A!!!F236!IOC3!!!!
S!PVCCMCP_CPU0!J6E1!C4!@baseboard_fab2_lib.baseboard_fab2(sch_1):page194_i55@mstr_sconn.sconn120_h61426002(chips)!SCONN120_H61426002_SM-CONN,H61A!!!F236!IOC4!!!!
S!PVCCMCP_CPU0!J6E1!C5!@baseboard_fab2_lib.baseboard_fab2(sch_1):page194_i55@mstr_sconn.sconn120_h61426002(chips)!SCONN120_H61426002_SM-CONN,H61A!!!F236!IOC5!!!!
S!PVCCMCP_CPU0!J6E1!C6!@baseboard_fab2_lib.baseboard_fab2(sch_1):page194_i55@mstr_sconn.sconn120_h61426002(chips)!SCONN120_H61426002_SM-CONN,H61A!!!F236!IOC6!!!!
S!PVCCMCP_CPU0!J6E1!C7!@baseboard_fab2_lib.baseboard_fab2(sch_1):page194_i55@mstr_sconn.sconn120_h61426002(chips)!SCONN120_H61426002_SM-CONN,H61A!!!F236!IOC7!!!!
S!PVCCMCP_CPU0!J6E1!C8!@baseboard_fab2_lib.baseboard_fab2(sch_1):page194_i55@mstr_sconn.sconn120_h61426002(chips)!SCONN120_H61426002_SM-CONN,H61A!!!F236!IOC8!!!!
S!PVCCMCP_CPU0!J6E1!C9!@baseboard_fab2_lib.baseboard_fab2(sch_1):page194_i55@mstr_sconn.sconn120_h61426002(chips)!SCONN120_H61426002_SM-CONN,H61A!!!F236!IOC9!!!!
S!VSENSE_P1V8MCP_CPU0_SKT_VSEN!J6E1!D1!@baseboard_fab2_lib.baseboard_fab2(sch_1):page194_i55@mstr_sconn.sconn120_h61426002(chips)!SCONN120_H61426002_SM-CONN,H61A!!!F236!IOD1!!!!
S!GND!J6E1!D10!@baseboard_fab2_lib.baseboard_fab2(sch_1):page194_i55@mstr_sconn.sconn120_h61426002(chips)!SCONN120_H61426002_SM-CONN,H61A!!!F236!IOD10!!!!
S!GND!J6E1!D11!@baseboard_fab2_lib.baseboard_fab2(sch_1):page194_i55@mstr_sconn.sconn120_h61426002(chips)!SCONN120_H61426002_SM-CONN,H61A!!!F236!IOD11!!!!
S!GND!J6E1!D12!@baseboard_fab2_lib.baseboard_fab2(sch_1):page194_i55@mstr_sconn.sconn120_h61426002(chips)!SCONN120_H61426002_SM-CONN,H61A!!!F236!IOD12!!!!
S!GND!J6E1!D13!@baseboard_fab2_lib.baseboard_fab2(sch_1):page194_i55@mstr_sconn.sconn120_h61426002(chips)!SCONN120_H61426002_SM-CONN,H61A!!!F236!IOD13!!!!
S!GND!J6E1!D14!@baseboard_fab2_lib.baseboard_fab2(sch_1):page194_i55@mstr_sconn.sconn120_h61426002(chips)!SCONN120_H61426002_SM-CONN,H61A!!!F236!IOD14!!!!
S!GND!J6E1!D15!@baseboard_fab2_lib.baseboard_fab2(sch_1):page194_i55@mstr_sconn.sconn120_h61426002(chips)!SCONN120_H61426002_SM-CONN,H61A!!!F236!IOD15!!!!
S!GND!J6E1!D16!@baseboard_fab2_lib.baseboard_fab2(sch_1):page194_i55@mstr_sconn.sconn120_h61426002(chips)!SCONN120_H61426002_SM-CONN,H61A!!!F236!IOD16!!!!
S!GND!J6E1!D17!@baseboard_fab2_lib.baseboard_fab2(sch_1):page194_i55@mstr_sconn.sconn120_h61426002(chips)!SCONN120_H61426002_SM-CONN,H61A!!!F236!IOD17!!!!
S!GND!J6E1!D18!@baseboard_fab2_lib.baseboard_fab2(sch_1):page194_i55@mstr_sconn.sconn120_h61426002(chips)!SCONN120_H61426002_SM-CONN,H61A!!!F236!IOD18!!!!
S!GND!J6E1!D19!@baseboard_fab2_lib.baseboard_fab2(sch_1):page194_i55@mstr_sconn.sconn120_h61426002(chips)!SCONN120_H61426002_SM-CONN,H61A!!!F236!IOD19!!!!
S!VSENSE_P1V8MCP_CPU0_SKT_VRTN!J6E1!D2!@baseboard_fab2_lib.baseboard_fab2(sch_1):page194_i55@mstr_sconn.sconn120_h61426002(chips)!SCONN120_H61426002_SM-CONN,H61A!!!F236!IOD2!!!!
S!GND!J6E1!D20!@baseboard_fab2_lib.baseboard_fab2(sch_1):page194_i55@mstr_sconn.sconn120_h61426002(chips)!SCONN120_H61426002_SM-CONN,H61A!!!F236!IOD20!!!!
S!GND!J6E1!D3!@baseboard_fab2_lib.baseboard_fab2(sch_1):page194_i55@mstr_sconn.sconn120_h61426002(chips)!SCONN120_H61426002_SM-CONN,H61A!!!F236!IOD3!!!!
S!GND!J6E1!D4!@baseboard_fab2_lib.baseboard_fab2(sch_1):page194_i55@mstr_sconn.sconn120_h61426002(chips)!SCONN120_H61426002_SM-CONN,H61A!!!F236!IOD4!!!!
S!GND!J6E1!D5!@baseboard_fab2_lib.baseboard_fab2(sch_1):page194_i55@mstr_sconn.sconn120_h61426002(chips)!SCONN120_H61426002_SM-CONN,H61A!!!F236!IOD5!!!!
S!GND!J6E1!D6!@baseboard_fab2_lib.baseboard_fab2(sch_1):page194_i55@mstr_sconn.sconn120_h61426002(chips)!SCONN120_H61426002_SM-CONN,H61A!!!F236!IOD6!!!!
S!GND!J6E1!D7!@baseboard_fab2_lib.baseboard_fab2(sch_1):page194_i55@mstr_sconn.sconn120_h61426002(chips)!SCONN120_H61426002_SM-CONN,H61A!!!F236!IOD7!!!!
S!GND!J6E1!D8!@baseboard_fab2_lib.baseboard_fab2(sch_1):page194_i55@mstr_sconn.sconn120_h61426002(chips)!SCONN120_H61426002_SM-CONN,H61A!!!F236!IOD8!!!!
S!GND!J6E1!D9!@baseboard_fab2_lib.baseboard_fab2(sch_1):page194_i55@mstr_sconn.sconn120_h61426002(chips)!SCONN120_H61426002_SM-CONN,H61A!!!F236!IOD9!!!!
S!P1V8_MCP_CPU0!J6E1!E1!@baseboard_fab2_lib.baseboard_fab2(sch_1):page194_i55@mstr_sconn.sconn120_h61426002(chips)!SCONN120_H61426002_SM-CONN,H61A!!!F236!IOE1!!!!
S!GND!J6E1!E10!@baseboard_fab2_lib.baseboard_fab2(sch_1):page194_i55@mstr_sconn.sconn120_h61426002(chips)!SCONN120_H61426002_SM-CONN,H61A!!!F236!IOE10!!!!
S!GND!J6E1!E11!@baseboard_fab2_lib.baseboard_fab2(sch_1):page194_i55@mstr_sconn.sconn120_h61426002(chips)!SCONN120_H61426002_SM-CONN,H61A!!!F236!IOE11!!!!
S!GND!J6E1!E12!@baseboard_fab2_lib.baseboard_fab2(sch_1):page194_i55@mstr_sconn.sconn120_h61426002(chips)!SCONN120_H61426002_SM-CONN,H61A!!!F236!IOE12!!!!
S!GND!J6E1!E13!@baseboard_fab2_lib.baseboard_fab2(sch_1):page194_i55@mstr_sconn.sconn120_h61426002(chips)!SCONN120_H61426002_SM-CONN,H61A!!!F236!IOE13!!!!
S!GND!J6E1!E14!@baseboard_fab2_lib.baseboard_fab2(sch_1):page194_i55@mstr_sconn.sconn120_h61426002(chips)!SCONN120_H61426002_SM-CONN,H61A!!!F236!IOE14!!!!
S!GND!J6E1!E15!@baseboard_fab2_lib.baseboard_fab2(sch_1):page194_i55@mstr_sconn.sconn120_h61426002(chips)!SCONN120_H61426002_SM-CONN,H61A!!!F236!IOE15!!!!
S!GND!J6E1!E16!@baseboard_fab2_lib.baseboard_fab2(sch_1):page194_i55@mstr_sconn.sconn120_h61426002(chips)!SCONN120_H61426002_SM-CONN,H61A!!!F236!IOE16!!!!
S!GND!J6E1!E17!@baseboard_fab2_lib.baseboard_fab2(sch_1):page194_i55@mstr_sconn.sconn120_h61426002(chips)!SCONN120_H61426002_SM-CONN,H61A!!!F236!IOE17!!!!
S!GND!J6E1!E18!@baseboard_fab2_lib.baseboard_fab2(sch_1):page194_i55@mstr_sconn.sconn120_h61426002(chips)!SCONN120_H61426002_SM-CONN,H61A!!!F236!IOE18!!!!
S!GND!J6E1!E19!@baseboard_fab2_lib.baseboard_fab2(sch_1):page194_i55@mstr_sconn.sconn120_h61426002(chips)!SCONN120_H61426002_SM-CONN,H61A!!!F236!IOE19!!!!
S!P1V8_MCP_CPU0!J6E1!E2!@baseboard_fab2_lib.baseboard_fab2(sch_1):page194_i55@mstr_sconn.sconn120_h61426002(chips)!SCONN120_H61426002_SM-CONN,H61A!!!F236!IOE2!!!!
S!GND!J6E1!E20!@baseboard_fab2_lib.baseboard_fab2(sch_1):page194_i55@mstr_sconn.sconn120_h61426002(chips)!SCONN120_H61426002_SM-CONN,H61A!!!F236!IOE20!!!!
S!GND!J6E1!E3!@baseboard_fab2_lib.baseboard_fab2(sch_1):page194_i55@mstr_sconn.sconn120_h61426002(chips)!SCONN120_H61426002_SM-CONN,H61A!!!F236!IOE3!!!!
S!GND!J6E1!E4!@baseboard_fab2_lib.baseboard_fab2(sch_1):page194_i55@mstr_sconn.sconn120_h61426002(chips)!SCONN120_H61426002_SM-CONN,H61A!!!F236!IOE4!!!!
S!CLK_322M_156M_CPU0_OSC_VRM_DP!J6E1!E5!@baseboard_fab2_lib.baseboard_fab2(sch_1):page194_i55@mstr_sconn.sconn120_h61426002(chips)!SCONN120_H61426002_SM-CONN,H61A!!!F236!IOE5!!!!
S!GND!J6E1!E6!@baseboard_fab2_lib.baseboard_fab2(sch_1):page194_i55@mstr_sconn.sconn120_h61426002(chips)!SCONN120_H61426002_SM-CONN,H61A!!!F236!IOE6!!!!
S!GND!J6E1!E7!@baseboard_fab2_lib.baseboard_fab2(sch_1):page194_i55@mstr_sconn.sconn120_h61426002(chips)!SCONN120_H61426002_SM-CONN,H61A!!!F236!IOE7!!!!
S!GND!J6E1!E8!@baseboard_fab2_lib.baseboard_fab2(sch_1):page194_i55@mstr_sconn.sconn120_h61426002(chips)!SCONN120_H61426002_SM-CONN,H61A!!!F236!IOE8!!!!
S!GND!J6E1!E9!@baseboard_fab2_lib.baseboard_fab2(sch_1):page194_i55@mstr_sconn.sconn120_h61426002(chips)!SCONN120_H61426002_SM-CONN,H61A!!!F236!IOE9!!!!
S!P1V8_MCP_CPU0!J6E1!F1!@baseboard_fab2_lib.baseboard_fab2(sch_1):page194_i55@mstr_sconn.sconn120_h61426002(chips)!SCONN120_H61426002_SM-CONN,H61A!!!F236!IOF1!!!!
S!GND!J6E1!F10!@baseboard_fab2_lib.baseboard_fab2(sch_1):page194_i55@mstr_sconn.sconn120_h61426002(chips)!SCONN120_H61426002_SM-CONN,H61A!!!F236!IOF10!!!!
S!GND!J6E1!F11!@baseboard_fab2_lib.baseboard_fab2(sch_1):page194_i55@mstr_sconn.sconn120_h61426002(chips)!SCONN120_H61426002_SM-CONN,H61A!!!F236!IOF11!!!!
S!GND!J6E1!F12!@baseboard_fab2_lib.baseboard_fab2(sch_1):page194_i55@mstr_sconn.sconn120_h61426002(chips)!SCONN120_H61426002_SM-CONN,H61A!!!F236!IOF12!!!!
S!GND!J6E1!F13!@baseboard_fab2_lib.baseboard_fab2(sch_1):page194_i55@mstr_sconn.sconn120_h61426002(chips)!SCONN120_H61426002_SM-CONN,H61A!!!F236!IOF13!!!!
S!GND!J6E1!F14!@baseboard_fab2_lib.baseboard_fab2(sch_1):page194_i55@mstr_sconn.sconn120_h61426002(chips)!SCONN120_H61426002_SM-CONN,H61A!!!F236!IOF14!!!!
S!GND!J6E1!F15!@baseboard_fab2_lib.baseboard_fab2(sch_1):page194_i55@mstr_sconn.sconn120_h61426002(chips)!SCONN120_H61426002_SM-CONN,H61A!!!F236!IOF15!!!!
S!GND!J6E1!F16!@baseboard_fab2_lib.baseboard_fab2(sch_1):page194_i55@mstr_sconn.sconn120_h61426002(chips)!SCONN120_H61426002_SM-CONN,H61A!!!F236!IOF16!!!!
S!GND!J6E1!F17!@baseboard_fab2_lib.baseboard_fab2(sch_1):page194_i55@mstr_sconn.sconn120_h61426002(chips)!SCONN120_H61426002_SM-CONN,H61A!!!F236!IOF17!!!!
S!GND!J6E1!F18!@baseboard_fab2_lib.baseboard_fab2(sch_1):page194_i55@mstr_sconn.sconn120_h61426002(chips)!SCONN120_H61426002_SM-CONN,H61A!!!F236!IOF18!!!!
S!GND!J6E1!F19!@baseboard_fab2_lib.baseboard_fab2(sch_1):page194_i55@mstr_sconn.sconn120_h61426002(chips)!SCONN120_H61426002_SM-CONN,H61A!!!F236!IOF19!!!!
S!P1V8_MCP_CPU0!J6E1!F2!@baseboard_fab2_lib.baseboard_fab2(sch_1):page194_i55@mstr_sconn.sconn120_h61426002(chips)!SCONN120_H61426002_SM-CONN,H61A!!!F236!IOF2!!!!
S!GND!J6E1!F20!@baseboard_fab2_lib.baseboard_fab2(sch_1):page194_i55@mstr_sconn.sconn120_h61426002(chips)!SCONN120_H61426002_SM-CONN,H61A!!!F236!IOF20!!!!
S!GND!J6E1!F3!@baseboard_fab2_lib.baseboard_fab2(sch_1):page194_i55@mstr_sconn.sconn120_h61426002(chips)!SCONN120_H61426002_SM-CONN,H61A!!!F236!IOF3!!!!
S!GND!J6E1!F4!@baseboard_fab2_lib.baseboard_fab2(sch_1):page194_i55@mstr_sconn.sconn120_h61426002(chips)!SCONN120_H61426002_SM-CONN,H61A!!!F236!IOF4!!!!
S!CLK_322M_156M_CPU0_OSC_VRM_DN!J6E1!F5!@baseboard_fab2_lib.baseboard_fab2(sch_1):page194_i55@mstr_sconn.sconn120_h61426002(chips)!SCONN120_H61426002_SM-CONN,H61A!!!F236!IOF5!!!!
S!GND!J6E1!F6!@baseboard_fab2_lib.baseboard_fab2(sch_1):page194_i55@mstr_sconn.sconn120_h61426002(chips)!SCONN120_H61426002_SM-CONN,H61A!!!F236!IOF6!!!!
S!GND!J6E1!F7!@baseboard_fab2_lib.baseboard_fab2(sch_1):page194_i55@mstr_sconn.sconn120_h61426002(chips)!SCONN120_H61426002_SM-CONN,H61A!!!F236!IOF7!!!!
S!GND!J6E1!F8!@baseboard_fab2_lib.baseboard_fab2(sch_1):page194_i55@mstr_sconn.sconn120_h61426002(chips)!SCONN120_H61426002_SM-CONN,H61A!!!F236!IOF8!!!!
S!GND!J6E1!F9!@baseboard_fab2_lib.baseboard_fab2(sch_1):page194_i55@mstr_sconn.sconn120_h61426002(chips)!SCONN120_H61426002_SM-CONN,H61A!!!F236!IOF9!!!!
S!GND!U1B3!1!@baseboard_fab2_lib.baseboard_fab2(sch_1):page209_i52@mstr_analog.adm4073(chips)!ADM4073_SM-EMPTY,G12194-001!!!F4196!GND(0)!!!!
S!GND!U1B3!2!@baseboard_fab2_lib.baseboard_fab2(sch_1):page209_i52@mstr_analog.adm4073(chips)!ADM4073_SM-EMPTY,G12194-001!!!F4196!GND(1)!!!!
S!PVCCIN_PVSA_CPU1_IINSEN!U1B3!6!@baseboard_fab2_lib.baseboard_fab2(sch_1):page209_i52@mstr_analog.adm4073(chips)!ADM4073_SM-EMPTY,G12194-001!!!F4196!\out\!!!!
S!VR_FET_SW_P12V_STBY_PVCCIN_CPU1!U1B3!5!@baseboard_fab2_lib.baseboard_fab2(sch_1):page209_i52@mstr_analog.adm4073(chips)!ADM4073_SM-EMPTY,G12194-001!!!F4196!RSN!!!!
S!VR_FET_SW_P12V_PVCCIN_CPU1_R!U1B3!4!@baseboard_fab2_lib.baseboard_fab2(sch_1):page209_i52@mstr_analog.adm4073(chips)!ADM4073_SM-EMPTY,G12194-001!!!F4196!RSP!!!!
S!VR_FET_SW_P12V_PVCCIN_CPU1_R!U1B3!3!@baseboard_fab2_lib.baseboard_fab2(sch_1):page209_i52@mstr_analog.adm4073(chips)!ADM4073_SM-EMPTY,G12194-001!!!F4196!VCC!!!!
S!GND!U4C1!1!@baseboard_fab2_lib.baseboard_fab2(sch_1):page204_i53@mstr_analog.adm4073(chips)!ADM4073_SM-EMPTY,G12194-001!!!F4195!GND(0)!!!!
S!GND!U4C1!2!@baseboard_fab2_lib.baseboard_fab2(sch_1):page204_i53@mstr_analog.adm4073(chips)!ADM4073_SM-EMPTY,G12194-001!!!F4195!GND(1)!!!!
S!PVCCIN_PVSA_CPU0_IINSEN!U4C1!6!@baseboard_fab2_lib.baseboard_fab2(sch_1):page204_i53@mstr_analog.adm4073(chips)!ADM4073_SM-EMPTY,G12194-001!!!F4195!\out\!!!!
S!VR_FET_SW_P12V_STBY_PVCCIN_CPU0!U4C1!5!@baseboard_fab2_lib.baseboard_fab2(sch_1):page204_i53@mstr_analog.adm4073(chips)!ADM4073_SM-EMPTY,G12194-001!!!F4195!RSN!!!!
S!VR_FET_SW_P12V_PVCCIN_CPU0_R!U4C1!4!@baseboard_fab2_lib.baseboard_fab2(sch_1):page204_i53@mstr_analog.adm4073(chips)!ADM4073_SM-EMPTY,G12194-001!!!F4195!RSP!!!!
S!VR_FET_SW_P12V_PVCCIN_CPU0_R!U4C1!3!@baseboard_fab2_lib.baseboard_fab2(sch_1):page204_i53@mstr_analog.adm4073(chips)!ADM4073_SM-EMPTY,G12194-001!!!F4195!VCC!!!!
S!P1V8_BMC_STBY_PCIE!C1T18!1!@baseboard_fab2_lib.baseboard_fab2(sch_1):page149_i152@mstr_discrete.cap(chips)!CAP_0402-1.0UF,6.3V,10%,EMPTY,A!!!F3757!A!!!!
S!GND!C1T18!2!@baseboard_fab2_lib.baseboard_fab2(sch_1):page149_i152@mstr_discrete.cap(chips)!CAP_0402-1.0UF,6.3V,10%,EMPTY,A!!!F3757!B!!!!
S!P1V8_BMC_STBY_PCIEA!C8F9!1!@baseboard_fab2_lib.baseboard_fab2(sch_1):page149_i161@mstr_discrete.cap(chips)!CAP_0402-1.0UF,6.3V,10%,EMPTY,A!!!F3756!A!!!!
S!GND!C8F9!2!@baseboard_fab2_lib.baseboard_fab2(sch_1):page149_i161@mstr_discrete.cap(chips)!CAP_0402-1.0UF,6.3V,10%,EMPTY,A!!!F3756!B!!!!
S!P1V8_BMC_STBY_PCIE!C1T16!1!@baseboard_fab2_lib.baseboard_fab2(sch_1):page149_i150@mstr_discrete.cap(chips)!CAP_0603-10UF,6.3V,20%,EMPTY,EA!!!F3092!A!!!!
S!GND!C1T16!2!@baseboard_fab2_lib.baseboard_fab2(sch_1):page149_i150@mstr_discrete.cap(chips)!CAP_0603-10UF,6.3V,20%,EMPTY,EA!!!F3092!B!!!!
S!P1V8_BMC_STBY_PCIEA!C8F10!1!@baseboard_fab2_lib.baseboard_fab2(sch_1):page149_i159@mstr_discrete.cap(chips)!CAP_0603-10UF,6.3V,20%,EMPTY,EA!!!F3091!A!!!!
S!GND!C8F10!2!@baseboard_fab2_lib.baseboard_fab2(sch_1):page149_i159@mstr_discrete.cap(chips)!CAP_0603-10UF,6.3V,20%,EMPTY,EA!!!F3091!B!!!!
S!P0V9_LAN!C9E1!1!@baseboard_fab2_lib.baseboard_fab2(sch_1):page139_i163@mstr_discrete.cap(chips)!CAP_0603-22.0UF,4V,20%,EMPTY,EA!!!F3068!A!!!!
S!GND!C9E1!2!@baseboard_fab2_lib.baseboard_fab2(sch_1):page139_i163@mstr_discrete.cap(chips)!CAP_0603-22.0UF,4V,20%,EMPTY,EA!!!F3068!B!!!!
S!P0V9_LAN!C9E12!1!@baseboard_fab2_lib.baseboard_fab2(sch_1):page139_i241@mstr_discrete.cap(chips)!CAP_0603-22.0UF,4V,20%,EMPTY,EA!!!F3067!A!!!!
S!GND!C9E12!2!@baseboard_fab2_lib.baseboard_fab2(sch_1):page139_i241@mstr_discrete.cap(chips)!CAP_0603-22.0UF,4V,20%,EMPTY,EA!!!F3067!B!!!!
S!P1V8_PCH_STBY!FB1T1!1!@baseboard_fab2_lib.baseboard_fab2(sch_1):page149_i153@mstr_discrete.ferrite(chips)!FERRITE_SMLF-300,EMPTY,693286-A!!!F2190!A!!!!
S!P1V8_BMC_STBY_PCIE!FB1T1!2!@baseboard_fab2_lib.baseboard_fab2(sch_1):page149_i153@mstr_discrete.ferrite(chips)!FERRITE_SMLF-300,EMPTY,693286-A!!!F2190!B!!!!
S!P1V8_PCH_STBY!FB2T1!1!@baseboard_fab2_lib.baseboard_fab2(sch_1):page149_i163@mstr_discrete.ferrite(chips)!FERRITE_SMLF-300,EMPTY,693286-A!!!F2189!A!!!!
S!P1V8_BMC_STBY_PCIEA!FB2T1!2!@baseboard_fab2_lib.baseboard_fab2(sch_1):page149_i163@mstr_discrete.ferrite(chips)!FERRITE_SMLF-300,EMPTY,693286-A!!!F2189!B!!!!
S!PU_24M_OSC_OE!Y9F2!1!@baseboard_fab2_lib.baseboard_fab2(sch_1):page145_i250@mstr_discrete.osc_c(chips)!OSC_C_SM4-24MHZ,OSC,D34520-021!!!F1987!ENABLE_CONTROL!!!!
S!GND!Y9F2!2!@baseboard_fab2_lib.baseboard_fab2(sch_1):page145_i250@mstr_discrete.osc_c(chips)!OSC_C_SM4-24MHZ,OSC,D34520-021!!!F1987!GND!!!!
S!CLK_24M_BMC_CLKIN_R!Y9F2!3!@baseboard_fab2_lib.baseboard_fab2(sch_1):page145_i250@mstr_discrete.osc_c(chips)!OSC_C_SM4-24MHZ,OSC,D34520-021!!!F1987!\out\!!!!
S!P3V3_STBY!Y9F2!4!@baseboard_fab2_lib.baseboard_fab2(sch_1):page145_i250@mstr_discrete.osc_c(chips)!OSC_C_SM4-24MHZ,OSC,D34520-021!!!F1987!VDD!!!!
S!SMB_OCP_FRU_STBY_LVC3_SCL!J8E4!1!@baseboard_fab2_lib.baseboard_fab2(sch_1):page188_i27@mstr_sconn.sconn64_h87568002_a(chips)!SCONN64_H87568002_A_SMT-CONN,HA!!!F134!IO1!!!!
S!GND!J8E4!10!@baseboard_fab2_lib.baseboard_fab2(sch_1):page188_i27@mstr_sconn.sconn64_h87568002_a(chips)!SCONN64_H87568002_A_SMT-CONN,HA!!!F134!IO10!!!!
S!KR_P3_OCP_TX_DP!J8E4!11!@baseboard_fab2_lib.baseboard_fab2(sch_1):page188_i27@mstr_sconn.sconn64_h87568002_a(chips)!SCONN64_H87568002_A_SMT-CONN,HA!!!F134!IO11!!!!
S!KR_P3_OCP_TX_DN!J8E4!12!@baseboard_fab2_lib.baseboard_fab2(sch_1):page188_i27@mstr_sconn.sconn64_h87568002_a(chips)!SCONN64_H87568002_A_SMT-CONN,HA!!!F134!IO12!!!!
S!GND!J8E4!13!@baseboard_fab2_lib.baseboard_fab2(sch_1):page188_i27@mstr_sconn.sconn64_h87568002_a(chips)!SCONN64_H87568002_A_SMT-CONN,HA!!!F134!IO13!!!!
S!LED_GBE_P2_0!J8E4!14!@baseboard_fab2_lib.baseboard_fab2(sch_1):page188_i27@mstr_sconn.sconn64_h87568002_a(chips)!SCONN64_H87568002_A_SMT-CONN,HA!!!F134!IO14!!!!
S!LED_GBE_P2_1!J8E4!15!@baseboard_fab2_lib.baseboard_fab2(sch_1):page188_i27@mstr_sconn.sconn64_h87568002_a(chips)!SCONN64_H87568002_A_SMT-CONN,HA!!!F134!IO15!!!!
S!GND!J8E4!16!@baseboard_fab2_lib.baseboard_fab2(sch_1):page188_i27@mstr_sconn.sconn64_h87568002_a(chips)!SCONN64_H87568002_A_SMT-CONN,HA!!!F134!IO16!!!!
S!KR_P2_OCP_RX_DP!J8E4!17!@baseboard_fab2_lib.baseboard_fab2(sch_1):page188_i27@mstr_sconn.sconn64_h87568002_a(chips)!SCONN64_H87568002_A_SMT-CONN,HA!!!F134!IO17!!!!
S!KR_P2_OCP_RX_DN!J8E4!18!@baseboard_fab2_lib.baseboard_fab2(sch_1):page188_i27@mstr_sconn.sconn64_h87568002_a(chips)!SCONN64_H87568002_A_SMT-CONN,HA!!!F134!IO18!!!!
S!GND!J8E4!19!@baseboard_fab2_lib.baseboard_fab2(sch_1):page188_i27@mstr_sconn.sconn64_h87568002_a(chips)!SCONN64_H87568002_A_SMT-CONN,HA!!!F134!IO19!!!!
S!SMB_OCP_FRU_STBY_LVC3_SDA!J8E4!2!@baseboard_fab2_lib.baseboard_fab2(sch_1):page188_i27@mstr_sconn.sconn64_h87568002_a(chips)!SCONN64_H87568002_A_SMT-CONN,HA!!!F134!IO2!!!!
S!SMB_PCH_MEZZ_LOM0_SCL!J8E4!20!@baseboard_fab2_lib.baseboard_fab2(sch_1):page188_i27@mstr_sconn.sconn64_h87568002_a(chips)!SCONN64_H87568002_A_SMT-CONN,HA!!!F134!IO20!!!!
S!SMB_PCH_MEZZ_LOM0_SDA!J8E4!21!@baseboard_fab2_lib.baseboard_fab2(sch_1):page188_i27@mstr_sconn.sconn64_h87568002_a(chips)!SCONN64_H87568002_A_SMT-CONN,HA!!!F134!IO21!!!!
S!GND!J8E4!22!@baseboard_fab2_lib.baseboard_fab2(sch_1):page188_i27@mstr_sconn.sconn64_h87568002_a(chips)!SCONN64_H87568002_A_SMT-CONN,HA!!!F134!IO22!!!!
S!KR_P3_OCP_RX_DP!J8E4!23!@baseboard_fab2_lib.baseboard_fab2(sch_1):page188_i27@mstr_sconn.sconn64_h87568002_a(chips)!SCONN64_H87568002_A_SMT-CONN,HA!!!F134!IO23!!!!
S!KR_P3_OCP_RX_DN!J8E4!24!@baseboard_fab2_lib.baseboard_fab2(sch_1):page188_i27@mstr_sconn.sconn64_h87568002_a(chips)!SCONN64_H87568002_A_SMT-CONN,HA!!!F134!IO24!!!!
S!GND!J8E4!25!@baseboard_fab2_lib.baseboard_fab2(sch_1):page188_i27@mstr_sconn.sconn64_h87568002_a(chips)!SCONN64_H87568002_A_SMT-CONN,HA!!!F134!IO25!!!!
S!SMB_PCH_MEZZ_LOM1_SCL!J8E4!26!@baseboard_fab2_lib.baseboard_fab2(sch_1):page188_i27@mstr_sconn.sconn64_h87568002_a(chips)!SCONN64_H87568002_A_SMT-CONN,HA!!!F134!IO26!!!!
S!SMB_PCH_MEZZ_LOM1_SDA!J8E4!27!@baseboard_fab2_lib.baseboard_fab2(sch_1):page188_i27@mstr_sconn.sconn64_h87568002_a(chips)!SCONN64_H87568002_A_SMT-CONN,HA!!!F134!IO27!!!!
S!GND!J8E4!28!@baseboard_fab2_lib.baseboard_fab2(sch_1):page188_i27@mstr_sconn.sconn64_h87568002_a(chips)!SCONN64_H87568002_A_SMT-CONN,HA!!!F134!IO28!!!!
S!SMB_PCH_MEZZ_LOM3_SCL!J8E4!29!@baseboard_fab2_lib.baseboard_fab2(sch_1):page188_i27@mstr_sconn.sconn64_h87568002_a(chips)!SCONN64_H87568002_A_SMT-CONN,HA!!!F134!IO29!!!!
S!TP_EXT_MDIO_I2C_SEL!J8E4!3!@baseboard_fab2_lib.baseboard_fab2(sch_1):page188_i27@mstr_sconn.sconn64_h87568002_a(chips)!SCONN64_H87568002_A_SMT-CONN,HA!!!F134!IO3!!!!
S!SMB_PCH_MEZZ_LOM3_SDA!J8E4!30!@baseboard_fab2_lib.baseboard_fab2(sch_1):page188_i27@mstr_sconn.sconn64_h87568002_a(chips)!SCONN64_H87568002_A_SMT-CONN,HA!!!F134!IO30!!!!
S!FM_GBE2_LVC3_MOD_ABS!J8E4!31!@baseboard_fab2_lib.baseboard_fab2(sch_1):page188_i27@mstr_sconn.sconn64_h87568002_a(chips)!SCONN64_H87568002_A_SMT-CONN,HA!!!F134!IO31!!!!
S!FM_GBE3_LVC3_MOD_ABS!J8E4!32!@baseboard_fab2_lib.baseboard_fab2(sch_1):page188_i27@mstr_sconn.sconn64_h87568002_a(chips)!SCONN64_H87568002_A_SMT-CONN,HA!!!F134!IO32!!!!
S!P12V_STBY!J8E4!33!@baseboard_fab2_lib.baseboard_fab2(sch_1):page188_i27@mstr_sconn.sconn64_h87568002_a(chips)!SCONN64_H87568002_A_SMT-CONN,HA!!!F134!IO33!!!!
S!P12V_STBY!J8E4!34!@baseboard_fab2_lib.baseboard_fab2(sch_1):page188_i27@mstr_sconn.sconn64_h87568002_a(chips)!SCONN64_H87568002_A_SMT-CONN,HA!!!F134!IO34!!!!
S!P12V_STBY!J8E4!35!@baseboard_fab2_lib.baseboard_fab2(sch_1):page188_i27@mstr_sconn.sconn64_h87568002_a(chips)!SCONN64_H87568002_A_SMT-CONN,HA!!!F134!IO35!!!!
S!TP_RSVD<0>!J8E4!36!@baseboard_fab2_lib.baseboard_fab2(sch_1):page188_i27@mstr_sconn.sconn64_h87568002_a(chips)!SCONN64_H87568002_A_SMT-CONN,HA!!!F134!IO36!!!!
S!FM_GBE0_LVC3_MOD_ABS!J8E4!37!@baseboard_fab2_lib.baseboard_fab2(sch_1):page188_i27@mstr_sconn.sconn64_h87568002_a(chips)!SCONN64_H87568002_A_SMT-CONN,HA!!!F134!IO37!!!!
S!FM_GBE1_LVC3_MOD_ABS!J8E4!38!@baseboard_fab2_lib.baseboard_fab2(sch_1):page188_i27@mstr_sconn.sconn64_h87568002_a(chips)!SCONN64_H87568002_A_SMT-CONN,HA!!!F134!IO38!!!!
S!GND!J8E4!39!@baseboard_fab2_lib.baseboard_fab2(sch_1):page188_i27@mstr_sconn.sconn64_h87568002_a(chips)!SCONN64_H87568002_A_SMT-CONN,HA!!!F134!IO39!!!!
S!GND!J8E4!4!@baseboard_fab2_lib.baseboard_fab2(sch_1):page188_i27@mstr_sconn.sconn64_h87568002_a(chips)!SCONN64_H87568002_A_SMT-CONN,HA!!!F134!IO4!!!!
S!KR_P0_OCP_TX_DP!J8E4!40!@baseboard_fab2_lib.baseboard_fab2(sch_1):page188_i27@mstr_sconn.sconn64_h87568002_a(chips)!SCONN64_H87568002_A_SMT-CONN,HA!!!F134!IO40!!!!
S!KR_P0_OCP_TX_DN!J8E4!41!@baseboard_fab2_lib.baseboard_fab2(sch_1):page188_i27@mstr_sconn.sconn64_h87568002_a(chips)!SCONN64_H87568002_A_SMT-CONN,HA!!!F134!IO41!!!!
S!GND!J8E4!42!@baseboard_fab2_lib.baseboard_fab2(sch_1):page188_i27@mstr_sconn.sconn64_h87568002_a(chips)!SCONN64_H87568002_A_SMT-CONN,HA!!!F134!IO42!!!!
S!LED_GBE_P0_0!J8E4!43!@baseboard_fab2_lib.baseboard_fab2(sch_1):page188_i27@mstr_sconn.sconn64_h87568002_a(chips)!SCONN64_H87568002_A_SMT-CONN,HA!!!F134!IO43!!!!
S!LED_GBE_P0_1!J8E4!44!@baseboard_fab2_lib.baseboard_fab2(sch_1):page188_i27@mstr_sconn.sconn64_h87568002_a(chips)!SCONN64_H87568002_A_SMT-CONN,HA!!!F134!IO44!!!!
S!GND!J8E4!45!@baseboard_fab2_lib.baseboard_fab2(sch_1):page188_i27@mstr_sconn.sconn64_h87568002_a(chips)!SCONN64_H87568002_A_SMT-CONN,HA!!!F134!IO45!!!!
S!KR_P1_OCP_TX_DP!J8E4!46!@baseboard_fab2_lib.baseboard_fab2(sch_1):page188_i27@mstr_sconn.sconn64_h87568002_a(chips)!SCONN64_H87568002_A_SMT-CONN,HA!!!F134!IO46!!!!
S!KR_P1_OCP_TX_DN!J8E4!47!@baseboard_fab2_lib.baseboard_fab2(sch_1):page188_i27@mstr_sconn.sconn64_h87568002_a(chips)!SCONN64_H87568002_A_SMT-CONN,HA!!!F134!IO47!!!!
S!GND!J8E4!48!@baseboard_fab2_lib.baseboard_fab2(sch_1):page188_i27@mstr_sconn.sconn64_h87568002_a(chips)!SCONN64_H87568002_A_SMT-CONN,HA!!!F134!IO48!!!!
S!TP_SHARED_KR_MDC_0!J8E4!49!@baseboard_fab2_lib.baseboard_fab2(sch_1):page188_i27@mstr_sconn.sconn64_h87568002_a(chips)!SCONN64_H87568002_A_SMT-CONN,HA!!!F134!IO49!!!!
S!KR_P2_OCP_TX_DP!J8E4!5!@baseboard_fab2_lib.baseboard_fab2(sch_1):page188_i27@mstr_sconn.sconn64_h87568002_a(chips)!SCONN64_H87568002_A_SMT-CONN,HA!!!F134!IO5!!!!
S!TP_SHARED_KR_MDIO_0!J8E4!50!@baseboard_fab2_lib.baseboard_fab2(sch_1):page188_i27@mstr_sconn.sconn64_h87568002_a(chips)!SCONN64_H87568002_A_SMT-CONN,HA!!!F134!IO50!!!!
S!GND!J8E4!51!@baseboard_fab2_lib.baseboard_fab2(sch_1):page188_i27@mstr_sconn.sconn64_h87568002_a(chips)!SCONN64_H87568002_A_SMT-CONN,HA!!!F134!IO51!!!!
S!KR_P0_OCP_RX_DP!J8E4!52!@baseboard_fab2_lib.baseboard_fab2(sch_1):page188_i27@mstr_sconn.sconn64_h87568002_a(chips)!SCONN64_H87568002_A_SMT-CONN,HA!!!F134!IO52!!!!
S!KR_P0_OCP_RX_DN!J8E4!53!@baseboard_fab2_lib.baseboard_fab2(sch_1):page188_i27@mstr_sconn.sconn64_h87568002_a(chips)!SCONN64_H87568002_A_SMT-CONN,HA!!!F134!IO53!!!!
S!GND!J8E4!54!@baseboard_fab2_lib.baseboard_fab2(sch_1):page188_i27@mstr_sconn.sconn64_h87568002_a(chips)!SCONN64_H87568002_A_SMT-CONN,HA!!!F134!IO54!!!!
S!LED_GBE_P3_0!J8E4!55!@baseboard_fab2_lib.baseboard_fab2(sch_1):page188_i27@mstr_sconn.sconn64_h87568002_a(chips)!SCONN64_H87568002_A_SMT-CONN,HA!!!F134!IO55!!!!
S!LED_GBE_P3_1!J8E4!56!@baseboard_fab2_lib.baseboard_fab2(sch_1):page188_i27@mstr_sconn.sconn64_h87568002_a(chips)!SCONN64_H87568002_A_SMT-CONN,HA!!!F134!IO56!!!!
S!GND!J8E4!57!@baseboard_fab2_lib.baseboard_fab2(sch_1):page188_i27@mstr_sconn.sconn64_h87568002_a(chips)!SCONN64_H87568002_A_SMT-CONN,HA!!!F134!IO57!!!!
S!KR_P1_OCP_RX_DP!J8E4!58!@baseboard_fab2_lib.baseboard_fab2(sch_1):page188_i27@mstr_sconn.sconn64_h87568002_a(chips)!SCONN64_H87568002_A_SMT-CONN,HA!!!F134!IO58!!!!
S!KR_P1_OCP_RX_DN!J8E4!59!@baseboard_fab2_lib.baseboard_fab2(sch_1):page188_i27@mstr_sconn.sconn64_h87568002_a(chips)!SCONN64_H87568002_A_SMT-CONN,HA!!!F134!IO59!!!!
S!KR_P2_OCP_TX_DN!J8E4!6!@baseboard_fab2_lib.baseboard_fab2(sch_1):page188_i27@mstr_sconn.sconn64_h87568002_a(chips)!SCONN64_H87568002_A_SMT-CONN,HA!!!F134!IO6!!!!
S!GND!J8E4!60!@baseboard_fab2_lib.baseboard_fab2(sch_1):page188_i27@mstr_sconn.sconn64_h87568002_a(chips)!SCONN64_H87568002_A_SMT-CONN,HA!!!F134!IO60!!!!
S!SMB_PCH_MEZZ_LOM2_SCL!J8E4!61!@baseboard_fab2_lib.baseboard_fab2(sch_1):page188_i27@mstr_sconn.sconn64_h87568002_a(chips)!SCONN64_H87568002_A_SMT-CONN,HA!!!F134!IO61!!!!
S!SMB_PCH_MEZZ_LOM2_SDA!J8E4!62!@baseboard_fab2_lib.baseboard_fab2(sch_1):page188_i27@mstr_sconn.sconn64_h87568002_a(chips)!SCONN64_H87568002_A_SMT-CONN,HA!!!F134!IO62!!!!
S!GND!J8E4!63!@baseboard_fab2_lib.baseboard_fab2(sch_1):page188_i27@mstr_sconn.sconn64_h87568002_a(chips)!SCONN64_H87568002_A_SMT-CONN,HA!!!F134!IO63!!!!
S!FM_OCP_MEZZC_PRES_N!J8E4!64!@baseboard_fab2_lib.baseboard_fab2(sch_1):page188_i27@mstr_sconn.sconn64_h87568002_a(chips)!SCONN64_H87568002_A_SMT-CONN,HA!!!F134!IO64!!!!
S!GND!J8E4!7!@baseboard_fab2_lib.baseboard_fab2(sch_1):page188_i27@mstr_sconn.sconn64_h87568002_a(chips)!SCONN64_H87568002_A_SMT-CONN,HA!!!F134!IO7!!!!
S!LED_GBE_P1_0!J8E4!8!@baseboard_fab2_lib.baseboard_fab2(sch_1):page188_i27@mstr_sconn.sconn64_h87568002_a(chips)!SCONN64_H87568002_A_SMT-CONN,HA!!!F134!IO8!!!!
S!LED_GBE_P1_1!J8E4!9!@baseboard_fab2_lib.baseboard_fab2(sch_1):page188_i27@mstr_sconn.sconn64_h87568002_a(chips)!SCONN64_H87568002_A_SMT-CONN,HA!!!F134!IO9!!!!
S!P5V_USB!C9B8!1!@baseboard_fab2_lib.baseboard_fab2(sch_1):page176_i113@mstr_discrete.capp(chips)!CAPP_7343HLF-330UF,10V,20%,POSA!!!F4103!A!!!!
S!GND!C9B8!2!@baseboard_fab2_lib.baseboard_fab2(sch_1):page176_i113@mstr_discrete.capp(chips)!CAPP_7343HLF-330UF,10V,20%,POSA!!!F4103!B!!!!
S!P12V_STBY!Q1B1!5!@baseboard_fab2_lib.baseboard_fab2(sch_1):page198_i86@mstr_discrete.mosfet_n(chips)!MOSFET_N_LCC3-BSZ019N03LS,NFETA!!!F2017!DRN!!!!
S!P12V_FAN_SWITCH_G!Q1B1!4!@baseboard_fab2_lib.baseboard_fab2(sch_1):page198_i86@mstr_discrete.mosfet_n(chips)!MOSFET_N_LCC3-BSZ019N03LS,NFETA!!!F2017!GATE!!!!
S!P12V_FAN!Q1B1!1!@baseboard_fab2_lib.baseboard_fab2(sch_1):page198_i86@mstr_discrete.mosfet_n(chips)!MOSFET_N_LCC3-BSZ019N03LS,NFETA!!!F2017!SRC!!!!
S!P12V_STBY!Q7E7!5!@baseboard_fab2_lib.baseboard_fab2(sch_1):page198_i88@mstr_discrete.mosfet_n(chips)!MOSFET_N_LCC3-BSZ019N03LS,NFETA!!!F2016!DRN!!!!
S!P12V_SWITCH_G!Q7E7!4!@baseboard_fab2_lib.baseboard_fab2(sch_1):page198_i88@mstr_discrete.mosfet_n(chips)!MOSFET_N_LCC3-BSZ019N03LS,NFETA!!!F2016!GATE!!!!
S!P12V!Q7E7!1!@baseboard_fab2_lib.baseboard_fab2(sch_1):page198_i88@mstr_discrete.mosfet_n(chips)!MOSFET_N_LCC3-BSZ019N03LS,NFETA!!!F2016!SRC!!!!
S!P5V_STBY!Q8B1!5!@baseboard_fab2_lib.baseboard_fab2(sch_1):page198_i87@mstr_discrete.mosfet_n(chips)!MOSFET_N_LCC3-BSZ019N03LS,NFETA!!!F2015!DRN!!!!
S!P5V_SWITCH_G!Q8B1!4!@baseboard_fab2_lib.baseboard_fab2(sch_1):page198_i87@mstr_discrete.mosfet_n(chips)!MOSFET_N_LCC3-BSZ019N03LS,NFETA!!!F2015!GATE!!!!
S!P5V!Q8B1!1!@baseboard_fab2_lib.baseboard_fab2(sch_1):page198_i87@mstr_discrete.mosfet_n(chips)!MOSFET_N_LCC3-BSZ019N03LS,NFETA!!!F2015!SRC!!!!
S!P3V3_STBY!Q8G1!5!@baseboard_fab2_lib.baseboard_fab2(sch_1):page198_i85@mstr_discrete.mosfet_n(chips)!MOSFET_N_LCC3-BSZ019N03LS,NFETA!!!F2014!DRN!!!!
S!P3V3_SWITCH_G!Q8G1!4!@baseboard_fab2_lib.baseboard_fab2(sch_1):page198_i85@mstr_discrete.mosfet_n(chips)!MOSFET_N_LCC3-BSZ019N03LS,NFETA!!!F2014!GATE!!!!
S!P3V3!Q8G1!1!@baseboard_fab2_lib.baseboard_fab2(sch_1):page198_i85@mstr_discrete.mosfet_n(chips)!MOSFET_N_LCC3-BSZ019N03LS,NFETA!!!F2014!SRC!!!!
S!PECI_CPU_G!R7D15!1!@baseboard_fab2_lib.baseboard_fab2(sch_1):page166_i32@mstr_discrete.res(chips)!RES_0402-348,1%,1/16W,CHIP,G21A!!!F660!A!!!!
S!GND!R7D15!2!@baseboard_fab2_lib.baseboard_fab2(sch_1):page166_i32@mstr_discrete.res(chips)!RES_0402-348,1%,1/16W,CHIP,G21A!!!F660!B!!!!
S!P3E_CPU0_PE1_SS_TXP<0>!C3P10!1!@baseboard_fab2_lib.baseboard_fab2(sch_1):page107_i417@mstr_discrete.cap(chips)!CAP_0402-0.22UF,16V,10%,EMPTY,A!!!F4052!A!!!!
S!P3E_CPU0_PE1_SS_C_TXP<0>!C3P10!2!@baseboard_fab2_lib.baseboard_fab2(sch_1):page107_i417@mstr_discrete.cap(chips)!CAP_0402-0.22UF,16V,10%,EMPTY,A!!!F4052!B!!!!
S!P3E_CPU0_PE1_SS_TXN<0>!C3P12!1!@baseboard_fab2_lib.baseboard_fab2(sch_1):page107_i415@mstr_discrete.cap(chips)!CAP_0402-0.22UF,16V,10%,EMPTY,A!!!F4051!A!!!!
S!P3E_CPU0_PE1_SS_C_TXN<0>!C3P12!2!@baseboard_fab2_lib.baseboard_fab2(sch_1):page107_i415@mstr_discrete.cap(chips)!CAP_0402-0.22UF,16V,10%,EMPTY,A!!!F4051!B!!!!
S!P3E_CPU0_PE1_SS_TXP<1>!C3P14!1!@baseboard_fab2_lib.baseboard_fab2(sch_1):page107_i431@mstr_discrete.cap(chips)!CAP_0402-0.22UF,16V,10%,EMPTY,A!!!F4050!A!!!!
S!P3E_CPU0_PE1_SS_C_TXP<1>!C3P14!2!@baseboard_fab2_lib.baseboard_fab2(sch_1):page107_i431@mstr_discrete.cap(chips)!CAP_0402-0.22UF,16V,10%,EMPTY,A!!!F4050!B!!!!
S!P3E_CPU0_PE1_SS_TXN<1>!C3P16!1!@baseboard_fab2_lib.baseboard_fab2(sch_1):page107_i422@mstr_discrete.cap(chips)!CAP_0402-0.22UF,16V,10%,EMPTY,A!!!F4049!A!!!!
S!P3E_CPU0_PE1_SS_C_TXN<1>!C3P16!2!@baseboard_fab2_lib.baseboard_fab2(sch_1):page107_i422@mstr_discrete.cap(chips)!CAP_0402-0.22UF,16V,10%,EMPTY,A!!!F4049!B!!!!
S!P3E_CPU0_PE1_SS_TXP<2>!C3P19!1!@baseboard_fab2_lib.baseboard_fab2(sch_1):page107_i427@mstr_discrete.cap(chips)!CAP_0402-0.22UF,16V,10%,EMPTY,A!!!F4048!A!!!!
S!P3E_CPU0_PE1_SS_C_TXP<2>!C3P19!2!@baseboard_fab2_lib.baseboard_fab2(sch_1):page107_i427@mstr_discrete.cap(chips)!CAP_0402-0.22UF,16V,10%,EMPTY,A!!!F4048!B!!!!
S!P3E_CPU0_PE1_SS_TXN<2>!C3P21!1!@baseboard_fab2_lib.baseboard_fab2(sch_1):page107_i423@mstr_discrete.cap(chips)!CAP_0402-0.22UF,16V,10%,EMPTY,A!!!F4047!A!!!!
S!P3E_CPU0_PE1_SS_C_TXN<2>!C3P21!2!@baseboard_fab2_lib.baseboard_fab2(sch_1):page107_i423@mstr_discrete.cap(chips)!CAP_0402-0.22UF,16V,10%,EMPTY,A!!!F4047!B!!!!
S!P3E_CPU0_PE1_SS_TXP<3>!C3P22!1!@baseboard_fab2_lib.baseboard_fab2(sch_1):page107_i435@mstr_discrete.cap(chips)!CAP_0402-0.22UF,16V,10%,EMPTY,A!!!F4046!A!!!!
S!P3E_CPU0_PE1_SS_C_TXP<3>!C3P22!2!@baseboard_fab2_lib.baseboard_fab2(sch_1):page107_i435@mstr_discrete.cap(chips)!CAP_0402-0.22UF,16V,10%,EMPTY,A!!!F4046!B!!!!
S!P3E_CPU0_PE1_SS_TXN<3>!C3P24!1!@baseboard_fab2_lib.baseboard_fab2(sch_1):page107_i424@mstr_discrete.cap(chips)!CAP_0402-0.22UF,16V,10%,EMPTY,A!!!F4045!A!!!!
S!P3E_CPU0_PE1_SS_C_TXN<3>!C3P24!2!@baseboard_fab2_lib.baseboard_fab2(sch_1):page107_i424@mstr_discrete.cap(chips)!CAP_0402-0.22UF,16V,10%,EMPTY,A!!!F4045!B!!!!
S!P3E_CPU0_PE1_SS_TXP<4>!C3P26!1!@baseboard_fab2_lib.baseboard_fab2(sch_1):page107_i444@mstr_discrete.cap(chips)!CAP_0402-0.22UF,16V,10%,EMPTY,A!!!F4044!A!!!!
S!P3E_CPU0_PE1_SS_C_TXP<4>!C3P26!2!@baseboard_fab2_lib.baseboard_fab2(sch_1):page107_i444@mstr_discrete.cap(chips)!CAP_0402-0.22UF,16V,10%,EMPTY,A!!!F4044!B!!!!
S!P3E_CPU0_PE1_SS_TXN<4>!C3P29!1!@baseboard_fab2_lib.baseboard_fab2(sch_1):page107_i437@mstr_discrete.cap(chips)!CAP_0402-0.22UF,16V,10%,EMPTY,A!!!F4043!A!!!!
S!P3E_CPU0_PE1_SS_C_TXN<4>!C3P29!2!@baseboard_fab2_lib.baseboard_fab2(sch_1):page107_i437@mstr_discrete.cap(chips)!CAP_0402-0.22UF,16V,10%,EMPTY,A!!!F4043!B!!!!
S!P3E_CPU0_PE1_SS_TXP<5>!C3P31!1!@baseboard_fab2_lib.baseboard_fab2(sch_1):page107_i452@mstr_discrete.cap(chips)!CAP_0402-0.22UF,16V,10%,EMPTY,A!!!F4042!A!!!!
S!P3E_CPU0_PE1_SS_C_TXP<5>!C3P31!2!@baseboard_fab2_lib.baseboard_fab2(sch_1):page107_i452@mstr_discrete.cap(chips)!CAP_0402-0.22UF,16V,10%,EMPTY,A!!!F4042!B!!!!
S!P3E_CPU0_PE1_SS_TXN<5>!C3P33!1!@baseboard_fab2_lib.baseboard_fab2(sch_1):page107_i439@mstr_discrete.cap(chips)!CAP_0402-0.22UF,16V,10%,EMPTY,A!!!F4041!A!!!!
S!P3E_CPU0_PE1_SS_C_TXN<5>!C3P33!2!@baseboard_fab2_lib.baseboard_fab2(sch_1):page107_i439@mstr_discrete.cap(chips)!CAP_0402-0.22UF,16V,10%,EMPTY,A!!!F4041!B!!!!
S!P3E_CPU0_PE1_SS_TXP<6>!C3P34!1!@baseboard_fab2_lib.baseboard_fab2(sch_1):page107_i447@mstr_discrete.cap(chips)!CAP_0402-0.22UF,16V,10%,EMPTY,A!!!F4040!A!!!!
S!P3E_CPU0_PE1_SS_C_TXP<6>!C3P34!2!@baseboard_fab2_lib.baseboard_fab2(sch_1):page107_i447@mstr_discrete.cap(chips)!CAP_0402-0.22UF,16V,10%,EMPTY,A!!!F4040!B!!!!
S!P3E_CPU0_PE1_SS_TXN<6>!C3P36!1!@baseboard_fab2_lib.baseboard_fab2(sch_1):page107_i438@mstr_discrete.cap(chips)!CAP_0402-0.22UF,16V,10%,EMPTY,A!!!F4039!A!!!!
S!P3E_CPU0_PE1_SS_C_TXN<6>!C3P36!2!@baseboard_fab2_lib.baseboard_fab2(sch_1):page107_i438@mstr_discrete.cap(chips)!CAP_0402-0.22UF,16V,10%,EMPTY,A!!!F4039!B!!!!
S!P3E_CPU0_PE1_SS_TXP<7>!C3P38!1!@baseboard_fab2_lib.baseboard_fab2(sch_1):page107_i455@mstr_discrete.cap(chips)!CAP_0402-0.22UF,16V,10%,EMPTY,A!!!F4038!A!!!!
S!P3E_CPU0_PE1_SS_C_TXP<7>!C3P38!2!@baseboard_fab2_lib.baseboard_fab2(sch_1):page107_i455@mstr_discrete.cap(chips)!CAP_0402-0.22UF,16V,10%,EMPTY,A!!!F4038!B!!!!
S!P3E_CPU0_PE1_SS_TXN<7>!C3P41!1!@baseboard_fab2_lib.baseboard_fab2(sch_1):page107_i448@mstr_discrete.cap(chips)!CAP_0402-0.22UF,16V,10%,EMPTY,A!!!F4037!A!!!!
S!P3E_CPU0_PE1_SS_C_TXN<7>!C3P41!2!@baseboard_fab2_lib.baseboard_fab2(sch_1):page107_i448@mstr_discrete.cap(chips)!CAP_0402-0.22UF,16V,10%,EMPTY,A!!!F4037!B!!!!
S!GND!J1B2!1!@baseboard_fab2_lib.baseboard_fab2(sch_1):page161_i32@mstr_conn.conn6_c74770005(chips)!CONN6_C74770005_PIP-HDR,C74770A!!!F2242!IO1!!!!
S!P12V_FAN!J1B2!2!@baseboard_fab2_lib.baseboard_fab2(sch_1):page161_i32@mstr_conn.conn6_c74770005(chips)!CONN6_C74770005_PIP-HDR,C74770A!!!F2242!IO2!!!!
S!FAN_TACH2_CPU1_D1!J1B2!3!@baseboard_fab2_lib.baseboard_fab2(sch_1):page161_i32@mstr_conn.conn6_c74770005(chips)!CONN6_C74770005_PIP-HDR,C74770A!!!F2242!IO3!!!!
S!FAN_PWM_OUT_SYS1_R!J1B2!4!@baseboard_fab2_lib.baseboard_fab2(sch_1):page161_i32@mstr_conn.conn6_c74770005(chips)!CONN6_C74770005_PIP-HDR,C74770A!!!F2242!IO4!!!!
S!FAN_TACH3_CPU1_D1!J1B2!5!@baseboard_fab2_lib.baseboard_fab2(sch_1):page161_i32@mstr_conn.conn6_c74770005(chips)!CONN6_C74770005_PIP-HDR,C74770A!!!F2242!IO5!!!!
S!TP_FAN_1!J1B2!6!@baseboard_fab2_lib.baseboard_fab2(sch_1):page161_i32@mstr_conn.conn6_c74770005(chips)!CONN6_C74770005_PIP-HDR,C74770A!!!F2242!IO6!!!!
S!GND!J1F2!1!@baseboard_fab2_lib.baseboard_fab2(sch_1):page161_i1@mstr_conn.conn6_c74770005(chips)!CONN6_C74770005_PIP-HDR,C74770A!!!F2241!IO1!!!!
S!P12V_FAN!J1F2!2!@baseboard_fab2_lib.baseboard_fab2(sch_1):page161_i1@mstr_conn.conn6_c74770005(chips)!CONN6_C74770005_PIP-HDR,C74770A!!!F2241!IO2!!!!
S!FAN_TACH0_CPU0_D1!J1F2!3!@baseboard_fab2_lib.baseboard_fab2(sch_1):page161_i1@mstr_conn.conn6_c74770005(chips)!CONN6_C74770005_PIP-HDR,C74770A!!!F2241!IO3!!!!
S!FAN_PWM_OUT_SYS0_R!J1F2!4!@baseboard_fab2_lib.baseboard_fab2(sch_1):page161_i1@mstr_conn.conn6_c74770005(chips)!CONN6_C74770005_PIP-HDR,C74770A!!!F2241!IO4!!!!
S!FAN_TACH1_CPU1_D1!J1F2!5!@baseboard_fab2_lib.baseboard_fab2(sch_1):page161_i1@mstr_conn.conn6_c74770005(chips)!CONN6_C74770005_PIP-HDR,C74770A!!!F2241!IO5!!!!
S!TP_FAN_0!J1F2!6!@baseboard_fab2_lib.baseboard_fab2(sch_1):page161_i1@mstr_conn.conn6_c74770005(chips)!CONN6_C74770005_PIP-HDR,C74770A!!!F2241!IO6!!!!
S!CLK_100M_PCH_XDP_DN!U7C1!A39!@baseboard_fab2_lib.baseboard_fab2(sch_1):page114_i40@chpset_lib.lbg_core_qat_ext_c(chips)!LBG_CORE_QAT_EXT_C_BGA1-IC,TBD!!!F2055!CLKOUT_ITPXDPN!!!!
S!CLK_100M_PCH_XDP_DP!U7C1!C39!@baseboard_fab2_lib.baseboard_fab2(sch_1):page114_i40@chpset_lib.lbg_core_qat_ext_c(chips)!LBG_CORE_QAT_EXT_C_BGA1-IC,TBD!!!F2055!CLKOUT_ITPXDPP!!!!
S!TP_CLK_100M_NSSCC0_DN!U7C1!A32!@baseboard_fab2_lib.baseboard_fab2(sch_1):page114_i40@chpset_lib.lbg_core_qat_ext_c(chips)!LBG_CORE_QAT_EXT_C_BGA1-IC,TBD!!!F2055!CLKOUT_NSSCCAP0N!!!!
S!TP_CLK_100M_NSSCC0_DP!U7C1!C32!@baseboard_fab2_lib.baseboard_fab2(sch_1):page114_i40@chpset_lib.lbg_core_qat_ext_c(chips)!LBG_CORE_QAT_EXT_C_BGA1-IC,TBD!!!F2055!CLKOUT_NSSCCAP0P!!!!
S!TP_CLK_100M_NSSCC1_DN!U7C1!B38!@baseboard_fab2_lib.baseboard_fab2(sch_1):page114_i40@chpset_lib.lbg_core_qat_ext_c(chips)!LBG_CORE_QAT_EXT_C_BGA1-IC,TBD!!!F2055!CLKOUT_NSSCCAP1N!!!!
S!TP_CLK_100M_NSSCC1_DP!U7C1!D38!@baseboard_fab2_lib.baseboard_fab2(sch_1):page114_i40@chpset_lib.lbg_core_qat_ext_c(chips)!LBG_CORE_QAT_EXT_C_BGA1-IC,TBD!!!F2055!CLKOUT_NSSCCAP1P!!!!
S!CLK_100M_BMC_PE_DN!U7C1!B29!@baseboard_fab2_lib.baseboard_fab2(sch_1):page114_i40@chpset_lib.lbg_core_qat_ext_c(chips)!LBG_CORE_QAT_EXT_C_BGA1-IC,TBD!!!F2055!CLKOUT_PLAT0N!!!!
S!CLK_100M_BMC_PE_DP!U7C1!D29!@baseboard_fab2_lib.baseboard_fab2(sch_1):page114_i40@chpset_lib.lbg_core_qat_ext_c(chips)!LBG_CORE_QAT_EXT_C_BGA1-IC,TBD!!!F2055!CLKOUT_PLAT0P!!!!
S!TP_CLK_100M_PLAT1_DN!U7C1!B40!@baseboard_fab2_lib.baseboard_fab2(sch_1):page114_i40@chpset_lib.lbg_core_qat_ext_c(chips)!LBG_CORE_QAT_EXT_C_BGA1-IC,TBD!!!F2055!CLKOUT_PLAT1N!!!!
S!TP_CLK_100M_PLAT1_DP!U7C1!D40!@baseboard_fab2_lib.baseboard_fab2(sch_1):page114_i40@chpset_lib.lbg_core_qat_ext_c(chips)!LBG_CORE_QAT_EXT_C_BGA1-IC,TBD!!!F2055!CLKOUT_PLAT1P!!!!
S!CLK_100M_AIRMAX8_PE1_DN!U7C1!K38!@baseboard_fab2_lib.baseboard_fab2(sch_1):page114_i40@chpset_lib.lbg_core_qat_ext_c(chips)!LBG_CORE_QAT_EXT_C_BGA1-IC,TBD!!!F2055!CLKOUT_SRCN(0)!!!!
S!CLK_100M_MEZZ3_DN!U7C1!B23!@baseboard_fab2_lib.baseboard_fab2(sch_1):page114_i40@chpset_lib.lbg_core_qat_ext_c(chips)!LBG_CORE_QAT_EXT_C_BGA1-IC,TBD!!!F2055!CLKOUT_SRCN(10)!!!!
S!CLK_100M_MEZZ4_DN!U7C1!B21!@baseboard_fab2_lib.baseboard_fab2(sch_1):page114_i40@chpset_lib.lbg_core_qat_ext_c(chips)!LBG_CORE_QAT_EXT_C_BGA1-IC,TBD!!!F2055!CLKOUT_SRCN(11)!!!!
S!TP_CLK_100M_SRC12_DN!U7C1!K24!@baseboard_fab2_lib.baseboard_fab2(sch_1):page114_i40@chpset_lib.lbg_core_qat_ext_c(chips)!LBG_CORE_QAT_EXT_C_BGA1-IC,TBD!!!F2055!CLKOUT_SRCN(12)!!!!
S!TP_CLK_100M_SRC13_DN!U7C1!C24!@baseboard_fab2_lib.baseboard_fab2(sch_1):page114_i40@chpset_lib.lbg_core_qat_ext_c(chips)!LBG_CORE_QAT_EXT_C_BGA1-IC,TBD!!!F2055!CLKOUT_SRCN(13)!!!!
S!CLK_100M_SPRV_DN!U7C1!C20!@baseboard_fab2_lib.baseboard_fab2(sch_1):page114_i40@chpset_lib.lbg_core_qat_ext_c(chips)!LBG_CORE_QAT_EXT_C_BGA1-IC,TBD!!!F2055!CLKOUT_SRCN(14)!!!!
S!CLK_100M_M2_DN!U7C1!K27!@baseboard_fab2_lib.baseboard_fab2(sch_1):page114_i40@chpset_lib.lbg_core_qat_ext_c(chips)!LBG_CORE_QAT_EXT_C_BGA1-IC,TBD!!!F2055!CLKOUT_SRCN(15)!!!!
S!CLK_100M_DB1200_DN!U7C1!K35!@baseboard_fab2_lib.baseboard_fab2(sch_1):page114_i40@chpset_lib.lbg_core_qat_ext_c(chips)!LBG_CORE_QAT_EXT_C_BGA1-IC,TBD!!!F2055!CLKOUT_SRCN(1)!!!!
S!CLK_100M_PCH_SLOTX24_S0_DN!U7C1!J33!@baseboard_fab2_lib.baseboard_fab2(sch_1):page114_i40@chpset_lib.lbg_core_qat_ext_c(chips)!LBG_CORE_QAT_EXT_C_BGA1-IC,TBD!!!F2055!CLKOUT_SRCN(2)!!!!
S!CLK_100M_PCH_SLOTX24_S1_DN!U7C1!K42!@baseboard_fab2_lib.baseboard_fab2(sch_1):page114_i40@chpset_lib.lbg_core_qat_ext_c(chips)!LBG_CORE_QAT_EXT_C_BGA1-IC,TBD!!!F2055!CLKOUT_SRCN(3)!!!!
S!CLK_100M_PCH_SLOTX24_S2_DN!U7C1!A28!@baseboard_fab2_lib.baseboard_fab2(sch_1):page114_i40@chpset_lib.lbg_core_qat_ext_c(chips)!LBG_CORE_QAT_EXT_C_BGA1-IC,TBD!!!F2055!CLKOUT_SRCN(4)!!!!
S!CLK_100M_PCH_SLOTX24_S3_DN!U7C1!J40!@baseboard_fab2_lib.baseboard_fab2(sch_1):page114_i40@chpset_lib.lbg_core_qat_ext_c(chips)!LBG_CORE_QAT_EXT_C_BGA1-IC,TBD!!!F2055!CLKOUT_SRCN(5)!!!!
S!CLK_100M_PCH_SLOTX24_S4_DN!U7C1!D33!@baseboard_fab2_lib.baseboard_fab2(sch_1):page114_i40@chpset_lib.lbg_core_qat_ext_c(chips)!LBG_CORE_QAT_EXT_C_BGA1-IC,TBD!!!F2055!CLKOUT_SRCN(6)!!!!
S!CLK_100M_PCH_SLOTX24_S5_DN!U7C1!H31!@baseboard_fab2_lib.baseboard_fab2(sch_1):page114_i40@chpset_lib.lbg_core_qat_ext_c(chips)!LBG_CORE_QAT_EXT_C_BGA1-IC,TBD!!!F2055!CLKOUT_SRCN(7)!!!!
S!CLK_100M_MEZZ1_DN!U7C1!D31!@baseboard_fab2_lib.baseboard_fab2(sch_1):page114_i40@chpset_lib.lbg_core_qat_ext_c(chips)!LBG_CORE_QAT_EXT_C_BGA1-IC,TBD!!!F2055!CLKOUT_SRCN(8)!!!!
S!CLK_100M_MEZZ2_DN!U7C1!J26!@baseboard_fab2_lib.baseboard_fab2(sch_1):page114_i40@chpset_lib.lbg_core_qat_ext_c(chips)!LBG_CORE_QAT_EXT_C_BGA1-IC,TBD!!!F2055!CLKOUT_SRCN(9)!!!!
S!CLK_100M_AIRMAX8_PE1_DP!U7C1!H38!@baseboard_fab2_lib.baseboard_fab2(sch_1):page114_i40@chpset_lib.lbg_core_qat_ext_c(chips)!LBG_CORE_QAT_EXT_C_BGA1-IC,TBD!!!F2055!CLKOUT_SRCP(0)!!!!
S!CLK_100M_MEZZ3_DP!U7C1!D23!@baseboard_fab2_lib.baseboard_fab2(sch_1):page114_i40@chpset_lib.lbg_core_qat_ext_c(chips)!LBG_CORE_QAT_EXT_C_BGA1-IC,TBD!!!F2055!CLKOUT_SRCP(10)!!!!
S!CLK_100M_MEZZ4_DP!U7C1!D21!@baseboard_fab2_lib.baseboard_fab2(sch_1):page114_i40@chpset_lib.lbg_core_qat_ext_c(chips)!LBG_CORE_QAT_EXT_C_BGA1-IC,TBD!!!F2055!CLKOUT_SRCP(11)!!!!
S!TP_CLK_100M_SRC12_DP!U7C1!H24!@baseboard_fab2_lib.baseboard_fab2(sch_1):page114_i40@chpset_lib.lbg_core_qat_ext_c(chips)!LBG_CORE_QAT_EXT_C_BGA1-IC,TBD!!!F2055!CLKOUT_SRCP(12)!!!!
S!TP_CLK_100M_SRC13_DP!U7C1!A24!@baseboard_fab2_lib.baseboard_fab2(sch_1):page114_i40@chpset_lib.lbg_core_qat_ext_c(chips)!LBG_CORE_QAT_EXT_C_BGA1-IC,TBD!!!F2055!CLKOUT_SRCP(13)!!!!
S!CLK_100M_SPRV_DP!U7C1!A20!@baseboard_fab2_lib.baseboard_fab2(sch_1):page114_i40@chpset_lib.lbg_core_qat_ext_c(chips)!LBG_CORE_QAT_EXT_C_BGA1-IC,TBD!!!F2055!CLKOUT_SRCP(14)!!!!
S!CLK_100M_M2_DP!U7C1!H27!@baseboard_fab2_lib.baseboard_fab2(sch_1):page114_i40@chpset_lib.lbg_core_qat_ext_c(chips)!LBG_CORE_QAT_EXT_C_BGA1-IC,TBD!!!F2055!CLKOUT_SRCP(15)!!!!
S!CLK_100M_DB1200_DP!U7C1!H35!@baseboard_fab2_lib.baseboard_fab2(sch_1):page114_i40@chpset_lib.lbg_core_qat_ext_c(chips)!LBG_CORE_QAT_EXT_C_BGA1-IC,TBD!!!F2055!CLKOUT_SRCP(1)!!!!
S!CLK_100M_PCH_SLOTX24_S0_DP!U7C1!G33!@baseboard_fab2_lib.baseboard_fab2(sch_1):page114_i40@chpset_lib.lbg_core_qat_ext_c(chips)!LBG_CORE_QAT_EXT_C_BGA1-IC,TBD!!!F2055!CLKOUT_SRCP(2)!!!!
S!CLK_100M_PCH_SLOTX24_S1_DP!U7C1!H42!@baseboard_fab2_lib.baseboard_fab2(sch_1):page114_i40@chpset_lib.lbg_core_qat_ext_c(chips)!LBG_CORE_QAT_EXT_C_BGA1-IC,TBD!!!F2055!CLKOUT_SRCP(3)!!!!
S!CLK_100M_PCH_SLOTX24_S2_DP!U7C1!C28!@baseboard_fab2_lib.baseboard_fab2(sch_1):page114_i40@chpset_lib.lbg_core_qat_ext_c(chips)!LBG_CORE_QAT_EXT_C_BGA1-IC,TBD!!!F2055!CLKOUT_SRCP(4)!!!!
S!CLK_100M_PCH_SLOTX24_S3_DP!U7C1!G40!@baseboard_fab2_lib.baseboard_fab2(sch_1):page114_i40@chpset_lib.lbg_core_qat_ext_c(chips)!LBG_CORE_QAT_EXT_C_BGA1-IC,TBD!!!F2055!CLKOUT_SRCP(5)!!!!
S!CLK_100M_PCH_SLOTX24_S4_DP!U7C1!B33!@baseboard_fab2_lib.baseboard_fab2(sch_1):page114_i40@chpset_lib.lbg_core_qat_ext_c(chips)!LBG_CORE_QAT_EXT_C_BGA1-IC,TBD!!!F2055!CLKOUT_SRCP(6)!!!!
S!CLK_100M_PCH_SLOTX24_S5_DP!U7C1!K31!@baseboard_fab2_lib.baseboard_fab2(sch_1):page114_i40@chpset_lib.lbg_core_qat_ext_c(chips)!LBG_CORE_QAT_EXT_C_BGA1-IC,TBD!!!F2055!CLKOUT_SRCP(7)!!!!
S!CLK_100M_MEZZ1_DP!U7C1!B31!@baseboard_fab2_lib.baseboard_fab2(sch_1):page114_i40@chpset_lib.lbg_core_qat_ext_c(chips)!LBG_CORE_QAT_EXT_C_BGA1-IC,TBD!!!F2055!CLKOUT_SRCP(8)!!!!
S!CLK_100M_MEZZ2_DP!U7C1!G26!@baseboard_fab2_lib.baseboard_fab2(sch_1):page114_i40@chpset_lib.lbg_core_qat_ext_c(chips)!LBG_CORE_QAT_EXT_C_BGA1-IC,TBD!!!F2055!CLKOUT_SRCP(9)!!!!
S!CLK_48M_USB_BMC!U7C1!BW50!@baseboard_fab2_lib.baseboard_fab2(sch_1):page114_i40@chpset_lib.lbg_core_qat_ext_c(chips)!LBG_CORE_QAT_EXT_C_BGA1-IC,TBD!!!F2055!CLOCKSE_BMCCLK!!!!
S!H_PMSYNC_CLK_24M_R!U7C1!BY51!@baseboard_fab2_lib.baseboard_fab2(sch_1):page114_i40@chpset_lib.lbg_core_qat_ext_c(chips)!LBG_CORE_QAT_EXT_C_BGA1-IC,TBD!!!F2055!CLOCKSE_PMSYNCCLK1!!!!
S!TP_CLK_24M_PMSYNC2!U7C1!BV51!@baseboard_fab2_lib.baseboard_fab2(sch_1):page114_i40@chpset_lib.lbg_core_qat_ext_c(chips)!LBG_CORE_QAT_EXT_C_BGA1-IC,TBD!!!F2055!CLOCKSE_PMSYNCCLK2!!!!
S!TP_PCH_RSVD64!U7C1!C26!@baseboard_fab2_lib.baseboard_fab2(sch_1):page114_i40@chpset_lib.lbg_core_qat_ext_c(chips)!LBG_CORE_QAT_EXT_C_BGA1-IC,TBD!!!F2055!RSVD(64)!!!!
S!TP_PCH_RSVD65!U7C1!A26!@baseboard_fab2_lib.baseboard_fab2(sch_1):page114_i40@chpset_lib.lbg_core_qat_ext_c(chips)!LBG_CORE_QAT_EXT_C_BGA1-IC,TBD!!!F2055!RSVD(65)!!!!
S!XTAL_33K_RTC1!U7C1!K17!@baseboard_fab2_lib.baseboard_fab2(sch_1):page114_i40@chpset_lib.lbg_core_qat_ext_c(chips)!LBG_CORE_QAT_EXT_C_BGA1-IC,TBD!!!F2055!RTCX1!!!!
S!XTAL_33K_RTC2!U7C1!H17!@baseboard_fab2_lib.baseboard_fab2(sch_1):page114_i40@chpset_lib.lbg_core_qat_ext_c(chips)!LBG_CORE_QAT_EXT_C_BGA1-IC,TBD!!!F2055!RTCX2!!!!
S!A_PCH_XCLK_BIASREF!U7C1!G44!@baseboard_fab2_lib.baseboard_fab2(sch_1):page114_i40@chpset_lib.lbg_core_qat_ext_c(chips)!LBG_CORE_QAT_EXT_C_BGA1-IC,TBD!!!F2055!XCLK_BIASREF!!!!
S!XTAL_PCH_48M_IN!U7C1!B35!@baseboard_fab2_lib.baseboard_fab2(sch_1):page114_i40@chpset_lib.lbg_core_qat_ext_c(chips)!LBG_CORE_QAT_EXT_C_BGA1-IC,TBD!!!F2055!XTAL_IN!!!!
S!XTAL_PCH_48M_OUT!U7C1!D35!@baseboard_fab2_lib.baseboard_fab2(sch_1):page114_i40@chpset_lib.lbg_core_qat_ext_c(chips)!LBG_CORE_QAT_EXT_C_BGA1-IC,TBD!!!F2055!XTAL_OUT!!!!
S!TP_PCH_RSVD55!U7C1!BN68!@baseboard_fab2_lib.baseboard_fab2(sch_1):page115_i74@chpset_lib.lbg_core_qat_ext_c(chips)!LBG_CORE_QAT_EXT_C_BGA1-IC,TBD!!!F2054!RSVD(55)!!!!
S!USB2_P01_DN!U7C1!BY60!@baseboard_fab2_lib.baseboard_fab2(sch_1):page115_i74@chpset_lib.lbg_core_qat_ext_c(chips)!LBG_CORE_QAT_EXT_C_BGA1-IC,TBD!!!F2054!USB2N_1!!!!
S!TP_USB2_P10_DN!U7C1!BW65!@baseboard_fab2_lib.baseboard_fab2(sch_1):page115_i74@chpset_lib.lbg_core_qat_ext_c(chips)!LBG_CORE_QAT_EXT_C_BGA1-IC,TBD!!!F2054!USB2N_10!!!!
S!TP_USB2_P11_DN!U7C1!CA54!@baseboard_fab2_lib.baseboard_fab2(sch_1):page115_i74@chpset_lib.lbg_core_qat_ext_c(chips)!LBG_CORE_QAT_EXT_C_BGA1-IC,TBD!!!F2054!USB2N_11!!!!
S!TP_USB2_P12_DN!U7C1!BW67!@baseboard_fab2_lib.baseboard_fab2(sch_1):page115_i74@chpset_lib.lbg_core_qat_ext_c(chips)!LBG_CORE_QAT_EXT_C_BGA1-IC,TBD!!!F2054!USB2N_12!!!!
S!TP_USB2_P13_DN!U7C1!BY53!@baseboard_fab2_lib.baseboard_fab2(sch_1):page115_i74@chpset_lib.lbg_core_qat_ext_c(chips)!LBG_CORE_QAT_EXT_C_BGA1-IC,TBD!!!F2054!USB2N_13!!!!
S!TP_USB2_P14_DN!U7C1!BW68!@baseboard_fab2_lib.baseboard_fab2(sch_1):page115_i74@chpset_lib.lbg_core_qat_ext_c(chips)!LBG_CORE_QAT_EXT_C_BGA1-IC,TBD!!!F2054!USB2N_14!!!!
S!TP_USB2_P02_DN!U7C1!CA61!@baseboard_fab2_lib.baseboard_fab2(sch_1):page115_i74@chpset_lib.lbg_core_qat_ext_c(chips)!LBG_CORE_QAT_EXT_C_BGA1-IC,TBD!!!F2054!USB2N_2!!!!
S!TP_USB2_P03_DN!U7C1!CA59!@baseboard_fab2_lib.baseboard_fab2(sch_1):page115_i74@chpset_lib.lbg_core_qat_ext_c(chips)!LBG_CORE_QAT_EXT_C_BGA1-IC,TBD!!!F2054!USB2N_3!!!!
S!USB_PCH_BMC_P4_DN!U7C1!BY62!@baseboard_fab2_lib.baseboard_fab2(sch_1):page115_i74@chpset_lib.lbg_core_qat_ext_c(chips)!LBG_CORE_QAT_EXT_C_BGA1-IC,TBD!!!F2054!USB2N_4!!!!
S!USB2_PCH_BMC_P5_DN!U7C1!BY58!@baseboard_fab2_lib.baseboard_fab2(sch_1):page115_i74@chpset_lib.lbg_core_qat_ext_c(chips)!LBG_CORE_QAT_EXT_C_BGA1-IC,TBD!!!F2054!USB2N_5!!!!
S!TP_USB2_P06_DN!U7C1!CA63!@baseboard_fab2_lib.baseboard_fab2(sch_1):page115_i74@chpset_lib.lbg_core_qat_ext_c(chips)!LBG_CORE_QAT_EXT_C_BGA1-IC,TBD!!!F2054!USB2N_6!!!!
S!TP_USB2_P07_DN!U7C1!CA57!@baseboard_fab2_lib.baseboard_fab2(sch_1):page115_i74@chpset_lib.lbg_core_qat_ext_c(chips)!LBG_CORE_QAT_EXT_C_BGA1-IC,TBD!!!F2054!USB2N_7!!!!
S!TP_USB2_P8_DN!U7C1!BY64!@baseboard_fab2_lib.baseboard_fab2(sch_1):page115_i74@chpset_lib.lbg_core_qat_ext_c(chips)!LBG_CORE_QAT_EXT_C_BGA1-IC,TBD!!!F2054!USB2N_8!!!!
S!TP_USB2_P9_DN!U7C1!BY55!@baseboard_fab2_lib.baseboard_fab2(sch_1):page115_i74@chpset_lib.lbg_core_qat_ext_c(chips)!LBG_CORE_QAT_EXT_C_BGA1-IC,TBD!!!F2054!USB2N_9!!!!
S!USB2_P01_DP!U7C1!BV60!@baseboard_fab2_lib.baseboard_fab2(sch_1):page115_i74@chpset_lib.lbg_core_qat_ext_c(chips)!LBG_CORE_QAT_EXT_C_BGA1-IC,TBD!!!F2054!USB2P_1!!!!
S!TP_USB2_P10_DP!U7C1!BU65!@baseboard_fab2_lib.baseboard_fab2(sch_1):page115_i74@chpset_lib.lbg_core_qat_ext_c(chips)!LBG_CORE_QAT_EXT_C_BGA1-IC,TBD!!!F2054!USB2P_10!!!!
S!TP_USB2_P11_DP!U7C1!BW54!@baseboard_fab2_lib.baseboard_fab2(sch_1):page115_i74@chpset_lib.lbg_core_qat_ext_c(chips)!LBG_CORE_QAT_EXT_C_BGA1-IC,TBD!!!F2054!USB2P_11!!!!
S!TP_USB2_P12_DP!U7C1!BV66!@baseboard_fab2_lib.baseboard_fab2(sch_1):page115_i74@chpset_lib.lbg_core_qat_ext_c(chips)!LBG_CORE_QAT_EXT_C_BGA1-IC,TBD!!!F2054!USB2P_12!!!!
S!TP_USB2_P13_DP!U7C1!BV53!@baseboard_fab2_lib.baseboard_fab2(sch_1):page115_i74@chpset_lib.lbg_core_qat_ext_c(chips)!LBG_CORE_QAT_EXT_C_BGA1-IC,TBD!!!F2054!USB2P_13!!!!
S!TP_USB2_P14_DP!U7C1!BU67!@baseboard_fab2_lib.baseboard_fab2(sch_1):page115_i74@chpset_lib.lbg_core_qat_ext_c(chips)!LBG_CORE_QAT_EXT_C_BGA1-IC,TBD!!!F2054!USB2P_14!!!!
S!TP_USB2_P02_DP!U7C1!BW61!@baseboard_fab2_lib.baseboard_fab2(sch_1):page115_i74@chpset_lib.lbg_core_qat_ext_c(chips)!LBG_CORE_QAT_EXT_C_BGA1-IC,TBD!!!F2054!USB2P_2!!!!
S!TP_USB2_P03_DP!U7C1!BW59!@baseboard_fab2_lib.baseboard_fab2(sch_1):page115_i74@chpset_lib.lbg_core_qat_ext_c(chips)!LBG_CORE_QAT_EXT_C_BGA1-IC,TBD!!!F2054!USB2P_3!!!!
S!USB_PCH_BMC_P4_DP!U7C1!BV62!@baseboard_fab2_lib.baseboard_fab2(sch_1):page115_i74@chpset_lib.lbg_core_qat_ext_c(chips)!LBG_CORE_QAT_EXT_C_BGA1-IC,TBD!!!F2054!USB2P_4!!!!
S!USB2_PCH_BMC_P5_DP!U7C1!BV58!@baseboard_fab2_lib.baseboard_fab2(sch_1):page115_i74@chpset_lib.lbg_core_qat_ext_c(chips)!LBG_CORE_QAT_EXT_C_BGA1-IC,TBD!!!F2054!USB2P_5!!!!
S!TP_USB2_P06_DP!U7C1!BW63!@baseboard_fab2_lib.baseboard_fab2(sch_1):page115_i74@chpset_lib.lbg_core_qat_ext_c(chips)!LBG_CORE_QAT_EXT_C_BGA1-IC,TBD!!!F2054!USB2P_6!!!!
S!TP_USB2_P07_DP!U7C1!BW57!@baseboard_fab2_lib.baseboard_fab2(sch_1):page115_i74@chpset_lib.lbg_core_qat_ext_c(chips)!LBG_CORE_QAT_EXT_C_BGA1-IC,TBD!!!F2054!USB2P_7!!!!
S!TP_USB2_P8_DP!U7C1!BV64!@baseboard_fab2_lib.baseboard_fab2(sch_1):page115_i74@chpset_lib.lbg_core_qat_ext_c(chips)!LBG_CORE_QAT_EXT_C_BGA1-IC,TBD!!!F2054!USB2P_8!!!!
S!TP_USB2_P9_DP!U7C1!BV55!@baseboard_fab2_lib.baseboard_fab2(sch_1):page115_i74@chpset_lib.lbg_core_qat_ext_c(chips)!LBG_CORE_QAT_EXT_C_BGA1-IC,TBD!!!F2054!USB2P_9!!!!
S!A_USB2_COMP!U7C1!BN70!@baseboard_fab2_lib.baseboard_fab2(sch_1):page115_i74@chpset_lib.lbg_core_qat_ext_c(chips)!LBG_CORE_QAT_EXT_C_BGA1-IC,TBD!!!F2054!USB2_COMP!!!!
S!A_USB2_VBUS!U7C1!BR67!@baseboard_fab2_lib.baseboard_fab2(sch_1):page115_i74@chpset_lib.lbg_core_qat_ext_c(chips)!LBG_CORE_QAT_EXT_C_BGA1-IC,TBD!!!F2054!USB2_VBUS!!!!
S!USB3_P01_RXN!U7C1!BK71!@baseboard_fab2_lib.baseboard_fab2(sch_1):page115_i74@chpset_lib.lbg_core_qat_ext_c(chips)!LBG_CORE_QAT_EXT_C_BGA1-IC,TBD!!!F2054!USB3_1_RXN!!!!
S!USB3_P01_RXP!U7C1!BK69!@baseboard_fab2_lib.baseboard_fab2(sch_1):page115_i74@chpset_lib.lbg_core_qat_ext_c(chips)!LBG_CORE_QAT_EXT_C_BGA1-IC,TBD!!!F2054!USB3_1_RXP!!!!
S!USB3_P01_TXN!U7C1!BL52!@baseboard_fab2_lib.baseboard_fab2(sch_1):page115_i74@chpset_lib.lbg_core_qat_ext_c(chips)!LBG_CORE_QAT_EXT_C_BGA1-IC,TBD!!!F2054!USB3_1_TXN!!!!
S!USB3_P01_TXP!U7C1!BK54!@baseboard_fab2_lib.baseboard_fab2(sch_1):page115_i74@chpset_lib.lbg_core_qat_ext_c(chips)!LBG_CORE_QAT_EXT_C_BGA1-IC,TBD!!!F2054!USB3_1_TXP!!!!
S!TP_USB3_P02_RXN!U7C1!BJ72!@baseboard_fab2_lib.baseboard_fab2(sch_1):page115_i74@chpset_lib.lbg_core_qat_ext_c(chips)!LBG_CORE_QAT_EXT_C_BGA1-IC,TBD!!!F2054!USB3_2_RXN!!!!
S!TP_USB3_P02_RXP!U7C1!BJ70!@baseboard_fab2_lib.baseboard_fab2(sch_1):page115_i74@chpset_lib.lbg_core_qat_ext_c(chips)!LBG_CORE_QAT_EXT_C_BGA1-IC,TBD!!!F2054!USB3_2_RXP!!!!
S!TP_USB3_P02_TXN!U7C1!BL56!@baseboard_fab2_lib.baseboard_fab2(sch_1):page115_i74@chpset_lib.lbg_core_qat_ext_c(chips)!LBG_CORE_QAT_EXT_C_BGA1-IC,TBD!!!F2054!USB3_2_TXN!!!!
S!TP_USB3_P02_TXP!U7C1!BJ56!@baseboard_fab2_lib.baseboard_fab2(sch_1):page115_i74@chpset_lib.lbg_core_qat_ext_c(chips)!LBG_CORE_QAT_EXT_C_BGA1-IC,TBD!!!F2054!USB3_2_TXP!!!!
S!TP_USB3_P03_RXN!U7C1!BH71!@baseboard_fab2_lib.baseboard_fab2(sch_1):page115_i74@chpset_lib.lbg_core_qat_ext_c(chips)!LBG_CORE_QAT_EXT_C_BGA1-IC,TBD!!!F2054!USB3_3_RXN!!!!
S!TP_USB3_P03_RXP!U7C1!BH69!@baseboard_fab2_lib.baseboard_fab2(sch_1):page115_i74@chpset_lib.lbg_core_qat_ext_c(chips)!LBG_CORE_QAT_EXT_C_BGA1-IC,TBD!!!F2054!USB3_3_RXP!!!!
S!TP_USB3_P03_TXN!U7C1!BM54!@baseboard_fab2_lib.baseboard_fab2(sch_1):page115_i74@chpset_lib.lbg_core_qat_ext_c(chips)!LBG_CORE_QAT_EXT_C_BGA1-IC,TBD!!!F2054!USB3_3_TXN!!!!
S!TP_USB3_P03_TXP!U7C1!BN56!@baseboard_fab2_lib.baseboard_fab2(sch_1):page115_i74@chpset_lib.lbg_core_qat_ext_c(chips)!LBG_CORE_QAT_EXT_C_BGA1-IC,TBD!!!F2054!USB3_3_TXP!!!!
S!TP_USB3_P04_RXN!U7C1!BF72!@baseboard_fab2_lib.baseboard_fab2(sch_1):page115_i74@chpset_lib.lbg_core_qat_ext_c(chips)!LBG_CORE_QAT_EXT_C_BGA1-IC,TBD!!!F2054!USB3_4_RXN!!!!
S!TP_USB3_P04_RXP!U7C1!BF70!@baseboard_fab2_lib.baseboard_fab2(sch_1):page115_i74@chpset_lib.lbg_core_qat_ext_c(chips)!LBG_CORE_QAT_EXT_C_BGA1-IC,TBD!!!F2054!USB3_4_RXP!!!!
S!TP_USB3_P04_TXN!U7C1!BH58!@baseboard_fab2_lib.baseboard_fab2(sch_1):page115_i74@chpset_lib.lbg_core_qat_ext_c(chips)!LBG_CORE_QAT_EXT_C_BGA1-IC,TBD!!!F2054!USB3_4_TXN!!!!
S!TP_USB3_P04_TXP!U7C1!BG56!@baseboard_fab2_lib.baseboard_fab2(sch_1):page115_i74@chpset_lib.lbg_core_qat_ext_c(chips)!LBG_CORE_QAT_EXT_C_BGA1-IC,TBD!!!F2054!USB3_4_TXP!!!!
S!TP_USB3_P05_RXN!U7C1!BE71!@baseboard_fab2_lib.baseboard_fab2(sch_1):page115_i74@chpset_lib.lbg_core_qat_ext_c(chips)!LBG_CORE_QAT_EXT_C_BGA1-IC,TBD!!!F2054!USB3_5_RXN!!!!
S!TP_USB3_P05_RXP!U7C1!BE69!@baseboard_fab2_lib.baseboard_fab2(sch_1):page115_i74@chpset_lib.lbg_core_qat_ext_c(chips)!LBG_CORE_QAT_EXT_C_BGA1-IC,TBD!!!F2054!USB3_5_RXP!!!!
S!TP_USB3_P05_TXN!U7C1!BK58!@baseboard_fab2_lib.baseboard_fab2(sch_1):page115_i74@chpset_lib.lbg_core_qat_ext_c(chips)!LBG_CORE_QAT_EXT_C_BGA1-IC,TBD!!!F2054!USB3_5_TXN!!!!
S!TP_USB3_P05_TXP!U7C1!BJ59!@baseboard_fab2_lib.baseboard_fab2(sch_1):page115_i74@chpset_lib.lbg_core_qat_ext_c(chips)!LBG_CORE_QAT_EXT_C_BGA1-IC,TBD!!!F2054!USB3_5_TXP!!!!
S!TP_USB3_P06_RXN!U7C1!BD72!@baseboard_fab2_lib.baseboard_fab2(sch_1):page115_i74@chpset_lib.lbg_core_qat_ext_c(chips)!LBG_CORE_QAT_EXT_C_BGA1-IC,TBD!!!F2054!USB3_6_RXN!!!!
S!TP_USB3_P06_RXP!U7C1!BD70!@baseboard_fab2_lib.baseboard_fab2(sch_1):page115_i74@chpset_lib.lbg_core_qat_ext_c(chips)!LBG_CORE_QAT_EXT_C_BGA1-IC,TBD!!!F2054!USB3_6_RXP!!!!
S!TP_USB3_P06_TXN!U7C1!BL59!@baseboard_fab2_lib.baseboard_fab2(sch_1):page115_i74@chpset_lib.lbg_core_qat_ext_c(chips)!LBG_CORE_QAT_EXT_C_BGA1-IC,TBD!!!F2054!USB3_6_TXN!!!!
S!TP_USB3_P06_TXP!U7C1!BM61!@baseboard_fab2_lib.baseboard_fab2(sch_1):page115_i74@chpset_lib.lbg_core_qat_ext_c(chips)!LBG_CORE_QAT_EXT_C_BGA1-IC,TBD!!!F2054!USB3_6_TXP!!!!
S!A_EXTCLKN!U7C1!D66!@baseboard_fab2_lib.baseboard_fab2(sch_1):page116_i220@chpset_lib.lbg_core_qat_ext_c(chips)!LBG_CORE_QAT_EXT_C_BGA1-IC,TBD!!!F2053!EXTCLKN!!!!
S!A_EXTCLKP!U7C1!E67!@baseboard_fab2_lib.baseboard_fab2(sch_1):page116_i220@chpset_lib.lbg_core_qat_ext_c(chips)!LBG_CORE_QAT_EXT_C_BGA1-IC,TBD!!!F2053!EXTCLKP!!!!
S!SATA6G_RX_DN<2>!U7C1!AV63!@baseboard_fab2_lib.baseboard_fab2(sch_1):page116_i220@chpset_lib.lbg_core_qat_ext_c(chips)!LBG_CORE_QAT_EXT_C_BGA1-IC,TBD!!!F2053!PCIE10_SSATA4_RXN!!!!
S!SATA6G_RX_DP<2>!U7C1!AU65!@baseboard_fab2_lib.baseboard_fab2(sch_1):page116_i220@chpset_lib.lbg_core_qat_ext_c(chips)!LBG_CORE_QAT_EXT_C_BGA1-IC,TBD!!!F2053!PCIE10_SSATA4_RXP!!!!
S!SATA6G_TX_DN<2>!U7C1!AD70!@baseboard_fab2_lib.baseboard_fab2(sch_1):page116_i220@chpset_lib.lbg_core_qat_ext_c(chips)!LBG_CORE_QAT_EXT_C_BGA1-IC,TBD!!!F2053!PCIE10_SSATA4_TXN!!!!
S!SATA6G_TX_DP<2>!U7C1!AD72!@baseboard_fab2_lib.baseboard_fab2(sch_1):page116_i220@chpset_lib.lbg_core_qat_ext_c(chips)!LBG_CORE_QAT_EXT_C_BGA1-IC,TBD!!!F2053!PCIE10_SSATA4_TXP!!!!
S!SATA6G_RX_DN<3>!U7C1!AT66!@baseboard_fab2_lib.baseboard_fab2(sch_1):page116_i220@chpset_lib.lbg_core_qat_ext_c(chips)!LBG_CORE_QAT_EXT_C_BGA1-IC,TBD!!!F2053!PCIE11_SSATA5_GBE_RXN!!!!
S!SATA6G_RX_DP<3>!U7C1!AV66!@baseboard_fab2_lib.baseboard_fab2(sch_1):page116_i220@chpset_lib.lbg_core_qat_ext_c(chips)!LBG_CORE_QAT_EXT_C_BGA1-IC,TBD!!!F2053!PCIE11_SSATA5_GBE_RXP!!!!
S!SATA6G_TX_DN<3>!U7C1!AC69!@baseboard_fab2_lib.baseboard_fab2(sch_1):page116_i220@chpset_lib.lbg_core_qat_ext_c(chips)!LBG_CORE_QAT_EXT_C_BGA1-IC,TBD!!!F2053!PCIE11_SSATA5_GBE_TXN!!!!
S!SATA6G_TX_DP<3>!U7C1!AC71!@baseboard_fab2_lib.baseboard_fab2(sch_1):page116_i220@chpset_lib.lbg_core_qat_ext_c(chips)!LBG_CORE_QAT_EXT_C_BGA1-IC,TBD!!!F2053!PCIE11_SSATA5_GBE_TXP!!!!
S!SATA6G_PCH_PCIE_UP_SATA_RXN<0>!U7C1!AR61!@baseboard_fab2_lib.baseboard_fab2(sch_1):page116_i220@chpset_lib.lbg_core_qat_ext_c(chips)!LBG_CORE_QAT_EXT_C_BGA1-IC,TBD!!!F2053!PCIE12_UP0_SATA0_RXN!!!!
S!SATA6G_PCH_PCIE_UP_SATA_RXP<0>!U7C1!AT63!@baseboard_fab2_lib.baseboard_fab2(sch_1):page116_i220@chpset_lib.lbg_core_qat_ext_c(chips)!LBG_CORE_QAT_EXT_C_BGA1-IC,TBD!!!F2053!PCIE12_UP0_SATA0_RXP!!!!
S!SATA6G_PCH_PCIE_UP_SATA_TXN<0>!U7C1!W69!@baseboard_fab2_lib.baseboard_fab2(sch_1):page116_i220@chpset_lib.lbg_core_qat_ext_c(chips)!LBG_CORE_QAT_EXT_C_BGA1-IC,TBD!!!F2053!PCIE12_UP0_SATA0_TXN!!!!
S!SATA6G_PCH_PCIE_UP_SATA_TXP<0>!U7C1!W71!@baseboard_fab2_lib.baseboard_fab2(sch_1):page116_i220@chpset_lib.lbg_core_qat_ext_c(chips)!LBG_CORE_QAT_EXT_C_BGA1-IC,TBD!!!F2053!PCIE12_UP0_SATA0_TXP!!!!
S!SATA6G_PCH_PCIE_UP_SATA_RXN<1>!U7C1!AL66!@baseboard_fab2_lib.baseboard_fab2(sch_1):page116_i220@chpset_lib.lbg_core_qat_ext_c(chips)!LBG_CORE_QAT_EXT_C_BGA1-IC,TBD!!!F2053!PCIE13_UP1_SATA1_RXN!!!!
S!SATA6G_PCH_PCIE_UP_SATA_RXP<1>!U7C1!AN65!@baseboard_fab2_lib.baseboard_fab2(sch_1):page116_i220@chpset_lib.lbg_core_qat_ext_c(chips)!LBG_CORE_QAT_EXT_C_BGA1-IC,TBD!!!F2053!PCIE13_UP1_SATA1_RXP!!!!
S!SATA6G_PCH_PCIE_UP_SATA_TXN<1>!U7C1!V70!@baseboard_fab2_lib.baseboard_fab2(sch_1):page116_i220@chpset_lib.lbg_core_qat_ext_c(chips)!LBG_CORE_QAT_EXT_C_BGA1-IC,TBD!!!F2053!PCIE13_UP1_SATA1_TXN!!!!
S!SATA6G_PCH_PCIE_UP_SATA_TXP<1>!U7C1!V72!@baseboard_fab2_lib.baseboard_fab2(sch_1):page116_i220@chpset_lib.lbg_core_qat_ext_c(chips)!LBG_CORE_QAT_EXT_C_BGA1-IC,TBD!!!F2053!PCIE13_UP1_SATA1_TXP!!!!
S!SATA6G_PCH_PCIE_UP_SATA_RXN<2>!U7C1!AK65!@baseboard_fab2_lib.baseboard_fab2(sch_1):page116_i220@chpset_lib.lbg_core_qat_ext_c(chips)!LBG_CORE_QAT_EXT_C_BGA1-IC,TBD!!!F2053!PCIE14_UP2_SATA2_RXN!!!!
S!SATA6G_PCH_PCIE_UP_SATA_RXP<2>!U7C1!AJ63!@baseboard_fab2_lib.baseboard_fab2(sch_1):page116_i220@chpset_lib.lbg_core_qat_ext_c(chips)!LBG_CORE_QAT_EXT_C_BGA1-IC,TBD!!!F2053!PCIE14_UP2_SATA2_RXP!!!!
S!SATA6G_PCH_PCIE_UP_SATA_TXN<2>!U7C1!T69!@baseboard_fab2_lib.baseboard_fab2(sch_1):page116_i220@chpset_lib.lbg_core_qat_ext_c(chips)!LBG_CORE_QAT_EXT_C_BGA1-IC,TBD!!!F2053!PCIE14_UP2_SATA2_TXN!!!!
S!SATA6G_PCH_PCIE_UP_SATA_TXP<2>!U7C1!T71!@baseboard_fab2_lib.baseboard_fab2(sch_1):page116_i220@chpset_lib.lbg_core_qat_ext_c(chips)!LBG_CORE_QAT_EXT_C_BGA1-IC,TBD!!!F2053!PCIE14_UP2_SATA2_TXP!!!!
S!SATA6G_PCH_PCIE_UP_SATA_RXN<3>!U7C1!AP63!@baseboard_fab2_lib.baseboard_fab2(sch_1):page116_i220@chpset_lib.lbg_core_qat_ext_c(chips)!LBG_CORE_QAT_EXT_C_BGA1-IC,TBD!!!F2053!PCIE15_UP3_SATA3_RXN!!!!
S!SATA6G_PCH_PCIE_UP_SATA_RXP<3>!U7C1!AL63!@baseboard_fab2_lib.baseboard_fab2(sch_1):page116_i220@chpset_lib.lbg_core_qat_ext_c(chips)!LBG_CORE_QAT_EXT_C_BGA1-IC,TBD!!!F2053!PCIE15_UP3_SATA3_RXP!!!!
S!SATA6G_PCH_PCIE_UP_SATA_TXN<3>!U7C1!R70!@baseboard_fab2_lib.baseboard_fab2(sch_1):page116_i220@chpset_lib.lbg_core_qat_ext_c(chips)!LBG_CORE_QAT_EXT_C_BGA1-IC,TBD!!!F2053!PCIE15_UP3_SATA3_TXN!!!!
S!SATA6G_PCH_PCIE_UP_SATA_TXP<3>!U7C1!R72!@baseboard_fab2_lib.baseboard_fab2(sch_1):page116_i220@chpset_lib.lbg_core_qat_ext_c(chips)!LBG_CORE_QAT_EXT_C_BGA1-IC,TBD!!!F2053!PCIE15_UP3_SATA3_TXP!!!!
S!SATA6G_PCH_PCIE_UP_SATA_RXN<4>!U7C1!AF65!@baseboard_fab2_lib.baseboard_fab2(sch_1):page116_i220@chpset_lib.lbg_core_qat_ext_c(chips)!LBG_CORE_QAT_EXT_C_BGA1-IC,TBD!!!F2053!PCIE16_UP4_SATA4_RXN!!!!
S!SATA6G_PCH_PCIE_UP_SATA_RXP<4>!U7C1!AH65!@baseboard_fab2_lib.baseboard_fab2(sch_1):page116_i220@chpset_lib.lbg_core_qat_ext_c(chips)!LBG_CORE_QAT_EXT_C_BGA1-IC,TBD!!!F2053!PCIE16_UP4_SATA4_RXP!!!!
S!SATA6G_PCH_PCIE_UP_SATA_TXN<4>!U7C1!P69!@baseboard_fab2_lib.baseboard_fab2(sch_1):page116_i220@chpset_lib.lbg_core_qat_ext_c(chips)!LBG_CORE_QAT_EXT_C_BGA1-IC,TBD!!!F2053!PCIE16_UP4_SATA4_TXN!!!!
S!SATA6G_PCH_PCIE_UP_SATA_TXP<4>!U7C1!P71!@baseboard_fab2_lib.baseboard_fab2(sch_1):page116_i220@chpset_lib.lbg_core_qat_ext_c(chips)!LBG_CORE_QAT_EXT_C_BGA1-IC,TBD!!!F2053!PCIE16_UP4_SATA4_TXP!!!!
S!SATA6G_PCH_PCIE_UP_SATA_RXN<5>!U7C1!AH61!@baseboard_fab2_lib.baseboard_fab2(sch_1):page116_i220@chpset_lib.lbg_core_qat_ext_c(chips)!LBG_CORE_QAT_EXT_C_BGA1-IC,TBD!!!F2053!PCIE17_UP5_SATA5_RXN!!!!
S!SATA6G_PCH_PCIE_UP_SATA_RXP<5>!U7C1!AG63!@baseboard_fab2_lib.baseboard_fab2(sch_1):page116_i220@chpset_lib.lbg_core_qat_ext_c(chips)!LBG_CORE_QAT_EXT_C_BGA1-IC,TBD!!!F2053!PCIE17_UP5_SATA5_RXP!!!!
S!SATA6G_PCH_PCIE_UP_SATA_TXN<5>!U7C1!N70!@baseboard_fab2_lib.baseboard_fab2(sch_1):page116_i220@chpset_lib.lbg_core_qat_ext_c(chips)!LBG_CORE_QAT_EXT_C_BGA1-IC,TBD!!!F2053!PCIE17_UP5_SATA5_TXN!!!!
S!SATA6G_PCH_PCIE_UP_SATA_TXP<5>!U7C1!N72!@baseboard_fab2_lib.baseboard_fab2(sch_1):page116_i220@chpset_lib.lbg_core_qat_ext_c(chips)!LBG_CORE_QAT_EXT_C_BGA1-IC,TBD!!!F2053!PCIE17_UP5_SATA5_TXP!!!!
S!SATA6G_PCH_PCIE_UP_SATA_RXN<6>!U7C1!AP59!@baseboard_fab2_lib.baseboard_fab2(sch_1):page116_i220@chpset_lib.lbg_core_qat_ext_c(chips)!LBG_CORE_QAT_EXT_C_BGA1-IC,TBD!!!F2053!PCIE18_UP6_SATA6_RXN!!!!
S!SATA6G_PCH_PCIE_UP_SATA_RXP<6>!U7C1!AN61!@baseboard_fab2_lib.baseboard_fab2(sch_1):page116_i220@chpset_lib.lbg_core_qat_ext_c(chips)!LBG_CORE_QAT_EXT_C_BGA1-IC,TBD!!!F2053!PCIE18_UP6_SATA6_RXP!!!!
S!SATA6G_PCH_PCIE_UP_SATA_TXN<6>!U7C1!M69!@baseboard_fab2_lib.baseboard_fab2(sch_1):page116_i220@chpset_lib.lbg_core_qat_ext_c(chips)!LBG_CORE_QAT_EXT_C_BGA1-IC,TBD!!!F2053!PCIE18_UP6_SATA6_TXN!!!!
S!SATA6G_PCH_PCIE_UP_SATA_TXP<6>!U7C1!M71!@baseboard_fab2_lib.baseboard_fab2(sch_1):page116_i220@chpset_lib.lbg_core_qat_ext_c(chips)!LBG_CORE_QAT_EXT_C_BGA1-IC,TBD!!!F2053!PCIE18_UP6_SATA6_TXP!!!!
S!SATA6G_PCH_PCIE_UP_SATA_RXN<7>!U7C1!AA61!@baseboard_fab2_lib.baseboard_fab2(sch_1):page116_i220@chpset_lib.lbg_core_qat_ext_c(chips)!LBG_CORE_QAT_EXT_C_BGA1-IC,TBD!!!F2053!PCIE19_UP7_SATA7_RXN!!!!
S!SATA6G_PCH_PCIE_UP_SATA_RXP<7>!U7C1!AD61!@baseboard_fab2_lib.baseboard_fab2(sch_1):page116_i220@chpset_lib.lbg_core_qat_ext_c(chips)!LBG_CORE_QAT_EXT_C_BGA1-IC,TBD!!!F2053!PCIE19_UP7_SATA7_RXP!!!!
S!SATA6G_PCH_PCIE_UP_SATA_TXN<7>!U7C1!L70!@baseboard_fab2_lib.baseboard_fab2(sch_1):page116_i220@chpset_lib.lbg_core_qat_ext_c(chips)!LBG_CORE_QAT_EXT_C_BGA1-IC,TBD!!!F2053!PCIE19_UP7_SATA7_TXN!!!!
S!SATA6G_PCH_PCIE_UP_SATA_TXP<7>!U7C1!L72!@baseboard_fab2_lib.baseboard_fab2(sch_1):page116_i220@chpset_lib.lbg_core_qat_ext_c(chips)!LBG_CORE_QAT_EXT_C_BGA1-IC,TBD!!!F2053!PCIE19_UP7_SATA7_TXP!!!!
S!P2E_SSB_BMC_RX_C_DN!U7C1!AN70!@baseboard_fab2_lib.baseboard_fab2(sch_1):page116_i220@chpset_lib.lbg_core_qat_ext_c(chips)!LBG_CORE_QAT_EXT_C_BGA1-IC,TBD!!!F2053!PCIE4_GBE_RXN!!!!
S!P2E_SSB_BMC_RX_C_DP!U7C1!AN72!@baseboard_fab2_lib.baseboard_fab2(sch_1):page116_i220@chpset_lib.lbg_core_qat_ext_c(chips)!LBG_CORE_QAT_EXT_C_BGA1-IC,TBD!!!F2053!PCIE4_GBE_RXP!!!!
S!P2E_SSB_BMC_TX_DN!U7C1!BG66!@baseboard_fab2_lib.baseboard_fab2(sch_1):page116_i220@chpset_lib.lbg_core_qat_ext_c(chips)!LBG_CORE_QAT_EXT_C_BGA1-IC,TBD!!!F2053!PCIE4_GBE_TXN!!!!
S!P2E_SSB_BMC_TX_DP!U7C1!BJ66!@baseboard_fab2_lib.baseboard_fab2(sch_1):page116_i220@chpset_lib.lbg_core_qat_ext_c(chips)!LBG_CORE_QAT_EXT_C_BGA1-IC,TBD!!!F2053!PCIE4_GBE_TXP!!!!
S!PE_PCH_SPRV_RX_C_DN!U7C1!AM69!@baseboard_fab2_lib.baseboard_fab2(sch_1):page116_i220@chpset_lib.lbg_core_qat_ext_c(chips)!LBG_CORE_QAT_EXT_C_BGA1-IC,TBD!!!F2053!PCIE5_GBE_RXN!!!!
S!PE_PCH_SPRV_RX_C_DP!U7C1!AM71!@baseboard_fab2_lib.baseboard_fab2(sch_1):page116_i220@chpset_lib.lbg_core_qat_ext_c(chips)!LBG_CORE_QAT_EXT_C_BGA1-IC,TBD!!!F2053!PCIE5_GBE_RXP!!!!
S!PE_PCH_SPRV_TX_DN!U7C1!BH65!@baseboard_fab2_lib.baseboard_fab2(sch_1):page116_i220@chpset_lib.lbg_core_qat_ext_c(chips)!LBG_CORE_QAT_EXT_C_BGA1-IC,TBD!!!F2053!PCIE5_GBE_TXN!!!!
S!PE_PCH_SPRV_TX_DP!U7C1!BJ63!@baseboard_fab2_lib.baseboard_fab2(sch_1):page116_i220@chpset_lib.lbg_core_qat_ext_c(chips)!LBG_CORE_QAT_EXT_C_BGA1-IC,TBD!!!F2053!PCIE5_GBE_TXP!!!!
S!SATA6G_S0_RX_DN!U7C1!BB63!@baseboard_fab2_lib.baseboard_fab2(sch_1):page116_i220@chpset_lib.lbg_core_qat_ext_c(chips)!LBG_CORE_QAT_EXT_C_BGA1-IC,TBD!!!F2053!PCIE6_SSATA0_RXN!!!!
S!SATA6G_S0_RX_DP!U7C1!BD61!@baseboard_fab2_lib.baseboard_fab2(sch_1):page116_i220@chpset_lib.lbg_core_qat_ext_c(chips)!LBG_CORE_QAT_EXT_C_BGA1-IC,TBD!!!F2053!PCIE6_SSATA0_RXP!!!!
S!SATA6G_S0_TX_DN!U7C1!AJ70!@baseboard_fab2_lib.baseboard_fab2(sch_1):page116_i220@chpset_lib.lbg_core_qat_ext_c(chips)!LBG_CORE_QAT_EXT_C_BGA1-IC,TBD!!!F2053!PCIE6_SSATA0_TXN!!!!
S!SATA6G_S0_TX_DP!U7C1!AJ72!@baseboard_fab2_lib.baseboard_fab2(sch_1):page116_i220@chpset_lib.lbg_core_qat_ext_c(chips)!LBG_CORE_QAT_EXT_C_BGA1-IC,TBD!!!F2053!PCIE6_SSATA0_TXP!!!!
S!SATA6G_S1_RX_DN!U7C1!AY59!@baseboard_fab2_lib.baseboard_fab2(sch_1):page116_i220@chpset_lib.lbg_core_qat_ext_c(chips)!LBG_CORE_QAT_EXT_C_BGA1-IC,TBD!!!F2053!PCIE7_SSATA1_RXN!!!!
S!SATA6G_S1_RX_DP!U7C1!BA61!@baseboard_fab2_lib.baseboard_fab2(sch_1):page116_i220@chpset_lib.lbg_core_qat_ext_c(chips)!LBG_CORE_QAT_EXT_C_BGA1-IC,TBD!!!F2053!PCIE7_SSATA1_RXP!!!!
S!SATA6G_S1_TX_DN!U7C1!AH69!@baseboard_fab2_lib.baseboard_fab2(sch_1):page116_i220@chpset_lib.lbg_core_qat_ext_c(chips)!LBG_CORE_QAT_EXT_C_BGA1-IC,TBD!!!F2053!PCIE7_SSATA1_TXN!!!!
S!SATA6G_S1_TX_DP!U7C1!AH71!@baseboard_fab2_lib.baseboard_fab2(sch_1):page116_i220@chpset_lib.lbg_core_qat_ext_c(chips)!LBG_CORE_QAT_EXT_C_BGA1-IC,TBD!!!F2053!PCIE7_SSATA1_TXP!!!!
S!SATA6G_RX_DN<0>!U7C1!BA65!@baseboard_fab2_lib.baseboard_fab2(sch_1):page116_i220@chpset_lib.lbg_core_qat_ext_c(chips)!LBG_CORE_QAT_EXT_C_BGA1-IC,TBD!!!F2053!PCIE8_SSATA2_GBE_RXN!!!!
S!SATA6G_RX_DP<0>!U7C1!BD65!@baseboard_fab2_lib.baseboard_fab2(sch_1):page116_i220@chpset_lib.lbg_core_qat_ext_c(chips)!LBG_CORE_QAT_EXT_C_BGA1-IC,TBD!!!F2053!PCIE8_SSATA2_GBE_RXP!!!!
S!SATA6G_TX_DN<0>!U7C1!AF70!@baseboard_fab2_lib.baseboard_fab2(sch_1):page116_i220@chpset_lib.lbg_core_qat_ext_c(chips)!LBG_CORE_QAT_EXT_C_BGA1-IC,TBD!!!F2053!PCIE8_SSATA2_GBE_TXN!!!!
S!SATA6G_TX_DP<0>!U7C1!AF72!@baseboard_fab2_lib.baseboard_fab2(sch_1):page116_i220@chpset_lib.lbg_core_qat_ext_c(chips)!LBG_CORE_QAT_EXT_C_BGA1-IC,TBD!!!F2053!PCIE8_SSATA2_GBE_TXP!!!!
S!SATA6G_RX_DN<1>!U7C1!AW65!@baseboard_fab2_lib.baseboard_fab2(sch_1):page116_i220@chpset_lib.lbg_core_qat_ext_c(chips)!LBG_CORE_QAT_EXT_C_BGA1-IC,TBD!!!F2053!PCIE9_SSATA3_RXN!!!!
S!SATA6G_RX_DP<1>!U7C1!AY66!@baseboard_fab2_lib.baseboard_fab2(sch_1):page116_i220@chpset_lib.lbg_core_qat_ext_c(chips)!LBG_CORE_QAT_EXT_C_BGA1-IC,TBD!!!F2053!PCIE9_SSATA3_RXP!!!!
S!SATA6G_TX_DN<1>!U7C1!AE69!@baseboard_fab2_lib.baseboard_fab2(sch_1):page116_i220@chpset_lib.lbg_core_qat_ext_c(chips)!LBG_CORE_QAT_EXT_C_BGA1-IC,TBD!!!F2053!PCIE9_SSATA3_TXN!!!!
S!SATA6G_TX_DP<1>!U7C1!AE71!@baseboard_fab2_lib.baseboard_fab2(sch_1):page116_i220@chpset_lib.lbg_core_qat_ext_c(chips)!LBG_CORE_QAT_EXT_C_BGA1-IC,TBD!!!F2053!PCIE9_SSATA3_TXP!!!!
S!A_PCIEUP_RCOMP_N!U7C1!AF58!@baseboard_fab2_lib.baseboard_fab2(sch_1):page116_i220@chpset_lib.lbg_core_qat_ext_c(chips)!LBG_CORE_QAT_EXT_C_BGA1-IC,TBD!!!F2053!PCIEUP_RCOMPN!!!!
S!A_PCIEUP_RCOMP_P!U7C1!AH58!@baseboard_fab2_lib.baseboard_fab2(sch_1):page116_i220@chpset_lib.lbg_core_qat_ext_c(chips)!LBG_CORE_QAT_EXT_C_BGA1-IC,TBD!!!F2053!PCIEUP_RCOMPP!!!!
S!A_PCIE_RCOMP_N!U7C1!BD58!@baseboard_fab2_lib.baseboard_fab2(sch_1):page116_i220@chpset_lib.lbg_core_qat_ext_c(chips)!LBG_CORE_QAT_EXT_C_BGA1-IC,TBD!!!F2053!PCIE_RCOMPN!!!!
S!A_PCIE_RCOMP_P!U7C1!BB56!@baseboard_fab2_lib.baseboard_fab2(sch_1):page116_i220@chpset_lib.lbg_core_qat_ext_c(chips)!LBG_CORE_QAT_EXT_C_BGA1-IC,TBD!!!F2053!PCIE_RCOMPP!!!!
S!TP_PCH_RSVD47!U7C1!AP69!@baseboard_fab2_lib.baseboard_fab2(sch_1):page116_i220@chpset_lib.lbg_core_qat_ext_c(chips)!LBG_CORE_QAT_EXT_C_BGA1-IC,TBD!!!F2053!RSVD(47)!!!!
S!TP_PCH_RSVD48!U7C1!AP71!@baseboard_fab2_lib.baseboard_fab2(sch_1):page116_i220@chpset_lib.lbg_core_qat_ext_c(chips)!LBG_CORE_QAT_EXT_C_BGA1-IC,TBD!!!F2053!RSVD(48)!!!!
S!TP_PCH_RSVD49!U7C1!G67!@baseboard_fab2_lib.baseboard_fab2(sch_1):page116_i220@chpset_lib.lbg_core_qat_ext_c(chips)!LBG_CORE_QAT_EXT_C_BGA1-IC,TBD!!!F2053!RSVD(49)!!!!
S!TP_PCH_RSVD50!U7C1!H69!@baseboard_fab2_lib.baseboard_fab2(sch_1):page116_i220@chpset_lib.lbg_core_qat_ext_c(chips)!LBG_CORE_QAT_EXT_C_BGA1-IC,TBD!!!F2053!RSVD(50)!!!!
S!TP_PCH_RSVD51!U7C1!AA69!@baseboard_fab2_lib.baseboard_fab2(sch_1):page116_i220@chpset_lib.lbg_core_qat_ext_c(chips)!LBG_CORE_QAT_EXT_C_BGA1-IC,TBD!!!F2053!RSVD(51)!!!!
S!TP_PCH_RSVD52!U7C1!AA71!@baseboard_fab2_lib.baseboard_fab2(sch_1):page116_i220@chpset_lib.lbg_core_qat_ext_c(chips)!LBG_CORE_QAT_EXT_C_BGA1-IC,TBD!!!F2053!RSVD(52)!!!!
S!P3E_PCH_M2_RX_DN<3>!U7C1!AV72!@baseboard_fab2_lib.baseboard_fab2(sch_1):page116_i220@chpset_lib.lbg_core_qat_ext_c(chips)!LBG_CORE_QAT_EXT_C_BGA1-IC,TBD!!!F2053!USB3_10_PCIE3_GBE_RXN!!!!
S!P3E_PCH_M2_RX_DP<3>!U7C1!AV70!@baseboard_fab2_lib.baseboard_fab2(sch_1):page116_i220@chpset_lib.lbg_core_qat_ext_c(chips)!LBG_CORE_QAT_EXT_C_BGA1-IC,TBD!!!F2053!USB3_10_PCIE3_GBE_RXP!!!!
S!P3E_PCH_M2_TX_DN<3>!U7C1!BH61!@baseboard_fab2_lib.baseboard_fab2(sch_1):page116_i220@chpset_lib.lbg_core_qat_ext_c(chips)!LBG_CORE_QAT_EXT_C_BGA1-IC,TBD!!!F2053!USB3_10_PCIE3_GBE_TXN!!!!
S!P3E_PCH_M2_TX_DP<3>!U7C1!BK61!@baseboard_fab2_lib.baseboard_fab2(sch_1):page116_i220@chpset_lib.lbg_core_qat_ext_c(chips)!LBG_CORE_QAT_EXT_C_BGA1-IC,TBD!!!F2053!USB3_10_PCIE3_GBE_TXP!!!!
S!P3E_PCH_RX_0_DN!U7C1!BA71!@baseboard_fab2_lib.baseboard_fab2(sch_1):page116_i220@chpset_lib.lbg_core_qat_ext_c(chips)!LBG_CORE_QAT_EXT_C_BGA1-IC,TBD!!!F2053!USB3_7_PCIE0_RXN!!!!
S!P3E_PCH_RX_0_DP!U7C1!BA69!@baseboard_fab2_lib.baseboard_fab2(sch_1):page116_i220@chpset_lib.lbg_core_qat_ext_c(chips)!LBG_CORE_QAT_EXT_C_BGA1-IC,TBD!!!F2053!USB3_7_PCIE0_RXP!!!!
S!P3E_PCH_TX_0_DN!U7C1!BR61!@baseboard_fab2_lib.baseboard_fab2(sch_1):page116_i220@chpset_lib.lbg_core_qat_ext_c(chips)!LBG_CORE_QAT_EXT_C_BGA1-IC,TBD!!!F2053!USB3_7_PCIE0_TXN!!!!
S!P3E_PCH_TX_0_DP!U7C1!BN63!@baseboard_fab2_lib.baseboard_fab2(sch_1):page116_i220@chpset_lib.lbg_core_qat_ext_c(chips)!LBG_CORE_QAT_EXT_C_BGA1-IC,TBD!!!F2053!USB3_7_PCIE0_TXP!!!!
S!P3E_PCH_M2_RX_DN<1>!U7C1!AY72!@baseboard_fab2_lib.baseboard_fab2(sch_1):page116_i220@chpset_lib.lbg_core_qat_ext_c(chips)!LBG_CORE_QAT_EXT_C_BGA1-IC,TBD!!!F2053!USB3_8_PCIE1_RXN!!!!
S!P3E_PCH_M2_RX_DP<1>!U7C1!AY70!@baseboard_fab2_lib.baseboard_fab2(sch_1):page116_i220@chpset_lib.lbg_core_qat_ext_c(chips)!LBG_CORE_QAT_EXT_C_BGA1-IC,TBD!!!F2053!USB3_8_PCIE1_RXP!!!!
S!P3E_PCH_M2_TX_DN<1>!U7C1!BM65!@baseboard_fab2_lib.baseboard_fab2(sch_1):page116_i220@chpset_lib.lbg_core_qat_ext_c(chips)!LBG_CORE_QAT_EXT_C_BGA1-IC,TBD!!!F2053!USB3_8_PCIE1_TXN!!!!
S!P3E_PCH_M2_TX_DP<1>!U7C1!BR65!@baseboard_fab2_lib.baseboard_fab2(sch_1):page116_i220@chpset_lib.lbg_core_qat_ext_c(chips)!LBG_CORE_QAT_EXT_C_BGA1-IC,TBD!!!F2053!USB3_8_PCIE1_TXP!!!!
S!P3E_PCH_M2_RX_DN<2>!U7C1!AW71!@baseboard_fab2_lib.baseboard_fab2(sch_1):page116_i220@chpset_lib.lbg_core_qat_ext_c(chips)!LBG_CORE_QAT_EXT_C_BGA1-IC,TBD!!!F2053!USB3_9_PCIE2_RXN!!!!
S!P3E_PCH_M2_RX_DP<2>!U7C1!AW69!@baseboard_fab2_lib.baseboard_fab2(sch_1):page116_i220@chpset_lib.lbg_core_qat_ext_c(chips)!LBG_CORE_QAT_EXT_C_BGA1-IC,TBD!!!F2053!USB3_9_PCIE2_RXP!!!!
S!P3E_PCH_M2_TX_DN<2>!U7C1!BK65!@baseboard_fab2_lib.baseboard_fab2(sch_1):page116_i220@chpset_lib.lbg_core_qat_ext_c(chips)!LBG_CORE_QAT_EXT_C_BGA1-IC,TBD!!!F2053!USB3_9_PCIE2_TXN!!!!
S!P3E_PCH_M2_TX_DP<2>!U7C1!BL66!@baseboard_fab2_lib.baseboard_fab2(sch_1):page116_i220@chpset_lib.lbg_core_qat_ext_c(chips)!LBG_CORE_QAT_EXT_C_BGA1-IC,TBD!!!F2053!USB3_9_PCIE2_TXP!!!!
S!DMI_CPU0_PCH_TX_C_DN<0>!U7C1!D42!@baseboard_fab2_lib.baseboard_fab2(sch_1):page117_i9@chpset_lib.lbg_core_qat_ext_c(chips)!LBG_CORE_QAT_EXT_C_BGA1-IC,TBD!!!F2052!DMI_RXN(0)!!!!
S!DMI_CPU0_PCH_TX_C_DN<1>!U7C1!C43!@baseboard_fab2_lib.baseboard_fab2(sch_1):page117_i9@chpset_lib.lbg_core_qat_ext_c(chips)!LBG_CORE_QAT_EXT_C_BGA1-IC,TBD!!!F2052!DMI_RXN(1)!!!!
S!DMI_CPU0_PCH_TX_C_DN<2>!U7C1!D44!@baseboard_fab2_lib.baseboard_fab2(sch_1):page117_i9@chpset_lib.lbg_core_qat_ext_c(chips)!LBG_CORE_QAT_EXT_C_BGA1-IC,TBD!!!F2052!DMI_RXN(2)!!!!
S!DMI_CPU0_PCH_TX_C_DN<3>!U7C1!C45!@baseboard_fab2_lib.baseboard_fab2(sch_1):page117_i9@chpset_lib.lbg_core_qat_ext_c(chips)!LBG_CORE_QAT_EXT_C_BGA1-IC,TBD!!!F2052!DMI_RXN(3)!!!!
S!DMI_CPU0_PCH_TX_C_DP<0>!U7C1!B42!@baseboard_fab2_lib.baseboard_fab2(sch_1):page117_i9@chpset_lib.lbg_core_qat_ext_c(chips)!LBG_CORE_QAT_EXT_C_BGA1-IC,TBD!!!F2052!DMI_RXP(0)!!!!
S!DMI_CPU0_PCH_TX_C_DP<1>!U7C1!A43!@baseboard_fab2_lib.baseboard_fab2(sch_1):page117_i9@chpset_lib.lbg_core_qat_ext_c(chips)!LBG_CORE_QAT_EXT_C_BGA1-IC,TBD!!!F2052!DMI_RXP(1)!!!!
S!DMI_CPU0_PCH_TX_C_DP<2>!U7C1!B44!@baseboard_fab2_lib.baseboard_fab2(sch_1):page117_i9@chpset_lib.lbg_core_qat_ext_c(chips)!LBG_CORE_QAT_EXT_C_BGA1-IC,TBD!!!F2052!DMI_RXP(2)!!!!
S!DMI_CPU0_PCH_TX_C_DP<3>!U7C1!A45!@baseboard_fab2_lib.baseboard_fab2(sch_1):page117_i9@chpset_lib.lbg_core_qat_ext_c(chips)!LBG_CORE_QAT_EXT_C_BGA1-IC,TBD!!!F2052!DMI_RXP(3)!!!!
S!DMI_CPU0_PCH_RX_DN<0>!U7C1!H46!@baseboard_fab2_lib.baseboard_fab2(sch_1):page117_i9@chpset_lib.lbg_core_qat_ext_c(chips)!LBG_CORE_QAT_EXT_C_BGA1-IC,TBD!!!F2052!DMI_TXN(0)!!!!
S!DMI_CPU0_PCH_RX_DN<1>!U7C1!J48!@baseboard_fab2_lib.baseboard_fab2(sch_1):page117_i9@chpset_lib.lbg_core_qat_ext_c(chips)!LBG_CORE_QAT_EXT_C_BGA1-IC,TBD!!!F2052!DMI_TXN(1)!!!!
S!DMI_CPU0_PCH_RX_DN<2>!U7C1!K50!@baseboard_fab2_lib.baseboard_fab2(sch_1):page117_i9@chpset_lib.lbg_core_qat_ext_c(chips)!LBG_CORE_QAT_EXT_C_BGA1-IC,TBD!!!F2052!DMI_TXN(2)!!!!
S!DMI_CPU0_PCH_RX_DN<3>!U7C1!P52!@baseboard_fab2_lib.baseboard_fab2(sch_1):page117_i9@chpset_lib.lbg_core_qat_ext_c(chips)!LBG_CORE_QAT_EXT_C_BGA1-IC,TBD!!!F2052!DMI_TXN(3)!!!!
S!DMI_CPU0_PCH_RX_DP<0>!U7C1!K46!@baseboard_fab2_lib.baseboard_fab2(sch_1):page117_i9@chpset_lib.lbg_core_qat_ext_c(chips)!LBG_CORE_QAT_EXT_C_BGA1-IC,TBD!!!F2052!DMI_TXP(0)!!!!
S!DMI_CPU0_PCH_RX_DP<1>!U7C1!H50!@baseboard_fab2_lib.baseboard_fab2(sch_1):page117_i9@chpset_lib.lbg_core_qat_ext_c(chips)!LBG_CORE_QAT_EXT_C_BGA1-IC,TBD!!!F2052!DMI_TXP(1)!!!!
S!DMI_CPU0_PCH_RX_DP<2>!U7C1!M52!@baseboard_fab2_lib.baseboard_fab2(sch_1):page117_i9@chpset_lib.lbg_core_qat_ext_c(chips)!LBG_CORE_QAT_EXT_C_BGA1-IC,TBD!!!F2052!DMI_TXP(2)!!!!
S!DMI_CPU0_PCH_RX_DP<3>!U7C1!N54!@baseboard_fab2_lib.baseboard_fab2(sch_1):page117_i9@chpset_lib.lbg_core_qat_ext_c(chips)!LBG_CORE_QAT_EXT_C_BGA1-IC,TBD!!!F2052!DMI_TXP(3)!!!!
S!P3E_CPU0_PE1_PCH_TXN<0>!U7C1!C48!@baseboard_fab2_lib.baseboard_fab2(sch_1):page117_i9@chpset_lib.lbg_core_qat_ext_c(chips)!LBG_CORE_QAT_EXT_C_BGA1-IC,TBD!!!F2052!PCIEUP_0_RXN!!!!
S!P3E_CPU0_PE1_PCH_TXP<0>!U7C1!A48!@baseboard_fab2_lib.baseboard_fab2(sch_1):page117_i9@chpset_lib.lbg_core_qat_ext_c(chips)!LBG_CORE_QAT_EXT_C_BGA1-IC,TBD!!!F2052!PCIEUP_0_RXP!!!!
S!P3E_CPU0_PE1_PCH_RXN<0>!U7C1!J52!@baseboard_fab2_lib.baseboard_fab2(sch_1):page117_i9@chpset_lib.lbg_core_qat_ext_c(chips)!LBG_CORE_QAT_EXT_C_BGA1-IC,TBD!!!F2052!PCIEUP_0_TXN!!!!
S!P3E_CPU0_PE1_PCH_RXP<0>!U7C1!G52!@baseboard_fab2_lib.baseboard_fab2(sch_1):page117_i9@chpset_lib.lbg_core_qat_ext_c(chips)!LBG_CORE_QAT_EXT_C_BGA1-IC,TBD!!!F2052!PCIEUP_0_TXP!!!!
S!P3E_CPU0_PE1_PCH_C_TXP<10>!U7C1!C59!@baseboard_fab2_lib.baseboard_fab2(sch_1):page117_i9@chpset_lib.lbg_core_qat_ext_c(chips)!LBG_CORE_QAT_EXT_C_BGA1-IC,TBD!!!F2052!PCIEUP_10_RXN!!!!
S!P3E_CPU0_PE1_PCH_C_TXN<10>!U7C1!A59!@baseboard_fab2_lib.baseboard_fab2(sch_1):page117_i9@chpset_lib.lbg_core_qat_ext_c(chips)!LBG_CORE_QAT_EXT_C_BGA1-IC,TBD!!!F2052!PCIEUP_10_RXP!!!!
S!P3E_CPU0_PE1_PCH_R_RXN<10>!U7C1!N65!@baseboard_fab2_lib.baseboard_fab2(sch_1):page117_i9@chpset_lib.lbg_core_qat_ext_c(chips)!LBG_CORE_QAT_EXT_C_BGA1-IC,TBD!!!F2052!PCIEUP_10_TXN!!!!
S!P3E_CPU0_PE1_PCH_R_RXP<10>!U7C1!P66!@baseboard_fab2_lib.baseboard_fab2(sch_1):page117_i9@chpset_lib.lbg_core_qat_ext_c(chips)!LBG_CORE_QAT_EXT_C_BGA1-IC,TBD!!!F2052!PCIEUP_10_TXP!!!!
S!P3E_CPU0_PE1_PCH_C_TXN<11>!U7C1!D60!@baseboard_fab2_lib.baseboard_fab2(sch_1):page117_i9@chpset_lib.lbg_core_qat_ext_c(chips)!LBG_CORE_QAT_EXT_C_BGA1-IC,TBD!!!F2052!PCIEUP_11_RXN!!!!
S!P3E_CPU0_PE1_PCH_C_TXP<11>!U7C1!B60!@baseboard_fab2_lib.baseboard_fab2(sch_1):page117_i9@chpset_lib.lbg_core_qat_ext_c(chips)!LBG_CORE_QAT_EXT_C_BGA1-IC,TBD!!!F2052!PCIEUP_11_RXP!!!!
S!P3E_CPU0_PE1_PCH_R_RXN<11>!U7C1!T59!@baseboard_fab2_lib.baseboard_fab2(sch_1):page117_i9@chpset_lib.lbg_core_qat_ext_c(chips)!LBG_CORE_QAT_EXT_C_BGA1-IC,TBD!!!F2052!PCIEUP_11_TXN!!!!
S!P3E_CPU0_PE1_PCH_R_RXP<11>!U7C1!V59!@baseboard_fab2_lib.baseboard_fab2(sch_1):page117_i9@chpset_lib.lbg_core_qat_ext_c(chips)!LBG_CORE_QAT_EXT_C_BGA1-IC,TBD!!!F2052!PCIEUP_11_TXP!!!!
S!P3E_CPU0_PE1_PCH_C_TXP<12>!U7C1!C61!@baseboard_fab2_lib.baseboard_fab2(sch_1):page117_i9@chpset_lib.lbg_core_qat_ext_c(chips)!LBG_CORE_QAT_EXT_C_BGA1-IC,TBD!!!F2052!PCIEUP_12_RXN!!!!
S!P3E_CPU0_PE1_PCH_C_TXN<12>!U7C1!A61!@baseboard_fab2_lib.baseboard_fab2(sch_1):page117_i9@chpset_lib.lbg_core_qat_ext_c(chips)!LBG_CORE_QAT_EXT_C_BGA1-IC,TBD!!!F2052!PCIEUP_12_RXP!!!!
S!P3E_CPU0_PE1_PCH_R_RXN<12>!U7C1!R65!@baseboard_fab2_lib.baseboard_fab2(sch_1):page117_i9@chpset_lib.lbg_core_qat_ext_c(chips)!LBG_CORE_QAT_EXT_C_BGA1-IC,TBD!!!F2052!PCIEUP_12_TXN!!!!
S!P3E_CPU0_PE1_PCH_R_RXP<12>!U7C1!U65!@baseboard_fab2_lib.baseboard_fab2(sch_1):page117_i9@chpset_lib.lbg_core_qat_ext_c(chips)!LBG_CORE_QAT_EXT_C_BGA1-IC,TBD!!!F2052!PCIEUP_12_TXP!!!!
S!P3E_CPU0_PE1_PCH_C_TXP<13>!U7C1!D62!@baseboard_fab2_lib.baseboard_fab2(sch_1):page117_i9@chpset_lib.lbg_core_qat_ext_c(chips)!LBG_CORE_QAT_EXT_C_BGA1-IC,TBD!!!F2052!PCIEUP_13_RXN!!!!
S!P3E_CPU0_PE1_PCH_C_TXN<13>!U7C1!B62!@baseboard_fab2_lib.baseboard_fab2(sch_1):page117_i9@chpset_lib.lbg_core_qat_ext_c(chips)!LBG_CORE_QAT_EXT_C_BGA1-IC,TBD!!!F2052!PCIEUP_13_RXP!!!!
S!P3E_CPU0_PE1_PCH_R_RXN<13>!U7C1!T63!@baseboard_fab2_lib.baseboard_fab2(sch_1):page117_i9@chpset_lib.lbg_core_qat_ext_c(chips)!LBG_CORE_QAT_EXT_C_BGA1-IC,TBD!!!F2052!PCIEUP_13_TXN!!!!
S!P3E_CPU0_PE1_PCH_R_RXP<13>!U7C1!U61!@baseboard_fab2_lib.baseboard_fab2(sch_1):page117_i9@chpset_lib.lbg_core_qat_ext_c(chips)!LBG_CORE_QAT_EXT_C_BGA1-IC,TBD!!!F2052!PCIEUP_13_TXP!!!!
S!P3E_CPU0_PE1_PCH_C_TXP<14>!U7C1!C63!@baseboard_fab2_lib.baseboard_fab2(sch_1):page117_i9@chpset_lib.lbg_core_qat_ext_c(chips)!LBG_CORE_QAT_EXT_C_BGA1-IC,TBD!!!F2052!PCIEUP_14_RXN!!!!
S!P3E_CPU0_PE1_PCH_C_TXN<14>!U7C1!A63!@baseboard_fab2_lib.baseboard_fab2(sch_1):page117_i9@chpset_lib.lbg_core_qat_ext_c(chips)!LBG_CORE_QAT_EXT_C_BGA1-IC,TBD!!!F2052!PCIEUP_14_RXP!!!!
S!P3E_CPU0_PE1_PCH_R_RXN<14>!U7C1!W65!@baseboard_fab2_lib.baseboard_fab2(sch_1):page117_i9@chpset_lib.lbg_core_qat_ext_c(chips)!LBG_CORE_QAT_EXT_C_BGA1-IC,TBD!!!F2052!PCIEUP_14_TXN!!!!
S!P3E_CPU0_PE1_PCH_R_RXP<14>!U7C1!V63!@baseboard_fab2_lib.baseboard_fab2(sch_1):page117_i9@chpset_lib.lbg_core_qat_ext_c(chips)!LBG_CORE_QAT_EXT_C_BGA1-IC,TBD!!!F2052!PCIEUP_14_TXP!!!!
S!P3E_CPU0_PE1_PCH_C_TXP<15>!U7C1!D64!@baseboard_fab2_lib.baseboard_fab2(sch_1):page117_i9@chpset_lib.lbg_core_qat_ext_c(chips)!LBG_CORE_QAT_EXT_C_BGA1-IC,TBD!!!F2052!PCIEUP_15_RXN!!!!
S!P3E_CPU0_PE1_PCH_C_TXN<15>!U7C1!B64!@baseboard_fab2_lib.baseboard_fab2(sch_1):page117_i9@chpset_lib.lbg_core_qat_ext_c(chips)!LBG_CORE_QAT_EXT_C_BGA1-IC,TBD!!!F2052!PCIEUP_15_RXP!!!!
S!P3E_CPU0_PE1_PCH_R_RXN<15>!U7C1!Y66!@baseboard_fab2_lib.baseboard_fab2(sch_1):page117_i9@chpset_lib.lbg_core_qat_ext_c(chips)!LBG_CORE_QAT_EXT_C_BGA1-IC,TBD!!!F2052!PCIEUP_15_TXN!!!!
S!P3E_CPU0_PE1_PCH_R_RXP<15>!U7C1!AA65!@baseboard_fab2_lib.baseboard_fab2(sch_1):page117_i9@chpset_lib.lbg_core_qat_ext_c(chips)!LBG_CORE_QAT_EXT_C_BGA1-IC,TBD!!!F2052!PCIEUP_15_TXP!!!!
S!P3E_CPU0_PE1_PCH_TXN<1>!U7C1!D49!@baseboard_fab2_lib.baseboard_fab2(sch_1):page117_i9@chpset_lib.lbg_core_qat_ext_c(chips)!LBG_CORE_QAT_EXT_C_BGA1-IC,TBD!!!F2052!PCIEUP_1_RXN!!!!
S!P3E_CPU0_PE1_PCH_TXP<1>!U7C1!B49!@baseboard_fab2_lib.baseboard_fab2(sch_1):page117_i9@chpset_lib.lbg_core_qat_ext_c(chips)!LBG_CORE_QAT_EXT_C_BGA1-IC,TBD!!!F2052!PCIEUP_1_RXP!!!!
S!P3E_CPU0_PE1_PCH_RXN<1>!U7C1!P56!@baseboard_fab2_lib.baseboard_fab2(sch_1):page117_i9@chpset_lib.lbg_core_qat_ext_c(chips)!LBG_CORE_QAT_EXT_C_BGA1-IC,TBD!!!F2052!PCIEUP_1_TXN!!!!
S!P3E_CPU0_PE1_PCH_RXP<1>!U7C1!M56!@baseboard_fab2_lib.baseboard_fab2(sch_1):page117_i9@chpset_lib.lbg_core_qat_ext_c(chips)!LBG_CORE_QAT_EXT_C_BGA1-IC,TBD!!!F2052!PCIEUP_1_TXP!!!!
S!P3E_CPU0_PE1_PCH_TXN<2>!U7C1!C50!@baseboard_fab2_lib.baseboard_fab2(sch_1):page117_i9@chpset_lib.lbg_core_qat_ext_c(chips)!LBG_CORE_QAT_EXT_C_BGA1-IC,TBD!!!F2052!PCIEUP_2_RXN!!!!
S!P3E_CPU0_PE1_PCH_TXP<2>!U7C1!A50!@baseboard_fab2_lib.baseboard_fab2(sch_1):page117_i9@chpset_lib.lbg_core_qat_ext_c(chips)!LBG_CORE_QAT_EXT_C_BGA1-IC,TBD!!!F2052!PCIEUP_2_RXP!!!!
S!P3E_CPU0_PE1_PCH_RXN<2>!U7C1!H54!@baseboard_fab2_lib.baseboard_fab2(sch_1):page117_i9@chpset_lib.lbg_core_qat_ext_c(chips)!LBG_CORE_QAT_EXT_C_BGA1-IC,TBD!!!F2052!PCIEUP_2_TXN!!!!
S!P3E_CPU0_PE1_PCH_RXP<2>!U7C1!G56!@baseboard_fab2_lib.baseboard_fab2(sch_1):page117_i9@chpset_lib.lbg_core_qat_ext_c(chips)!LBG_CORE_QAT_EXT_C_BGA1-IC,TBD!!!F2052!PCIEUP_2_TXP!!!!
S!P3E_CPU0_PE1_PCH_TXN<3>!U7C1!D51!@baseboard_fab2_lib.baseboard_fab2(sch_1):page117_i9@chpset_lib.lbg_core_qat_ext_c(chips)!LBG_CORE_QAT_EXT_C_BGA1-IC,TBD!!!F2052!PCIEUP_3_RXN!!!!
S!P3E_CPU0_PE1_PCH_TXP<3>!U7C1!B51!@baseboard_fab2_lib.baseboard_fab2(sch_1):page117_i9@chpset_lib.lbg_core_qat_ext_c(chips)!LBG_CORE_QAT_EXT_C_BGA1-IC,TBD!!!F2052!PCIEUP_3_RXP!!!!
S!P3E_CPU0_PE1_PCH_RXN<3>!U7C1!J56!@baseboard_fab2_lib.baseboard_fab2(sch_1):page117_i9@chpset_lib.lbg_core_qat_ext_c(chips)!LBG_CORE_QAT_EXT_C_BGA1-IC,TBD!!!F2052!PCIEUP_3_TXN!!!!
S!P3E_CPU0_PE1_PCH_RXP<3>!U7C1!K58!@baseboard_fab2_lib.baseboard_fab2(sch_1):page117_i9@chpset_lib.lbg_core_qat_ext_c(chips)!LBG_CORE_QAT_EXT_C_BGA1-IC,TBD!!!F2052!PCIEUP_3_TXP!!!!
S!P3E_CPU0_PE1_PCH_TXN<4>!U7C1!C52!@baseboard_fab2_lib.baseboard_fab2(sch_1):page117_i9@chpset_lib.lbg_core_qat_ext_c(chips)!LBG_CORE_QAT_EXT_C_BGA1-IC,TBD!!!F2052!PCIEUP_4_RXN!!!!
S!P3E_CPU0_PE1_PCH_TXP<4>!U7C1!A52!@baseboard_fab2_lib.baseboard_fab2(sch_1):page117_i9@chpset_lib.lbg_core_qat_ext_c(chips)!LBG_CORE_QAT_EXT_C_BGA1-IC,TBD!!!F2052!PCIEUP_4_RXP!!!!
S!P3E_CPU0_PE1_PCH_RXN<4>!U7C1!N58!@baseboard_fab2_lib.baseboard_fab2(sch_1):page117_i9@chpset_lib.lbg_core_qat_ext_c(chips)!LBG_CORE_QAT_EXT_C_BGA1-IC,TBD!!!F2052!PCIEUP_4_TXN!!!!
S!P3E_CPU0_PE1_PCH_RXP<4>!U7C1!M59!@baseboard_fab2_lib.baseboard_fab2(sch_1):page117_i9@chpset_lib.lbg_core_qat_ext_c(chips)!LBG_CORE_QAT_EXT_C_BGA1-IC,TBD!!!F2052!PCIEUP_4_TXP!!!!
S!P3E_CPU0_PE1_PCH_TXN<5>!U7C1!D53!@baseboard_fab2_lib.baseboard_fab2(sch_1):page117_i9@chpset_lib.lbg_core_qat_ext_c(chips)!LBG_CORE_QAT_EXT_C_BGA1-IC,TBD!!!F2052!PCIEUP_5_RXN!!!!
S!P3E_CPU0_PE1_PCH_TXP<5>!U7C1!B53!@baseboard_fab2_lib.baseboard_fab2(sch_1):page117_i9@chpset_lib.lbg_core_qat_ext_c(chips)!LBG_CORE_QAT_EXT_C_BGA1-IC,TBD!!!F2052!PCIEUP_5_RXP!!!!
S!P3E_CPU0_PE1_PCH_RXN<5>!U7C1!N61!@baseboard_fab2_lib.baseboard_fab2(sch_1):page117_i9@chpset_lib.lbg_core_qat_ext_c(chips)!LBG_CORE_QAT_EXT_C_BGA1-IC,TBD!!!F2052!PCIEUP_5_TXN!!!!
S!P3E_CPU0_PE1_PCH_RXP<5>!U7C1!K61!@baseboard_fab2_lib.baseboard_fab2(sch_1):page117_i9@chpset_lib.lbg_core_qat_ext_c(chips)!LBG_CORE_QAT_EXT_C_BGA1-IC,TBD!!!F2052!PCIEUP_5_TXP!!!!
S!P3E_CPU0_PE1_PCH_TXN<6>!U7C1!C54!@baseboard_fab2_lib.baseboard_fab2(sch_1):page117_i9@chpset_lib.lbg_core_qat_ext_c(chips)!LBG_CORE_QAT_EXT_C_BGA1-IC,TBD!!!F2052!PCIEUP_6_RXN!!!!
S!P3E_CPU0_PE1_PCH_TXP<6>!U7C1!A54!@baseboard_fab2_lib.baseboard_fab2(sch_1):page117_i9@chpset_lib.lbg_core_qat_ext_c(chips)!LBG_CORE_QAT_EXT_C_BGA1-IC,TBD!!!F2052!PCIEUP_6_RXP!!!!
S!P3E_CPU0_PE1_PCH_RXN<6>!U7C1!H61!@baseboard_fab2_lib.baseboard_fab2(sch_1):page117_i9@chpset_lib.lbg_core_qat_ext_c(chips)!LBG_CORE_QAT_EXT_C_BGA1-IC,TBD!!!F2052!PCIEUP_6_TXN!!!!
S!P3E_CPU0_PE1_PCH_RXP<6>!U7C1!J63!@baseboard_fab2_lib.baseboard_fab2(sch_1):page117_i9@chpset_lib.lbg_core_qat_ext_c(chips)!LBG_CORE_QAT_EXT_C_BGA1-IC,TBD!!!F2052!PCIEUP_6_TXP!!!!
S!P3E_CPU0_PE1_PCH_TXN<7>!U7C1!D55!@baseboard_fab2_lib.baseboard_fab2(sch_1):page117_i9@chpset_lib.lbg_core_qat_ext_c(chips)!LBG_CORE_QAT_EXT_C_BGA1-IC,TBD!!!F2052!PCIEUP_7_RXN!!!!
S!P3E_CPU0_PE1_PCH_TXP<7>!U7C1!B55!@baseboard_fab2_lib.baseboard_fab2(sch_1):page117_i9@chpset_lib.lbg_core_qat_ext_c(chips)!LBG_CORE_QAT_EXT_C_BGA1-IC,TBD!!!F2052!PCIEUP_7_RXP!!!!
S!P3E_CPU0_PE1_PCH_RXN<7>!U7C1!P59!@baseboard_fab2_lib.baseboard_fab2(sch_1):page117_i9@chpset_lib.lbg_core_qat_ext_c(chips)!LBG_CORE_QAT_EXT_C_BGA1-IC,TBD!!!F2052!PCIEUP_7_TXN!!!!
S!P3E_CPU0_PE1_PCH_RXP<7>!U7C1!R61!@baseboard_fab2_lib.baseboard_fab2(sch_1):page117_i9@chpset_lib.lbg_core_qat_ext_c(chips)!LBG_CORE_QAT_EXT_C_BGA1-IC,TBD!!!F2052!PCIEUP_7_TXP!!!!
S!P3E_CPU0_PE1_PCH_C_TXP<8>!U7C1!C57!@baseboard_fab2_lib.baseboard_fab2(sch_1):page117_i9@chpset_lib.lbg_core_qat_ext_c(chips)!LBG_CORE_QAT_EXT_C_BGA1-IC,TBD!!!F2052!PCIEUP_8_RXN!!!!
S!P3E_CPU0_PE1_PCH_C_TXN<8>!U7C1!A57!@baseboard_fab2_lib.baseboard_fab2(sch_1):page117_i9@chpset_lib.lbg_core_qat_ext_c(chips)!LBG_CORE_QAT_EXT_C_BGA1-IC,TBD!!!F2052!PCIEUP_8_RXP!!!!
S!P3E_CPU0_PE1_PCH_R_RXN<8>!U7C1!K65!@baseboard_fab2_lib.baseboard_fab2(sch_1):page117_i9@chpset_lib.lbg_core_qat_ext_c(chips)!LBG_CORE_QAT_EXT_C_BGA1-IC,TBD!!!F2052!PCIEUP_8_TXN!!!!
S!P3E_CPU0_PE1_PCH_R_RXP<8>!U7C1!M63!@baseboard_fab2_lib.baseboard_fab2(sch_1):page117_i9@chpset_lib.lbg_core_qat_ext_c(chips)!LBG_CORE_QAT_EXT_C_BGA1-IC,TBD!!!F2052!PCIEUP_8_TXP!!!!
S!P3E_CPU0_PE1_PCH_C_TXP<9>!U7C1!D58!@baseboard_fab2_lib.baseboard_fab2(sch_1):page117_i9@chpset_lib.lbg_core_qat_ext_c(chips)!LBG_CORE_QAT_EXT_C_BGA1-IC,TBD!!!F2052!PCIEUP_9_RXN!!!!
S!P3E_CPU0_PE1_PCH_C_TXN<9>!U7C1!B58!@baseboard_fab2_lib.baseboard_fab2(sch_1):page117_i9@chpset_lib.lbg_core_qat_ext_c(chips)!LBG_CORE_QAT_EXT_C_BGA1-IC,TBD!!!F2052!PCIEUP_9_RXP!!!!
S!P3E_CPU0_PE1_PCH_R_RXN<9>!U7C1!J66!@baseboard_fab2_lib.baseboard_fab2(sch_1):page117_i9@chpset_lib.lbg_core_qat_ext_c(chips)!LBG_CORE_QAT_EXT_C_BGA1-IC,TBD!!!F2052!PCIEUP_9_TXN!!!!
S!P3E_CPU0_PE1_PCH_R_RXP<9>!U7C1!M66!@baseboard_fab2_lib.baseboard_fab2(sch_1):page117_i9@chpset_lib.lbg_core_qat_ext_c(chips)!LBG_CORE_QAT_EXT_C_BGA1-IC,TBD!!!F2052!PCIEUP_9_TXP!!!!
S!XDP_TRST_N!U7C1!AT56!@baseboard_fab2_lib.baseboard_fab2(sch_1):page118_i73@chpset_lib.lbg_core_qat_ext_c(chips)!LBG_CORE_QAT_EXT_C_BGA1-IC,TBD!!!F2051!CPU_TRST_N!!!!
S!PWRGD_DSW_PWROK!U7C1!K13!@baseboard_fab2_lib.baseboard_fab2(sch_1):page118_i73@chpset_lib.lbg_core_qat_ext_c(chips)!LBG_CORE_QAT_EXT_C_BGA1-IC,TBD!!!F2051!DSW_PWROK!!!!
S!XDP_PCH_PWR_DEBUG_N!U7C1!G15!@baseboard_fab2_lib.baseboard_fab2(sch_1):page118_i73@chpset_lib.lbg_core_qat_ext_c(chips)!LBG_CORE_QAT_EXT_C_BGA1-IC,TBD!!!F2051!GPD0!!!!
S!RST_PCH_SYSRST_BTN_OUT_N!U7C1!B14!@baseboard_fab2_lib.baseboard_fab2(sch_1):page118_i73@chpset_lib.lbg_core_qat_ext_c(chips)!LBG_CORE_QAT_EXT_C_BGA1-IC,TBD!!!F2051!GPD10_SLP_S5_N!!!!
S!FM_GBE_LOM_DISABLE_N!U7C1!A13!@baseboard_fab2_lib.baseboard_fab2(sch_1):page118_i73@chpset_lib.lbg_core_qat_ext_c(chips)!LBG_CORE_QAT_EXT_C_BGA1-IC,TBD!!!F2051!GPD11_GBEPHY!!!!
S!FM_CPU1_SKTOCC_LVT3_N!U7C1!H13!@baseboard_fab2_lib.baseboard_fab2(sch_1):page118_i73@chpset_lib.lbg_core_qat_ext_c(chips)!LBG_CORE_QAT_EXT_C_BGA1-IC,TBD!!!F2051!GPD1_ACPRESENT!!!!
S!RST_BMC_SRST_R_N!U7C1!M11!@baseboard_fab2_lib.baseboard_fab2(sch_1):page118_i73@chpset_lib.lbg_core_qat_ext_c(chips)!LBG_CORE_QAT_EXT_C_BGA1-IC,TBD!!!F2051!GPD2_GBE_WAKE_N!!!!
S!FM_PCH_PWRBTN_N!U7C1!C15!@baseboard_fab2_lib.baseboard_fab2(sch_1):page118_i73@chpset_lib.lbg_core_qat_ext_c(chips)!LBG_CORE_QAT_EXT_C_BGA1-IC,TBD!!!F2051!GPD3_PWRBTN_N!!!!
S!FM_SLPS3_N!U7C1!D14!@baseboard_fab2_lib.baseboard_fab2(sch_1):page118_i73@chpset_lib.lbg_core_qat_ext_c(chips)!LBG_CORE_QAT_EXT_C_BGA1-IC,TBD!!!F2051!GPD4_SLP_S3_N!!!!
S!FM_SLPS4_N!U7C1!B16!@baseboard_fab2_lib.baseboard_fab2(sch_1):page118_i73@chpset_lib.lbg_core_qat_ext_c(chips)!LBG_CORE_QAT_EXT_C_BGA1-IC,TBD!!!F2051!GPD5_SLP_S4_N!!!!
S!FM_CPU0_SKTOCC_LVT3_N!U7C1!G11!@baseboard_fab2_lib.baseboard_fab2(sch_1):page118_i73@chpset_lib.lbg_core_qat_ext_c(chips)!LBG_CORE_QAT_EXT_C_BGA1-IC,TBD!!!F2051!GPD6_SLP_A_N!!!!
S!FM_BATTERY_SENSE_EN_N!U7C1!H9!@baseboard_fab2_lib.baseboard_fab2(sch_1):page118_i73@chpset_lib.lbg_core_qat_ext_c(chips)!LBG_CORE_QAT_EXT_C_BGA1-IC,TBD!!!F2051!GPD7!!!!
S!IRQ_SML1_PMBUS_ALERT_N!U7C1!C13!@baseboard_fab2_lib.baseboard_fab2(sch_1):page118_i73@chpset_lib.lbg_core_qat_ext_c(chips)!LBG_CORE_QAT_EXT_C_BGA1-IC,TBD!!!F2051!GPD8_SUSCLK!!!!
S!FM_BMC_CPLD_MP_RST_N!U7C1!A15!@baseboard_fab2_lib.baseboard_fab2(sch_1):page118_i73@chpset_lib.lbg_core_qat_ext_c(chips)!LBG_CORE_QAT_EXT_C_BGA1-IC,TBD!!!F2051!GPD9!!!!
S!XDP_ITP_PMODE!U7C1!AR54!@baseboard_fab2_lib.baseboard_fab2(sch_1):page118_i73@chpset_lib.lbg_core_qat_ext_c(chips)!LBG_CORE_QAT_EXT_C_BGA1-IC,TBD!!!F2051!ITP_PMODE!!!!
S!XDP_PCH_CPU_TCK0!U7C1!AF54!@baseboard_fab2_lib.baseboard_fab2(sch_1):page118_i73@chpset_lib.lbg_core_qat_ext_c(chips)!LBG_CORE_QAT_EXT_C_BGA1-IC,TBD!!!F2051!JTAGX!!!!
S!XDP_PCH_TCK1!U7C1!AL56!@baseboard_fab2_lib.baseboard_fab2(sch_1):page118_i73@chpset_lib.lbg_core_qat_ext_c(chips)!LBG_CORE_QAT_EXT_C_BGA1-IC,TBD!!!F2051!JTAG_TCK!!!!
S!XDP_TDI!U7C1!AN54!@baseboard_fab2_lib.baseboard_fab2(sch_1):page118_i73@chpset_lib.lbg_core_qat_ext_c(chips)!LBG_CORE_QAT_EXT_C_BGA1-IC,TBD!!!F2051!JTAG_TDI!!!!
S!XDP_TDO!U7C1!AP56!@baseboard_fab2_lib.baseboard_fab2(sch_1):page118_i73@chpset_lib.lbg_core_qat_ext_c(chips)!LBG_CORE_QAT_EXT_C_BGA1-IC,TBD!!!F2051!JTAG_TDO!!!!
S!XDP_TMS!U7C1!AH54!@baseboard_fab2_lib.baseboard_fab2(sch_1):page118_i73@chpset_lib.lbg_core_qat_ext_c(chips)!LBG_CORE_QAT_EXT_C_BGA1-IC,TBD!!!F2051!JTAG_TMS!!!!
S!A_KR0_RBIAS!U7C1!BB29!@baseboard_fab2_lib.baseboard_fab2(sch_1):page118_i73@chpset_lib.lbg_core_qat_ext_c(chips)!LBG_CORE_QAT_EXT_C_BGA1-IC,TBD!!!F2051!LAN_RBIAS_0!!!!
S!A_KR1_RBIAS!U7C1!BD42!@baseboard_fab2_lib.baseboard_fab2(sch_1):page118_i73@chpset_lib.lbg_core_qat_ext_c(chips)!LBG_CORE_QAT_EXT_C_BGA1-IC,TBD!!!F2051!LAN_RBIAS_1!!!!
S!KR_P0_OCP_RX_C_DN!U7C1!BH31!@baseboard_fab2_lib.baseboard_fab2(sch_1):page118_i73@chpset_lib.lbg_core_qat_ext_c(chips)!LBG_CORE_QAT_EXT_C_BGA1-IC,TBD!!!F2051!LAN_RX_P0N!!!!
S!KR_P0_OCP_RX_C_DP!U7C1!BF31!@baseboard_fab2_lib.baseboard_fab2(sch_1):page118_i73@chpset_lib.lbg_core_qat_ext_c(chips)!LBG_CORE_QAT_EXT_C_BGA1-IC,TBD!!!F2051!LAN_RX_P0P!!!!
S!KR_P1_OCP_RX_C_DN!U7C1!BG29!@baseboard_fab2_lib.baseboard_fab2(sch_1):page118_i73@chpset_lib.lbg_core_qat_ext_c(chips)!LBG_CORE_QAT_EXT_C_BGA1-IC,TBD!!!F2051!LAN_RX_P1N!!!!
S!KR_P1_OCP_RX_C_DP!U7C1!BJ29!@baseboard_fab2_lib.baseboard_fab2(sch_1):page118_i73@chpset_lib.lbg_core_qat_ext_c(chips)!LBG_CORE_QAT_EXT_C_BGA1-IC,TBD!!!F2051!LAN_RX_P1P!!!!
S!KR_P2_OCP_RX_C_DN!U7C1!BJ37!@baseboard_fab2_lib.baseboard_fab2(sch_1):page118_i73@chpset_lib.lbg_core_qat_ext_c(chips)!LBG_CORE_QAT_EXT_C_BGA1-IC,TBD!!!F2051!LAN_RX_P2N!!!!
S!KR_P2_OCP_RX_C_DP!U7C1!BG37!@baseboard_fab2_lib.baseboard_fab2(sch_1):page118_i73@chpset_lib.lbg_core_qat_ext_c(chips)!LBG_CORE_QAT_EXT_C_BGA1-IC,TBD!!!F2051!LAN_RX_P2P!!!!
S!KR_P3_OCP_RX_C_DN!U7C1!BF35!@baseboard_fab2_lib.baseboard_fab2(sch_1):page118_i73@chpset_lib.lbg_core_qat_ext_c(chips)!LBG_CORE_QAT_EXT_C_BGA1-IC,TBD!!!F2051!LAN_RX_P3N!!!!
S!KR_P3_OCP_RX_C_DP!U7C1!BH35!@baseboard_fab2_lib.baseboard_fab2(sch_1):page118_i73@chpset_lib.lbg_core_qat_ext_c(chips)!LBG_CORE_QAT_EXT_C_BGA1-IC,TBD!!!F2051!LAN_RX_P3P!!!!
S!KR_P0_OCP_TX_DN!U7C1!BM27!@baseboard_fab2_lib.baseboard_fab2(sch_1):page118_i73@chpset_lib.lbg_core_qat_ext_c(chips)!LBG_CORE_QAT_EXT_C_BGA1-IC,TBD!!!F2051!LAN_TX_P0N!!!!
S!KR_P0_OCP_TX_DP!U7C1!BR27!@baseboard_fab2_lib.baseboard_fab2(sch_1):page118_i73@chpset_lib.lbg_core_qat_ext_c(chips)!LBG_CORE_QAT_EXT_C_BGA1-IC,TBD!!!F2051!LAN_TX_P0P!!!!
S!KR_P1_OCP_TX_DN!U7C1!BM24!@baseboard_fab2_lib.baseboard_fab2(sch_1):page118_i73@chpset_lib.lbg_core_qat_ext_c(chips)!LBG_CORE_QAT_EXT_C_BGA1-IC,TBD!!!F2051!LAN_TX_P1N!!!!
S!KR_P1_OCP_TX_DP!U7C1!BR24!@baseboard_fab2_lib.baseboard_fab2(sch_1):page118_i73@chpset_lib.lbg_core_qat_ext_c(chips)!LBG_CORE_QAT_EXT_C_BGA1-IC,TBD!!!F2051!LAN_TX_P1P!!!!
S!KR_P2_OCP_TX_DN!U7C1!BM35!@baseboard_fab2_lib.baseboard_fab2(sch_1):page118_i73@chpset_lib.lbg_core_qat_ext_c(chips)!LBG_CORE_QAT_EXT_C_BGA1-IC,TBD!!!F2051!LAN_TX_P2N!!!!
S!KR_P2_OCP_TX_DP!U7C1!BR35!@baseboard_fab2_lib.baseboard_fab2(sch_1):page118_i73@chpset_lib.lbg_core_qat_ext_c(chips)!LBG_CORE_QAT_EXT_C_BGA1-IC,TBD!!!F2051!LAN_TX_P2P!!!!
S!KR_P3_OCP_TX_DN!U7C1!BR31!@baseboard_fab2_lib.baseboard_fab2(sch_1):page118_i73@chpset_lib.lbg_core_qat_ext_c(chips)!LBG_CORE_QAT_EXT_C_BGA1-IC,TBD!!!F2051!LAN_TX_P3N!!!!
S!KR_P3_OCP_TX_DP!U7C1!BM31!@baseboard_fab2_lib.baseboard_fab2(sch_1):page118_i73@chpset_lib.lbg_core_qat_ext_c(chips)!LBG_CORE_QAT_EXT_C_BGA1-IC,TBD!!!F2051!LAN_TX_P3P!!!!
S!XTAL_KR_25M_IN!U7C1!BV16!@baseboard_fab2_lib.baseboard_fab2(sch_1):page118_i73@chpset_lib.lbg_core_qat_ext_c(chips)!LBG_CORE_QAT_EXT_C_BGA1-IC,TBD!!!F2051!LAN_XTAL_IN!!!!
S!XTAL_KR_25M_OUT!U7C1!BY16!@baseboard_fab2_lib.baseboard_fab2(sch_1):page118_i73@chpset_lib.lbg_core_qat_ext_c(chips)!LBG_CORE_QAT_EXT_C_BGA1-IC,TBD!!!F2051!LAN_XTAL_OUT!!!!
S!PWRGD_PCH_PWROK!U7C1!R17!@baseboard_fab2_lib.baseboard_fab2(sch_1):page118_i73@chpset_lib.lbg_core_qat_ext_c(chips)!LBG_CORE_QAT_EXT_C_BGA1-IC,TBD!!!F2051!PCH_PWROK!!!!
S!PECI_PCH!U7C1!U9!@baseboard_fab2_lib.baseboard_fab2(sch_1):page118_i73@chpset_lib.lbg_core_qat_ext_c(chips)!LBG_CORE_QAT_EXT_C_BGA1-IC,TBD!!!F2051!PECI!!!!
S!TP_PLTRST_CPU_N!U7C1!U17!@baseboard_fab2_lib.baseboard_fab2(sch_1):page118_i73@chpset_lib.lbg_core_qat_ext_c(chips)!LBG_CORE_QAT_EXT_C_BGA1-IC,TBD!!!F2051!PLTRST_CPU_N!!!!
S!H_PM_SYNC1_GTL_R!U7C1!U13!@baseboard_fab2_lib.baseboard_fab2(sch_1):page118_i73@chpset_lib.lbg_core_qat_ext_c(chips)!LBG_CORE_QAT_EXT_C_BGA1-IC,TBD!!!F2051!PM_SYNC!!!!
S!TP_PM_SYNC_GTL!U7C1!V7!@baseboard_fab2_lib.baseboard_fab2(sch_1):page118_i73@chpset_lib.lbg_core_qat_ext_c(chips)!LBG_CORE_QAT_EXT_C_BGA1-IC,TBD!!!F2051!PM_SYNC2!!!!
S!XDP_PRDY_N!U7C1!AD54!@baseboard_fab2_lib.baseboard_fab2(sch_1):page118_i73@chpset_lib.lbg_core_qat_ext_c(chips)!LBG_CORE_QAT_EXT_C_BGA1-IC,TBD!!!F2051!PRDY_N!!!!
S!XDP_PREQ_N!U7C1!U54!@baseboard_fab2_lib.baseboard_fab2(sch_1):page118_i73@chpset_lib.lbg_core_qat_ext_c(chips)!LBG_CORE_QAT_EXT_C_BGA1-IC,TBD!!!F2051!PREQ_N!!!!
S!PWRGD_CPUPWRGD_GTL!U7C1!R9!@baseboard_fab2_lib.baseboard_fab2(sch_1):page118_i73@chpset_lib.lbg_core_qat_ext_c(chips)!LBG_CORE_QAT_EXT_C_BGA1-IC,TBD!!!F2051!PROC_PWRGD!!!!
S!RST_RSMRST_N!U7C1!P15!@baseboard_fab2_lib.baseboard_fab2(sch_1):page118_i73@chpset_lib.lbg_core_qat_ext_c(chips)!LBG_CORE_QAT_EXT_C_BGA1-IC,TBD!!!F2051!RSMRST_N!!!!
S!TP_PCH_RSVD32!U7C1!AA54!@baseboard_fab2_lib.baseboard_fab2(sch_1):page118_i73@chpset_lib.lbg_core_qat_ext_c(chips)!LBG_CORE_QAT_EXT_C_BGA1-IC,TBD!!!F2051!RSVD(32)!!!!
S!TP_PCH_RSVD33!U7C1!V56!@baseboard_fab2_lib.baseboard_fab2(sch_1):page118_i73@chpset_lib.lbg_core_qat_ext_c(chips)!LBG_CORE_QAT_EXT_C_BGA1-IC,TBD!!!F2051!RSVD(33)!!!!
S!TP_PCH_RSVD34!U7C1!Y56!@baseboard_fab2_lib.baseboard_fab2(sch_1):page118_i73@chpset_lib.lbg_core_qat_ext_c(chips)!LBG_CORE_QAT_EXT_C_BGA1-IC,TBD!!!F2051!RSVD(34)!!!!
S!TP_PCH_RSVD35!U7C1!W54!@baseboard_fab2_lib.baseboard_fab2(sch_1):page118_i73@chpset_lib.lbg_core_qat_ext_c(chips)!LBG_CORE_QAT_EXT_C_BGA1-IC,TBD!!!F2051!RSVD(35)!!!!
S!TP_PCH_RSVD36!U7C1!AK54!@baseboard_fab2_lib.baseboard_fab2(sch_1):page118_i73@chpset_lib.lbg_core_qat_ext_c(chips)!LBG_CORE_QAT_EXT_C_BGA1-IC,TBD!!!F2051!RSVD(36)!!!!
S!TP_PCH_RSVD37!U7C1!BN29!@baseboard_fab2_lib.baseboard_fab2(sch_1):page118_i73@chpset_lib.lbg_core_qat_ext_c(chips)!LBG_CORE_QAT_EXT_C_BGA1-IC,TBD!!!F2051!RSVD(37)!!!!
S!TP_PCH_RSVD38!U7C1!BL29!@baseboard_fab2_lib.baseboard_fab2(sch_1):page118_i73@chpset_lib.lbg_core_qat_ext_c(chips)!LBG_CORE_QAT_EXT_C_BGA1-IC,TBD!!!F2051!RSVD(38)!!!!
S!TP_10GBE_KR0_MON_DN!U7C1!BL26!@baseboard_fab2_lib.baseboard_fab2(sch_1):page118_i73@chpset_lib.lbg_core_qat_ext_c(chips)!LBG_CORE_QAT_EXT_C_BGA1-IC,TBD!!!F2051!RSVD(39)!!!!
S!TP_10GBE_KR0_MON_DP!U7C1!BN26!@baseboard_fab2_lib.baseboard_fab2(sch_1):page118_i73@chpset_lib.lbg_core_qat_ext_c(chips)!LBG_CORE_QAT_EXT_C_BGA1-IC,TBD!!!F2051!RSVD(40)!!!!
S!TP_PCH_RSVD41!U7C1!BJ40!@baseboard_fab2_lib.baseboard_fab2(sch_1):page118_i73@chpset_lib.lbg_core_qat_ext_c(chips)!LBG_CORE_QAT_EXT_C_BGA1-IC,TBD!!!F2051!RSVD(41)!!!!
S!TP_PCH_RSVD42!U7C1!BG40!@baseboard_fab2_lib.baseboard_fab2(sch_1):page118_i73@chpset_lib.lbg_core_qat_ext_c(chips)!LBG_CORE_QAT_EXT_C_BGA1-IC,TBD!!!F2051!RSVD(42)!!!!
S!TP_10GBE_KR1_MON_DN!U7C1!BL33!@baseboard_fab2_lib.baseboard_fab2(sch_1):page118_i73@chpset_lib.lbg_core_qat_ext_c(chips)!LBG_CORE_QAT_EXT_C_BGA1-IC,TBD!!!F2051!RSVD(43)!!!!
S!TP_10GBE_KR1_MON_DP!U7C1!BN33!@baseboard_fab2_lib.baseboard_fab2(sch_1):page118_i73@chpset_lib.lbg_core_qat_ext_c(chips)!LBG_CORE_QAT_EXT_C_BGA1-IC,TBD!!!F2051!RSVD(44)!!!!
S!TP_PCH_RSVD45!U7C1!P22!@baseboard_fab2_lib.baseboard_fab2(sch_1):page118_i73@chpset_lib.lbg_core_qat_ext_c(chips)!LBG_CORE_QAT_EXT_C_BGA1-IC,TBD!!!F2051!RSVD(45)!!!!
S!TP_PCH_RSVD53!U7C1!P26!@baseboard_fab2_lib.baseboard_fab2(sch_1):page118_i73@chpset_lib.lbg_core_qat_ext_c(chips)!LBG_CORE_QAT_EXT_C_BGA1-IC,TBD!!!F2051!RSVD(53)!!!!
S!TP_PCH_RSVD54!U7C1!R24!@baseboard_fab2_lib.baseboard_fab2(sch_1):page118_i73@chpset_lib.lbg_core_qat_ext_c(chips)!LBG_CORE_QAT_EXT_C_BGA1-IC,TBD!!!F2051!RSVD(54)!!!!
S!TP_SLP_LAN_N!U7C1!M15!@baseboard_fab2_lib.baseboard_fab2(sch_1):page118_i73@chpset_lib.lbg_core_qat_ext_c(chips)!LBG_CORE_QAT_EXT_C_BGA1-IC,TBD!!!F2051!SLP_GBE_N!!!!
S!FM_SLP_SUS_N!U7C1!P7!@baseboard_fab2_lib.baseboard_fab2(sch_1):page118_i73@chpset_lib.lbg_core_qat_ext_c(chips)!LBG_CORE_QAT_EXT_C_BGA1-IC,TBD!!!F2051!SLP_SUS_N!!!!
S!PWRGD_SYS_PWROK!U7C1!BY19!@baseboard_fab2_lib.baseboard_fab2(sch_1):page118_i73@chpset_lib.lbg_core_qat_ext_c(chips)!LBG_CORE_QAT_EXT_C_BGA1-IC,TBD!!!F2051!SYS_PWROK!!!!
S!RST_BMC_SYSRST_BTN_OUT_B_N!U7C1!BV19!@baseboard_fab2_lib.baseboard_fab2(sch_1):page118_i73@chpset_lib.lbg_core_qat_ext_c(chips)!LBG_CORE_QAT_EXT_C_BGA1-IC,TBD!!!F2051!SYS_RESET_N!!!!
S!FM_PCH_LVC1_THERMTRIP_N!U7C1!V15!@baseboard_fab2_lib.baseboard_fab2(sch_1):page118_i73@chpset_lib.lbg_core_qat_ext_c(chips)!LBG_CORE_QAT_EXT_C_BGA1-IC,TBD!!!F2051!THRMTRIP_N!!!!
S!TP_CPU_PCH_TRIGGER_IN!U7C1!M7!@baseboard_fab2_lib.baseboard_fab2(sch_1):page118_i73@chpset_lib.lbg_core_qat_ext_c(chips)!LBG_CORE_QAT_EXT_C_BGA1-IC,TBD!!!F2051!TRIGGER_IN!!!!
S!TP_CPU_PCH_TRIGGER_OUT!U7C1!R13!@baseboard_fab2_lib.baseboard_fab2(sch_1):page118_i73@chpset_lib.lbg_core_qat_ext_c(chips)!LBG_CORE_QAT_EXT_C_BGA1-IC,TBD!!!F2051!TRIGGER_OUT!!!!
S!IRQ_LVC3_WAKE_N!U7C1!K9!@baseboard_fab2_lib.baseboard_fab2(sch_1):page118_i73@chpset_lib.lbg_core_qat_ext_c(chips)!LBG_CORE_QAT_EXT_C_BGA1-IC,TBD!!!F2051!WAKE_N!!!!
S!PU_FM_RCIN_N!U7C1!N3!@baseboard_fab2_lib.baseboard_fab2(sch_1):page119_i115@chpset_lib.lbg_core_qat_ext_c(chips)!LBG_CORE_QAT_EXT_C_BGA1-IC,TBD!!!F2050!GPP_A0_RCIN_N_ESPI_ALERT1_N!!!!
S!IRQ_VM_INT_N!U7C1!AA4!@baseboard_fab2_lib.baseboard_fab2(sch_1):page119_i115@chpset_lib.lbg_core_qat_ext_c(chips)!LBG_CORE_QAT_EXT_C_BGA1-IC,TBD!!!F2050!GPP_A10_CLKOUT_LPC1!!!!
S!PU_LPC_PME_N!U7C1!AC2!@baseboard_fab2_lib.baseboard_fab2(sch_1):page119_i115@chpset_lib.lbg_core_qat_ext_c(chips)!LBG_CORE_QAT_EXT_C_BGA1-IC,TBD!!!F2050!GPP_A11_PME_N!!!!
S!PU_IRQ_PCH_SCI_WHEA_N!U7C1!R1!@baseboard_fab2_lib.baseboard_fab2(sch_1):page119_i115@chpset_lib.lbg_core_qat_ext_c(chips)!LBG_CORE_QAT_EXT_C_BGA1-IC,TBD!!!F2050!GPP_A12_BMBUSY_N_SXEXITHLDOFF_N!!!!
S!FM_MB_SLOT_ID0!U7C1!T4!@baseboard_fab2_lib.baseboard_fab2(sch_1):page119_i115@chpset_lib.lbg_core_qat_ext_c(chips)!LBG_CORE_QAT_EXT_C_BGA1-IC,TBD!!!F2050!GPP_A13_SUSWARN_N_SUSPWRDNACK!!!!
S!FM_MB_SLOT_ID1!U7C1!AB3!@baseboard_fab2_lib.baseboard_fab2(sch_1):page119_i115@chpset_lib.lbg_core_qat_ext_c(chips)!LBG_CORE_QAT_EXT_C_BGA1-IC,TBD!!!F2050!GPP_A14_ESPI_RESET_N!!!!
S!FM_MB_SLOT_ID2!U7C1!AC4!@baseboard_fab2_lib.baseboard_fab2(sch_1):page119_i115@chpset_lib.lbg_core_qat_ext_c(chips)!LBG_CORE_QAT_EXT_C_BGA1-IC,TBD!!!F2050!GPP_A15_SUSACK_N!!!!
S!FM_UART_PRES_N!U7C1!T2!@baseboard_fab2_lib.baseboard_fab2(sch_1):page119_i115@chpset_lib.lbg_core_qat_ext_c(chips)!LBG_CORE_QAT_EXT_C_BGA1-IC,TBD!!!F2050!GPP_A16_CLKOUT_LPC2!!!!
S!FM_CPU_BMC_INIT!U7C1!AD1!@baseboard_fab2_lib.baseboard_fab2(sch_1):page119_i115@chpset_lib.lbg_core_qat_ext_c(chips)!LBG_CORE_QAT_EXT_C_BGA1-IC,TBD!!!F2050!GPP_A17!!!!
S!TP_IE_FM_UV_THRESHOLD_SET!U7C1!AD3!@baseboard_fab2_lib.baseboard_fab2(sch_1):page119_i115@chpset_lib.lbg_core_qat_ext_c(chips)!LBG_CORE_QAT_EXT_C_BGA1-IC,TBD!!!F2050!GPP_A18!!!!
S!FM_ME_RECOVER_N!U7C1!V3!@baseboard_fab2_lib.baseboard_fab2(sch_1):page119_i115@chpset_lib.lbg_core_qat_ext_c(chips)!LBG_CORE_QAT_EXT_C_BGA1-IC,TBD!!!F2050!GPP_A19!!!!
S!LPC_LAD0_IO0!U7C1!Y3!@baseboard_fab2_lib.baseboard_fab2(sch_1):page119_i115@chpset_lib.lbg_core_qat_ext_c(chips)!LBG_CORE_QAT_EXT_C_BGA1-IC,TBD!!!F2050!GPP_A1_LAD0_ESPI_IO0!!!!
S!FM_POST_CARD_PRES_BMC_N!U7C1!W4!@baseboard_fab2_lib.baseboard_fab2(sch_1):page119_i115@chpset_lib.lbg_core_qat_ext_c(chips)!LBG_CORE_QAT_EXT_C_BGA1-IC,TBD!!!F2050!GPP_A20!!!!
S!FM_OCP_MEZZA_PRES_N!U7C1!AE2!@baseboard_fab2_lib.baseboard_fab2(sch_1):page119_i115@chpset_lib.lbg_core_qat_ext_c(chips)!LBG_CORE_QAT_EXT_C_BGA1-IC,TBD!!!F2050!GPP_A21!!!!
S!FM_TPM_PRES_N!U7C1!AE4!@baseboard_fab2_lib.baseboard_fab2(sch_1):page119_i115@chpset_lib.lbg_core_qat_ext_c(chips)!LBG_CORE_QAT_EXT_C_BGA1-IC,TBD!!!F2050!GPP_A22!!!!
S!FM_BMC_READY_N!U7C1!V1!@baseboard_fab2_lib.baseboard_fab2(sch_1):page119_i115@chpset_lib.lbg_core_qat_ext_c(chips)!LBG_CORE_QAT_EXT_C_BGA1-IC,TBD!!!F2050!GPP_A23!!!!
S!LPC_LAD1_IO1!U7C1!N1!@baseboard_fab2_lib.baseboard_fab2(sch_1):page119_i115@chpset_lib.lbg_core_qat_ext_c(chips)!LBG_CORE_QAT_EXT_C_BGA1-IC,TBD!!!F2050!GPP_A2_LAD1_ESPI_IO1!!!!
S!LPC_LAD2_IO2!U7C1!W2!@baseboard_fab2_lib.baseboard_fab2(sch_1):page119_i115@chpset_lib.lbg_core_qat_ext_c(chips)!LBG_CORE_QAT_EXT_C_BGA1-IC,TBD!!!F2050!GPP_A3_LAD2_ESPI_IO2!!!!
S!LPC_LAD3_IO3!U7C1!Y1!@baseboard_fab2_lib.baseboard_fab2(sch_1):page119_i115@chpset_lib.lbg_core_qat_ext_c(chips)!LBG_CORE_QAT_EXT_C_BGA1-IC,TBD!!!F2050!GPP_A4_LAD3_ESPI_IO3!!!!
S!LPC_LFRAME_N_CS0_N!U7C1!P4!@baseboard_fab2_lib.baseboard_fab2(sch_1):page119_i115@chpset_lib.lbg_core_qat_ext_c(chips)!LBG_CORE_QAT_EXT_C_BGA1-IC,TBD!!!F2050!GPP_A5_LFRAME_N_ESPI_CS0_N!!!!
S!IRQ_LPC_SERIRQ_N!U7C1!P2!@baseboard_fab2_lib.baseboard_fab2(sch_1):page119_i115@chpset_lib.lbg_core_qat_ext_c(chips)!LBG_CORE_QAT_EXT_C_BGA1-IC,TBD!!!F2050!GPP_A6_SERIRQ_ESPI_CS1_N!!!!
S!IRQ_PIRQA_SPI_TPM_N!U7C1!AA2!@baseboard_fab2_lib.baseboard_fab2(sch_1):page119_i115@chpset_lib.lbg_core_qat_ext_c(chips)!LBG_CORE_QAT_EXT_C_BGA1-IC,TBD!!!F2050!GPP_A7_PIRQA_N_ESPI_ALERT0_N!!!!
S!PU_LPC_CLKRUN_N!U7C1!AB1!@baseboard_fab2_lib.baseboard_fab2(sch_1):page119_i115@chpset_lib.lbg_core_qat_ext_c(chips)!LBG_CORE_QAT_EXT_C_BGA1-IC,TBD!!!F2050!GPP_A8_CLKRUN_N!!!!
S!CLK_24M_BMC_LPC_R!U7C1!R3!@baseboard_fab2_lib.baseboard_fab2(sch_1):page119_i115@chpset_lib.lbg_core_qat_ext_c(chips)!LBG_CORE_QAT_EXT_C_BGA1-IC,TBD!!!F2050!GPP_A9_CLKOUT_LPC0_ESPI_CLK!!!!
S!VID_PCH_CORE_PVNN_AUX_VID_0!U7C1!BL7!@baseboard_fab2_lib.baseboard_fab2(sch_1):page119_i115@chpset_lib.lbg_core_qat_ext_c(chips)!LBG_CORE_QAT_EXT_C_BGA1-IC,TBD!!!F2050!GPP_B0_CORE_VID0!!!!
S!RST_SYSTEM_BTN_N!U7C1!BL11!@baseboard_fab2_lib.baseboard_fab2(sch_1):page119_i115@chpset_lib.lbg_core_qat_ext_c(chips)!LBG_CORE_QAT_EXT_C_BGA1-IC,TBD!!!F2050!GPP_B10_SRCCLKREQ5_N!!!!
S!FM_PMBUS_ALERT_BUF_EN_N!U7C1!BK9!@baseboard_fab2_lib.baseboard_fab2(sch_1):page119_i115@chpset_lib.lbg_core_qat_ext_c(chips)!LBG_CORE_QAT_EXT_C_BGA1-IC,TBD!!!F2050!GPP_B11!!!!
S!FM_GLOBAL_RST_WARN_N!U7C1!BL18!@baseboard_fab2_lib.baseboard_fab2(sch_1):page119_i115@chpset_lib.lbg_core_qat_ext_c(chips)!LBG_CORE_QAT_EXT_C_BGA1-IC,TBD!!!F2050!GPP_B12_GLB_RST_WARN_N!!!!
S!RST_PLTRST_N!U7C1!BN18!@baseboard_fab2_lib.baseboard_fab2(sch_1):page119_i115@chpset_lib.lbg_core_qat_ext_c(chips)!LBG_CORE_QAT_EXT_C_BGA1-IC,TBD!!!F2050!GPP_B13_PLTRST_N!!!!
S!FM_BIOS_TOP_SWAP_SPKR!U7C1!BH13!@baseboard_fab2_lib.baseboard_fab2(sch_1):page119_i115@chpset_lib.lbg_core_qat_ext_c(chips)!LBG_CORE_QAT_EXT_C_BGA1-IC,TBD!!!F2050!GPP_B14_SPKR!!!!
S!FM_UART_ALERT_N!U7C1!BK13!@baseboard_fab2_lib.baseboard_fab2(sch_1):page119_i115@chpset_lib.lbg_core_qat_ext_c(chips)!LBG_CORE_QAT_EXT_C_BGA1-IC,TBD!!!F2050!GPP_B15!!!!
S!IRQ_PCH_NIC_ALERT_N!U7C1!BG22!@baseboard_fab2_lib.baseboard_fab2(sch_1):page119_i115@chpset_lib.lbg_core_qat_ext_c(chips)!LBG_CORE_QAT_EXT_C_BGA1-IC,TBD!!!F2050!GPP_B16!!!!
S!FM_PCH_PWRBTN_OUT_N!U7C1!BG15!@baseboard_fab2_lib.baseboard_fab2(sch_1):page119_i115@chpset_lib.lbg_core_qat_ext_c(chips)!LBG_CORE_QAT_EXT_C_BGA1-IC,TBD!!!F2050!GPP_B17!!!!
S!FM_UV_ADR_TRIGGER_EN!U7C1!BL15!@baseboard_fab2_lib.baseboard_fab2(sch_1):page119_i115@chpset_lib.lbg_core_qat_ext_c(chips)!LBG_CORE_QAT_EXT_C_BGA1-IC,TBD!!!F2050!GPP_B18!!!!
S!FM_BIOS_PREFRB2_GOOD!U7C1!BK20!@baseboard_fab2_lib.baseboard_fab2(sch_1):page119_i115@chpset_lib.lbg_core_qat_ext_c(chips)!LBG_CORE_QAT_EXT_C_BGA1-IC,TBD!!!F2050!GPP_B19!!!!
S!VID_PCH_CORE_PVNN_AUX_VID_1!U7C1!BH9!@baseboard_fab2_lib.baseboard_fab2(sch_1):page119_i115@chpset_lib.lbg_core_qat_ext_c(chips)!LBG_CORE_QAT_EXT_C_BGA1-IC,TBD!!!F2050!GPP_B1_CORE_VID1!!!!
S!PU_IRQ_VRALERT_N!U7C1!BN15!@baseboard_fab2_lib.baseboard_fab2(sch_1):page119_i115@chpset_lib.lbg_core_qat_ext_c(chips)!LBG_CORE_QAT_EXT_C_BGA1-IC,TBD!!!F2050!GPP_B2!!!!
S!FM_BIOS_POST_CMPLT_N!U7C1!BJ22!@baseboard_fab2_lib.baseboard_fab2(sch_1):page119_i115@chpset_lib.lbg_core_qat_ext_c(chips)!LBG_CORE_QAT_EXT_C_BGA1-IC,TBD!!!F2050!GPP_B20!!!!
S!FM_FAST_PROCHOT_EN_N!U7C1!BH17!@baseboard_fab2_lib.baseboard_fab2(sch_1):page119_i115@chpset_lib.lbg_core_qat_ext_c(chips)!LBG_CORE_QAT_EXT_C_BGA1-IC,TBD!!!F2050!GPP_B21!!!!
S!FM_USB_P0_EN_BOOT_BIOS_STRAP_N!U7C1!BR17!@baseboard_fab2_lib.baseboard_fab2(sch_1):page119_i115@chpset_lib.lbg_core_qat_ext_c(chips)!LBG_CORE_QAT_EXT_C_BGA1-IC,TBD!!!F2050!GPP_B22!!!!
S!FM_PCH_BMC_THERMTRIP_EXI_STRAP_!U7C1!BM20!@baseboard_fab2_lib.baseboard_fab2(sch_1):page119_i115@chpset_lib.lbg_core_qat_ext_c(chips)!LBG_CORE_QAT_EXT_C_BGA1-IC,TBD!!!F2050!GPP_B23_MEIE_SML1ALRT_N_PHOT_N!!!!
S!FM_QAT_EN_N!U7C1!BR9!@baseboard_fab2_lib.baseboard_fab2(sch_1):page119_i115@chpset_lib.lbg_core_qat_ext_c(chips)!LBG_CORE_QAT_EXT_C_BGA1-IC,TBD!!!F2050!GPP_B3_CPU_GP2!!!!
S!IRQ_PVDDQ_ABC_VRHOT_LVT3_N!U7C1!BN7!@baseboard_fab2_lib.baseboard_fab2(sch_1):page119_i115@chpset_lib.lbg_core_qat_ext_c(chips)!LBG_CORE_QAT_EXT_C_BGA1-IC,TBD!!!F2050!GPP_B4_CPU_GP3!!!!
S!IRQ_PVDDQ_DEF_VRHOT_LVT3_N!U7C1!BK17!@baseboard_fab2_lib.baseboard_fab2(sch_1):page119_i115@chpset_lib.lbg_core_qat_ext_c(chips)!LBG_CORE_QAT_EXT_C_BGA1-IC,TBD!!!F2050!GPP_B5_SRCCLKREQ0_N!!!!
S!IRQ_PVDDQ_GHJ_VRHOT_LVT3_N!U7C1!BG18!@baseboard_fab2_lib.baseboard_fab2(sch_1):page119_i115@chpset_lib.lbg_core_qat_ext_c(chips)!LBG_CORE_QAT_EXT_C_BGA1-IC,TBD!!!F2050!GPP_B6_SRCCLKREQ1_N!!!!
S!IRQ_PVDDQ_KLM_VRHOT_LVT3_N!U7C1!BR13!@baseboard_fab2_lib.baseboard_fab2(sch_1):page119_i115@chpset_lib.lbg_core_qat_ext_c(chips)!LBG_CORE_QAT_EXT_C_BGA1-IC,TBD!!!F2050!GPP_B7_SRCCLKREQ2_N!!!!
S!FP_NMI_BTN_N!U7C1!BN11!@baseboard_fab2_lib.baseboard_fab2(sch_1):page119_i115@chpset_lib.lbg_core_qat_ext_c(chips)!LBG_CORE_QAT_EXT_C_BGA1-IC,TBD!!!F2050!GPP_B8_SRCCLKREQ3_N!!!!
S!FM_PWR_BTN_N!U7C1!BH20!@baseboard_fab2_lib.baseboard_fab2(sch_1):page119_i115@chpset_lib.lbg_core_qat_ext_c(chips)!LBG_CORE_QAT_EXT_C_BGA1-IC,TBD!!!F2050!GPP_B9_SRCCLKREQ4_N!!!!
S!SMB_HOST_STBY_LVC3_SCL_R1!U7C1!BW28!@baseboard_fab2_lib.baseboard_fab2(sch_1):page119_i115@chpset_lib.lbg_core_qat_ext_c(chips)!LBG_CORE_QAT_EXT_C_BGA1-IC,TBD!!!F2050!GPP_C0_SMBCLK!!!!
S!FM_PCH_SATA_RAID_KEY!U7C1!BV31!@baseboard_fab2_lib.baseboard_fab2(sch_1):page119_i115@chpset_lib.lbg_core_qat_ext_c(chips)!LBG_CORE_QAT_EXT_C_BGA1-IC,TBD!!!F2050!GPP_C10!!!!
S!FM_BOARD_REV_ID2!U7C1!BV33!@baseboard_fab2_lib.baseboard_fab2(sch_1):page119_i115@chpset_lib.lbg_core_qat_ext_c(chips)!LBG_CORE_QAT_EXT_C_BGA1-IC,TBD!!!F2050!GPP_C11!!!!
S!FM_BOARD_REV_ID0!U7C1!CA30!@baseboard_fab2_lib.baseboard_fab2(sch_1):page119_i115@chpset_lib.lbg_core_qat_ext_c(chips)!LBG_CORE_QAT_EXT_C_BGA1-IC,TBD!!!F2050!GPP_C12!!!!
S!FM_BOARD_REV_ID1!U7C1!BV38!@baseboard_fab2_lib.baseboard_fab2(sch_1):page119_i115@chpset_lib.lbg_core_qat_ext_c(chips)!LBG_CORE_QAT_EXT_C_BGA1-IC,TBD!!!F2050!GPP_C13!!!!
S!IRQ_BMC_PCH_SCI_LPC_N!U7C1!BY38!@baseboard_fab2_lib.baseboard_fab2(sch_1):page119_i115@chpset_lib.lbg_core_qat_ext_c(chips)!LBG_CORE_QAT_EXT_C_BGA1-IC,TBD!!!F2050!GPP_C14!!!!
S!FM_SLT_CFG0!U7C1!CA32!@baseboard_fab2_lib.baseboard_fab2(sch_1):page119_i115@chpset_lib.lbg_core_qat_ext_c(chips)!LBG_CORE_QAT_EXT_C_BGA1-IC,TBD!!!F2050!GPP_C15!!!!
S!FM_SLT_CFG1!U7C1!BW37!@baseboard_fab2_lib.baseboard_fab2(sch_1):page119_i115@chpset_lib.lbg_core_qat_ext_c(chips)!LBG_CORE_QAT_EXT_C_BGA1-IC,TBD!!!F2050!GPP_C16!!!!
S!FM_SLT_CFG2_R!U7C1!BY31!@baseboard_fab2_lib.baseboard_fab2(sch_1):page119_i115@chpset_lib.lbg_core_qat_ext_c(chips)!LBG_CORE_QAT_EXT_C_BGA1-IC,TBD!!!F2050!GPP_C17!!!!
S!FM_PMBUS_ALERT_BUF_EN_N!U7C1!BY35!@baseboard_fab2_lib.baseboard_fab2(sch_1):page119_i115@chpset_lib.lbg_core_qat_ext_c(chips)!LBG_CORE_QAT_EXT_C_BGA1-IC,TBD!!!F2050!GPP_C18!!!!
S!FM_BB_BMC_MP_GPIO!U7C1!BW39!@baseboard_fab2_lib.baseboard_fab2(sch_1):page119_i115@chpset_lib.lbg_core_qat_ext_c(chips)!LBG_CORE_QAT_EXT_C_BGA1-IC,TBD!!!F2050!GPP_C19!!!!
S!SMB_HOST_STBY_LVC3_SDA_R1!U7C1!BV27!@baseboard_fab2_lib.baseboard_fab2(sch_1):page119_i115@chpset_lib.lbg_core_qat_ext_c(chips)!LBG_CORE_QAT_EXT_C_BGA1-IC,TBD!!!F2050!GPP_C1_SMBDATA!!!!
S!FM_THROTTLE_N!U7C1!CA39!@baseboard_fab2_lib.baseboard_fab2(sch_1):page119_i115@chpset_lib.lbg_core_qat_ext_c(chips)!LBG_CORE_QAT_EXT_C_BGA1-IC,TBD!!!F2050!GPP_C20!!!!
S!FM_BIOS_POST_CMPLT_N!U7C1!BY33!@baseboard_fab2_lib.baseboard_fab2(sch_1):page119_i115@chpset_lib.lbg_core_qat_ext_c(chips)!LBG_CORE_QAT_EXT_C_BGA1-IC,TBD!!!F2050!GPP_C21!!!!
S!IRQ_BMC_PCH_SMI_LPC_N!U7C1!CA34!@baseboard_fab2_lib.baseboard_fab2(sch_1):page119_i115@chpset_lib.lbg_core_qat_ext_c(chips)!LBG_CORE_QAT_EXT_C_BGA1-IC,TBD!!!F2050!GPP_C22!!!!
S!FM_CPU_CATERR_DLY_LVT3_R_N!U7C1!CA37!@baseboard_fab2_lib.baseboard_fab2(sch_1):page119_i115@chpset_lib.lbg_core_qat_ext_c(chips)!LBG_CORE_QAT_EXT_C_BGA1-IC,TBD!!!F2050!GPP_C23!!!!
S!PU_PCH_TLS_ENABLE_STRAP!U7C1!BY27!@baseboard_fab2_lib.baseboard_fab2(sch_1):page119_i115@chpset_lib.lbg_core_qat_ext_c(chips)!LBG_CORE_QAT_EXT_C_BGA1-IC,TBD!!!F2050!GPP_C2_SMBALERT_N!!!!
S!SMB_SMLINK0_STBY_LVC3_SCL_R1!U7C1!BV29!@baseboard_fab2_lib.baseboard_fab2(sch_1):page119_i115@chpset_lib.lbg_core_qat_ext_c(chips)!LBG_CORE_QAT_EXT_C_BGA1-IC,TBD!!!F2050!GPP_C3_SML0CLK_IE!!!!
S!SMB_SMLINK0_STBY_LVC3_SDA_R1!U7C1!BW30!@baseboard_fab2_lib.baseboard_fab2(sch_1):page119_i115@chpset_lib.lbg_core_qat_ext_c(chips)!LBG_CORE_QAT_EXT_C_BGA1-IC,TBD!!!F2050!GPP_C4_SML0DATA_IE!!!!
S!IRQ_SML0_ALERT_N!U7C1!BW34!@baseboard_fab2_lib.baseboard_fab2(sch_1):page119_i115@chpset_lib.lbg_core_qat_ext_c(chips)!LBG_CORE_QAT_EXT_C_BGA1-IC,TBD!!!F2050!GPP_C5_SML0ALERT_IE_N!!!!
S!SMB_PMBUS_BMC_STBY_LVC3_SCL_R1!U7C1!CA28!@baseboard_fab2_lib.baseboard_fab2(sch_1):page119_i115@chpset_lib.lbg_core_qat_ext_c(chips)!LBG_CORE_QAT_EXT_C_BGA1-IC,TBD!!!F2050!GPP_C6_SML1CLK_IE!!!!
S!SMB_PMBUS_BMC_STBY_LVC3_SDA_R1!U7C1!BV35!@baseboard_fab2_lib.baseboard_fab2(sch_1):page119_i115@chpset_lib.lbg_core_qat_ext_c(chips)!LBG_CORE_QAT_EXT_C_BGA1-IC,TBD!!!F2050!GPP_C7_SML1DATA_IE!!!!
S!FM_PASSWORD_CLEAR_N!U7C1!BW32!@baseboard_fab2_lib.baseboard_fab2(sch_1):page119_i115@chpset_lib.lbg_core_qat_ext_c(chips)!LBG_CORE_QAT_EXT_C_BGA1-IC,TBD!!!F2050!GPP_C8!!!!
S!FM_CPU1_RC_ERROR_N!U7C1!BY29!@baseboard_fab2_lib.baseboard_fab2(sch_1):page119_i115@chpset_lib.lbg_core_qat_ext_c(chips)!LBG_CORE_QAT_EXT_C_BGA1-IC,TBD!!!F2050!GPP_C9!!!!
S!IRQ_BMC_PCH_NMI_STBY_R_N!U7C1!BR42!@baseboard_fab2_lib.baseboard_fab2(sch_1):page119_i115@chpset_lib.lbg_core_qat_ext_c(chips)!LBG_CORE_QAT_EXT_C_BGA1-IC,TBD!!!F2050!GPP_D0!!!!
S!FM_PWR_LED_N!U7C1!BK46!@baseboard_fab2_lib.baseboard_fab2(sch_1):page119_i115@chpset_lib.lbg_core_qat_ext_c(chips)!LBG_CORE_QAT_EXT_C_BGA1-IC,TBD!!!F2050!GPP_D1!!!!
S!H_CPU0_FAST_WAKE_LVT3_N!U7C1!BV47!@baseboard_fab2_lib.baseboard_fab2(sch_1):page119_i115@chpset_lib.lbg_core_qat_ext_c(chips)!LBG_CORE_QAT_EXT_C_BGA1-IC,TBD!!!F2050!GPP_D10_SSATA_DEVSLP4!!!!
S!IRQ_LOM_ALERT_N!U7C1!BY47!@baseboard_fab2_lib.baseboard_fab2(sch_1):page119_i115@chpset_lib.lbg_core_qat_ext_c(chips)!LBG_CORE_QAT_EXT_C_BGA1-IC,TBD!!!F2050!GPP_D11_SSATA_DEVSLP5!!!!
S!TP_PCH_GPP_D12!U7C1!BN40!@baseboard_fab2_lib.baseboard_fab2(sch_1):page119_i115@chpset_lib.lbg_core_qat_ext_c(chips)!LBG_CORE_QAT_EXT_C_BGA1-IC,TBD!!!F2050!GPP_D12_SSATA_SDATAOUT1!!!!
S!SMB_SLOTX24_STBY_LVC3_SCL_R1!U7C1!BY44!@baseboard_fab2_lib.baseboard_fab2(sch_1):page119_i115@chpset_lib.lbg_core_qat_ext_c(chips)!LBG_CORE_QAT_EXT_C_BGA1-IC,TBD!!!F2050!GPP_D13_SML0BCLK_IE!!!!
S!SMB_SLOTX24_STBY_LVC3_SDA_R1!U7C1!BL44!@baseboard_fab2_lib.baseboard_fab2(sch_1):page119_i115@chpset_lib.lbg_core_qat_ext_c(chips)!LBG_CORE_QAT_EXT_C_BGA1-IC,TBD!!!F2050!GPP_D14_SML0BDATA_IE!!!!
S!SGPIO_PCH_SSATA_DOUT0!U7C1!BW43!@baseboard_fab2_lib.baseboard_fab2(sch_1):page119_i115@chpset_lib.lbg_core_qat_ext_c(chips)!LBG_CORE_QAT_EXT_C_BGA1-IC,TBD!!!F2050!GPP_D15_SSATA_SDATAOUT0!!!!
S!IRQ_OOB_MGMT_RISER_ALERT_N!U7C1!BV42!@baseboard_fab2_lib.baseboard_fab2(sch_1):page119_i115@chpset_lib.lbg_core_qat_ext_c(chips)!LBG_CORE_QAT_EXT_C_BGA1-IC,TBD!!!F2050!GPP_D16_SML0BALERT_IE_N!!!!
S!FM_XRC_PRESENT_N!U7C1!BW48!@baseboard_fab2_lib.baseboard_fab2(sch_1):page119_i115@chpset_lib.lbg_core_qat_ext_c(chips)!LBG_CORE_QAT_EXT_C_BGA1-IC,TBD!!!F2050!GPP_D17!!!!
S!FM_XRC_READY_N!U7C1!CA41!@baseboard_fab2_lib.baseboard_fab2(sch_1):page119_i115@chpset_lib.lbg_core_qat_ext_c(chips)!LBG_CORE_QAT_EXT_C_BGA1-IC,TBD!!!F2050!GPP_D18!!!!
S!FM_ADR_MODE_SEL_R!U7C1!CA43!@baseboard_fab2_lib.baseboard_fab2(sch_1):page119_i115@chpset_lib.lbg_core_qat_ext_c(chips)!LBG_CORE_QAT_EXT_C_BGA1-IC,TBD!!!F2050!GPP_D19!!!!
S!IRQ_HSC_FAULT_N!U7C1!BJ44!@baseboard_fab2_lib.baseboard_fab2(sch_1):page119_i115@chpset_lib.lbg_core_qat_ext_c(chips)!LBG_CORE_QAT_EXT_C_BGA1-IC,TBD!!!F2050!GPP_D2!!!!
S!FM_BMC_HEARTBEAT_N!U7C1!CA48!@baseboard_fab2_lib.baseboard_fab2(sch_1):page119_i115@chpset_lib.lbg_core_qat_ext_c(chips)!LBG_CORE_QAT_EXT_C_BGA1-IC,TBD!!!F2050!GPP_D20!!!!
S!SP2_BMC_CM_UART_RX!U7C1!BV44!@baseboard_fab2_lib.baseboard_fab2(sch_1):page119_i115@chpset_lib.lbg_core_qat_ext_c(chips)!LBG_CORE_QAT_EXT_C_BGA1-IC,TBD!!!F2050!GPP_D21_IE_UART_RX!!!!
S!SP2_BMC_CM_UART_TX!U7C1!BR46!@baseboard_fab2_lib.baseboard_fab2(sch_1):page119_i115@chpset_lib.lbg_core_qat_ext_c(chips)!LBG_CORE_QAT_EXT_C_BGA1-IC,TBD!!!F2050!GPP_D22_IE_UART_TX!!!!
S!FM_CPU0_THERMTRIP_LATCH_LVT3_N!U7C1!BN44!@baseboard_fab2_lib.baseboard_fab2(sch_1):page119_i115@chpset_lib.lbg_core_qat_ext_c(chips)!LBG_CORE_QAT_EXT_C_BGA1-IC,TBD!!!F2050!GPP_D23!!!!
S!IRQ_MEZZ_LAN_ALERT_N!U7C1!BW45!@baseboard_fab2_lib.baseboard_fab2(sch_1):page119_i115@chpset_lib.lbg_core_qat_ext_c(chips)!LBG_CORE_QAT_EXT_C_BGA1-IC,TBD!!!F2050!GPP_D3!!!!
S!FM_PCH_PLD_DATA_R!U7C1!BM42!@baseboard_fab2_lib.baseboard_fab2(sch_1):page119_i115@chpset_lib.lbg_core_qat_ext_c(chips)!LBG_CORE_QAT_EXT_C_BGA1-IC,TBD!!!F2050!GPP_D4!!!!
S!FM_BMC_ENABLE_N!U7C1!BM38!@baseboard_fab2_lib.baseboard_fab2(sch_1):page119_i115@chpset_lib.lbg_core_qat_ext_c(chips)!LBG_CORE_QAT_EXT_C_BGA1-IC,TBD!!!F2050!GPP_D5!!!!
S!FM_CPLD_BMC_PWRDN_N!U7C1!BW41!@baseboard_fab2_lib.baseboard_fab2(sch_1):page119_i115@chpset_lib.lbg_core_qat_ext_c(chips)!LBG_CORE_QAT_EXT_C_BGA1-IC,TBD!!!F2050!GPP_D6!!!!
S!FM_BMC_CPLD_GPO!U7C1!CA45!@baseboard_fab2_lib.baseboard_fab2(sch_1):page119_i115@chpset_lib.lbg_core_qat_ext_c(chips)!LBG_CORE_QAT_EXT_C_BGA1-IC,TBD!!!F2050!GPP_D7!!!!
S!FM_BMC_FAULT_LED_N!U7C1!BR38!@baseboard_fab2_lib.baseboard_fab2(sch_1):page119_i115@chpset_lib.lbg_core_qat_ext_c(chips)!LBG_CORE_QAT_EXT_C_BGA1-IC,TBD!!!F2050!GPP_D8!!!!
S!IRQ_FORCE_NM_THROTTLE_N!U7C1!BY42!@baseboard_fab2_lib.baseboard_fab2(sch_1):page119_i115@chpset_lib.lbg_core_qat_ext_c(chips)!LBG_CORE_QAT_EXT_C_BGA1-IC,TBD!!!F2050!GPP_D9_SSATA_DEVSLP3!!!!
S!A_RCOMP_3P3!U7C1!BY25!@baseboard_fab2_lib.baseboard_fab2(sch_1):page120_i147@chpset_lib.lbg_core_qat_ext_c(chips)!LBG_CORE_QAT_EXT_C_BGA1-IC,TBD!!!F2049!GPIO_RCOMP_3P3!!!!
S!FM_CPU0_RC_EN!U7C1!BH50!@baseboard_fab2_lib.baseboard_fab2(sch_1):page120_i147@chpset_lib.lbg_core_qat_ext_c(chips)!LBG_CORE_QAT_EXT_C_BGA1-IC,TBD!!!F2049!GPP_E0_SATAXPCIE0_SATAGP0!!!!
S!IRQ_BMC_PCH_SCI_LPC_N!U7C1!BN48!@baseboard_fab2_lib.baseboard_fab2(sch_1):page120_i147@chpset_lib.lbg_core_qat_ext_c(chips)!LBG_CORE_QAT_EXT_C_BGA1-IC,TBD!!!F2049!GPP_E10_USB2_OC1_N!!!!
S!IRQ_BMC_PCH_SMI_LPC_N!U7C1!AW54!@baseboard_fab2_lib.baseboard_fab2(sch_1):page120_i147@chpset_lib.lbg_core_qat_ext_c(chips)!LBG_CORE_QAT_EXT_C_BGA1-IC,TBD!!!F2049!GPP_E11_USB2_OC2_N!!!!
S!IRQ_UV_DETECT_N!U7C1!AU58!@baseboard_fab2_lib.baseboard_fab2(sch_1):page120_i147@chpset_lib.lbg_core_qat_ext_c(chips)!LBG_CORE_QAT_EXT_C_BGA1-IC,TBD!!!F2049!GPP_E12_USB2_OC3_N!!!!
S!FM_CPU1_RC_EN!U7C1!AY52!@baseboard_fab2_lib.baseboard_fab2(sch_1):page120_i147@chpset_lib.lbg_core_qat_ext_c(chips)!LBG_CORE_QAT_EXT_C_BGA1-IC,TBD!!!F2049!GPP_E1_SATAXPCIE1_SATAGP1!!!!
S!FM_POST_CARD_PRES_BMC_N!U7C1!BG52!@baseboard_fab2_lib.baseboard_fab2(sch_1):page120_i147@chpset_lib.lbg_core_qat_ext_c(chips)!LBG_CORE_QAT_EXT_C_BGA1-IC,TBD!!!F2049!GPP_E2_SATAXPCIE2_SATAGP2!!!!
S!FM_CPLD_ADR_TRIGGER_R_N!U7C1!BE52!@baseboard_fab2_lib.baseboard_fab2(sch_1):page120_i147@chpset_lib.lbg_core_qat_ext_c(chips)!LBG_CORE_QAT_EXT_C_BGA1-IC,TBD!!!F2049!GPP_E3_CPU_GP0!!!!
S!FM_CPU_ERR2_LVT3_N!U7C1!AV52!@baseboard_fab2_lib.baseboard_fab2(sch_1):page120_i147@chpset_lib.lbg_core_qat_ext_c(chips)!LBG_CORE_QAT_EXT_C_BGA1-IC,TBD!!!F2049!GPP_E4_SATA_DEVSLP0!!!!
S!FM_CPU_MSMI_LVT3_N!U7C1!AT52!@baseboard_fab2_lib.baseboard_fab2(sch_1):page120_i147@chpset_lib.lbg_core_qat_ext_c(chips)!LBG_CORE_QAT_EXT_C_BGA1-IC,TBD!!!F2049!GPP_E5_SATA_DEVSLP1!!!!
S!IRQ_BMC_PCH_NMI_STBY_N!U7C1!BB52!@baseboard_fab2_lib.baseboard_fab2(sch_1):page120_i147@chpset_lib.lbg_core_qat_ext_c(chips)!LBG_CORE_QAT_EXT_C_BGA1-IC,TBD!!!F2049!GPP_E6_SATA_DEVSLP2!!!!
S!FM_ADR_SMI_GPIO_N!U7C1!BJ48!@baseboard_fab2_lib.baseboard_fab2(sch_1):page120_i147@chpset_lib.lbg_core_qat_ext_c(chips)!LBG_CORE_QAT_EXT_C_BGA1-IC,TBD!!!F2049!GPP_E7_CPU_GP1!!!!
S!LED_PCH_SATA_HDD_N!U7C1!AV56!@baseboard_fab2_lib.baseboard_fab2(sch_1):page120_i147@chpset_lib.lbg_core_qat_ext_c(chips)!LBG_CORE_QAT_EXT_C_BGA1-IC,TBD!!!F2049!GPP_E8_SATA_LED_N!!!!
S!FM_OC0_USB_N!U7C1!BL48!@baseboard_fab2_lib.baseboard_fab2(sch_1):page120_i147@chpset_lib.lbg_core_qat_ext_c(chips)!LBG_CORE_QAT_EXT_C_BGA1-IC,TBD!!!F2049!GPP_E9_USB2_OC0_N!!!!
S!IRQ_OC_DETECT_N!U7C1!AG7!@baseboard_fab2_lib.baseboard_fab2(sch_1):page120_i147@chpset_lib.lbg_core_qat_ext_c(chips)!LBG_CORE_QAT_EXT_C_BGA1-IC,TBD!!!F2049!GPP_F0_SATAXPCIE3_SATAGP3!!!!
S!SGPIO_PCH_SATA_CLOCK!U7C1!AL7!@baseboard_fab2_lib.baseboard_fab2(sch_1):page120_i147@chpset_lib.lbg_core_qat_ext_c(chips)!LBG_CORE_QAT_EXT_C_BGA1-IC,TBD!!!F2049!GPP_F10_SATA_SCLOCK!!!!
S!SGPIO_PCH_SATA_LOAD!U7C1!AR9!@baseboard_fab2_lib.baseboard_fab2(sch_1):page120_i147@chpset_lib.lbg_core_qat_ext_c(chips)!LBG_CORE_QAT_EXT_C_BGA1-IC,TBD!!!F2049!GPP_F11_SATA_SLOAD!!!!
S!TP_PCH_GPP_F12!U7C1!AP7!@baseboard_fab2_lib.baseboard_fab2(sch_1):page120_i147@chpset_lib.lbg_core_qat_ext_c(chips)!LBG_CORE_QAT_EXT_C_BGA1-IC,TBD!!!F2049!GPP_F12_SATA_SDATAOUT1!!!!
S!SGPIO_PCH_SATA_DOUT0!U7C1!AP11!@baseboard_fab2_lib.baseboard_fab2(sch_1):page120_i147@chpset_lib.lbg_core_qat_ext_c(chips)!LBG_CORE_QAT_EXT_C_BGA1-IC,TBD!!!F2049!GPP_F13_SATA_SDATAOUT0!!!!
S!LED_PCH_SSATA_HDD_N!U7C1!AL11!@baseboard_fab2_lib.baseboard_fab2(sch_1):page120_i147@chpset_lib.lbg_core_qat_ext_c(chips)!LBG_CORE_QAT_EXT_C_BGA1-IC,TBD!!!F2049!GPP_F14_SSATA_LED_N!!!!
S!FM_FORCE_ADR_N!U7C1!AR13!@baseboard_fab2_lib.baseboard_fab2(sch_1):page120_i147@chpset_lib.lbg_core_qat_ext_c(chips)!LBG_CORE_QAT_EXT_C_BGA1-IC,TBD!!!F2049!GPP_F15_USB2_OC4_N!!!!
S!FM_IE_DISABLE_N!U7C1!AU13!@baseboard_fab2_lib.baseboard_fab2(sch_1):page120_i147@chpset_lib.lbg_core_qat_ext_c(chips)!LBG_CORE_QAT_EXT_C_BGA1-IC,TBD!!!F2049!GPP_F16_USB2_OC5_N!!!!
S!FM_BIOS_TOP_SWAP!U7C1!AP15!@baseboard_fab2_lib.baseboard_fab2(sch_1):page120_i147@chpset_lib.lbg_core_qat_ext_c(chips)!LBG_CORE_QAT_EXT_C_BGA1-IC,TBD!!!F2049!GPP_F17_USB2_OC6_N!!!!
S!FM_MEM_THERM_EVENT_PCH_N!U7C1!AL15!@baseboard_fab2_lib.baseboard_fab2(sch_1):page120_i147@chpset_lib.lbg_core_qat_ext_c(chips)!LBG_CORE_QAT_EXT_C_BGA1-IC,TBD!!!F2049!GPP_F18_USB2_OC7_N!!!!
S!SMB_LAN_STBY_LVC3_SCL_R2!U7C1!AU9!@baseboard_fab2_lib.baseboard_fab2(sch_1):page120_i147@chpset_lib.lbg_core_qat_ext_c(chips)!LBG_CORE_QAT_EXT_C_BGA1-IC,TBD!!!F2049!GPP_F19_LAN_SMBCLK!!!!
S!FM_HSC_TIMER_EXP_N!U7C1!AK9!@baseboard_fab2_lib.baseboard_fab2(sch_1):page120_i147@chpset_lib.lbg_core_qat_ext_c(chips)!LBG_CORE_QAT_EXT_C_BGA1-IC,TBD!!!F2049!GPP_F1_SATAXPCIE4_SATAGP4!!!!
S!SMB_LAN_STBY_LVC3_SDA_R2!U7C1!AU20!@baseboard_fab2_lib.baseboard_fab2(sch_1):page120_i147@chpset_lib.lbg_core_qat_ext_c(chips)!LBG_CORE_QAT_EXT_C_BGA1-IC,TBD!!!F2049!GPP_F20_LAN_SMBDATA!!!!
S!IRQ_PCH_NIC_ALERT_N!U7C1!AR17!@baseboard_fab2_lib.baseboard_fab2(sch_1):page120_i147@chpset_lib.lbg_core_qat_ext_c(chips)!LBG_CORE_QAT_EXT_C_BGA1-IC,TBD!!!F2049!GPP_F21_LAN_SMBALRT_N!!!!
S!SGPIO_PCH_SSATA_CLOCK!U7C1!AP18!@baseboard_fab2_lib.baseboard_fab2(sch_1):page120_i147@chpset_lib.lbg_core_qat_ext_c(chips)!LBG_CORE_QAT_EXT_C_BGA1-IC,TBD!!!F2049!GPP_F22_SSATA_SCLOCK!!!!
S!SGPIO_PCH_SSATA_LOAD!U7C1!AU17!@baseboard_fab2_lib.baseboard_fab2(sch_1):page120_i147@chpset_lib.lbg_core_qat_ext_c(chips)!LBG_CORE_QAT_EXT_C_BGA1-IC,TBD!!!F2049!GPP_F23_SSATA_SLOAD!!!!
S!FM_MP_PS_FAIL_N!U7C1!AK20!@baseboard_fab2_lib.baseboard_fab2(sch_1):page120_i147@chpset_lib.lbg_core_qat_ext_c(chips)!LBG_CORE_QAT_EXT_C_BGA1-IC,TBD!!!F2049!GPP_F2_SATAXPCIE5_SATAGP5!!!!
S!FM_MP_PS_REDUNDANT_LOST_N!U7C1!AK13!@baseboard_fab2_lib.baseboard_fab2(sch_1):page120_i147@chpset_lib.lbg_core_qat_ext_c(chips)!LBG_CORE_QAT_EXT_C_BGA1-IC,TBD!!!F2049!GPP_F3_SATAXPCIE6_SATAGP6!!!!
S!FM_BMC_READY_N!U7C1!AH13!@baseboard_fab2_lib.baseboard_fab2(sch_1):page120_i147@chpset_lib.lbg_core_qat_ext_c(chips)!LBG_CORE_QAT_EXT_C_BGA1-IC,TBD!!!F2049!GPP_F4_SATAXPCIE7_SATAGP7!!!!
S!FM_BIOS_USB_RECOVERY!U7C1!AH17!@baseboard_fab2_lib.baseboard_fab2(sch_1):page120_i147@chpset_lib.lbg_core_qat_ext_c(chips)!LBG_CORE_QAT_EXT_C_BGA1-IC,TBD!!!F2049!GPP_F5_SATA_DEVSLP3!!!!
S!JTAG_PCH_PLD_TCK!U7C1!AL18!@baseboard_fab2_lib.baseboard_fab2(sch_1):page120_i147@chpset_lib.lbg_core_qat_ext_c(chips)!LBG_CORE_QAT_EXT_C_BGA1-IC,TBD!!!F2049!GPP_F6_SATA_DEVSLP4!!!!
S!JTAG_PCH_PLD_TDI!U7C1!AK17!@baseboard_fab2_lib.baseboard_fab2(sch_1):page120_i147@chpset_lib.lbg_core_qat_ext_c(chips)!LBG_CORE_QAT_EXT_C_BGA1-IC,TBD!!!F2049!GPP_F7_SATA_DEVSLP5!!!!
S!JTAG_PCH_PLD_TMS!U7C1!AH9!@baseboard_fab2_lib.baseboard_fab2(sch_1):page120_i147@chpset_lib.lbg_core_qat_ext_c(chips)!LBG_CORE_QAT_EXT_C_BGA1-IC,TBD!!!F2049!GPP_F8_SATA_DEVSLP6!!!!
S!JTAG_PCH_PLD_TDO!U7C1!AR20!@baseboard_fab2_lib.baseboard_fab2(sch_1):page120_i147@chpset_lib.lbg_core_qat_ext_c(chips)!LBG_CORE_QAT_EXT_C_BGA1-IC,TBD!!!F2049!GPP_F9_SATA_DEVSLP7!!!!
S!FAN_TACH0!U7C1!AY11!@baseboard_fab2_lib.baseboard_fab2(sch_1):page120_i147@chpset_lib.lbg_core_qat_ext_c(chips)!LBG_CORE_QAT_EXT_C_BGA1-IC,TBD!!!F2049!GPP_G0_FANTACH0_FANTACH0IE!!!!
S!FM_CPU0_FIVR_FAULT_LVT3_N!U7C1!BE11!@baseboard_fab2_lib.baseboard_fab2(sch_1):page120_i147@chpset_lib.lbg_core_qat_ext_c(chips)!LBG_CORE_QAT_EXT_C_BGA1-IC,TBD!!!F2049!GPP_G10_FANPWM2_FANPWM2IE!!!!
S!FM_CPU1_FIVR_FAULT_LVT3_N!U7C1!BA20!@baseboard_fab2_lib.baseboard_fab2(sch_1):page120_i147@chpset_lib.lbg_core_qat_ext_c(chips)!LBG_CORE_QAT_EXT_C_BGA1-IC,TBD!!!F2049!GPP_G11_FANPWM3_FANPMW3IE!!!!
S!FM_BOARD_SKU_ID0!U7C1!BD13!@baseboard_fab2_lib.baseboard_fab2(sch_1):page120_i147@chpset_lib.lbg_core_qat_ext_c(chips)!LBG_CORE_QAT_EXT_C_BGA1-IC,TBD!!!F2049!GPP_G12!!!!
S!FM_BOARD_SKU_ID1!U7C1!AY18!@baseboard_fab2_lib.baseboard_fab2(sch_1):page120_i147@chpset_lib.lbg_core_qat_ext_c(chips)!LBG_CORE_QAT_EXT_C_BGA1-IC,TBD!!!F2049!GPP_G13!!!!
S!FM_BOARD_SKU_ID2!U7C1!AV7!@baseboard_fab2_lib.baseboard_fab2(sch_1):page120_i147@chpset_lib.lbg_core_qat_ext_c(chips)!LBG_CORE_QAT_EXT_C_BGA1-IC,TBD!!!F2049!GPP_G14!!!!
S!FM_BOARD_SKU_ID3!U7C1!BE18!@baseboard_fab2_lib.baseboard_fab2(sch_1):page120_i147@chpset_lib.lbg_core_qat_ext_c(chips)!LBG_CORE_QAT_EXT_C_BGA1-IC,TBD!!!F2049!GPP_G15!!!!
S!FM_BOARD_SKU_ID4!U7C1!BD17!@baseboard_fab2_lib.baseboard_fab2(sch_1):page120_i147@chpset_lib.lbg_core_qat_ext_c(chips)!LBG_CORE_QAT_EXT_C_BGA1-IC,TBD!!!F2049!GPP_G16!!!!
S!FM_ADR_COMPLETE_R1!U7C1!BD9!@baseboard_fab2_lib.baseboard_fab2(sch_1):page120_i147@chpset_lib.lbg_core_qat_ext_c(chips)!LBG_CORE_QAT_EXT_C_BGA1-IC,TBD!!!F2049!GPP_G17_ADR_COMPLETE!!!!
S!FM_NMI_EVENT_N!U7C1!BE7!@baseboard_fab2_lib.baseboard_fab2(sch_1):page120_i147@chpset_lib.lbg_core_qat_ext_c(chips)!LBG_CORE_QAT_EXT_C_BGA1-IC,TBD!!!F2049!GPP_G18_NMI_N!!!!
S!FM_BIOS_SMI_ACTIVE_N!U7C1!BE15!@baseboard_fab2_lib.baseboard_fab2(sch_1):page120_i147@chpset_lib.lbg_core_qat_ext_c(chips)!LBG_CORE_QAT_EXT_C_BGA1-IC,TBD!!!F2049!GPP_G19_SMI_N!!!!
S!FAN_TACH1!U7C1!AV15!@baseboard_fab2_lib.baseboard_fab2(sch_1):page120_i147@chpset_lib.lbg_core_qat_ext_c(chips)!LBG_CORE_QAT_EXT_C_BGA1-IC,TBD!!!F2049!GPP_G1_FANTACH1_FANTACH1IE!!!!
S!IRQ_FORCE_NM_THROTTLE_N!U7C1!BA17!@baseboard_fab2_lib.baseboard_fab2(sch_1):page120_i147@chpset_lib.lbg_core_qat_ext_c(chips)!LBG_CORE_QAT_EXT_C_BGA1-IC,TBD!!!F2049!GPP_G20_SSATA_DEVSLP0!!!!
S!FM_SOL_UART_CH_SEL!U7C1!BG7!@baseboard_fab2_lib.baseboard_fab2(sch_1):page120_i147@chpset_lib.lbg_core_qat_ext_c(chips)!LBG_CORE_QAT_EXT_C_BGA1-IC,TBD!!!F2049!GPP_G21_SSATA_DEVSLP1!!!!
S!FM_CPU0_RC_ERROR_N!U7C1!BD20!@baseboard_fab2_lib.baseboard_fab2(sch_1):page120_i147@chpset_lib.lbg_core_qat_ext_c(chips)!LBG_CORE_QAT_EXT_C_BGA1-IC,TBD!!!F2049!GPP_G22_SSATA_DEVSLP2!!!!
S!FM_UARTSW_MSB_N!U7C1!BA13!@baseboard_fab2_lib.baseboard_fab2(sch_1):page120_i147@chpset_lib.lbg_core_qat_ext_c(chips)!LBG_CORE_QAT_EXT_C_BGA1-IC,TBD!!!F2049!GPP_G23_SSATAXPCIE0_SSATAGP0!!!!
S!FAN_TACH2!U7C1!BE22!@baseboard_fab2_lib.baseboard_fab2(sch_1):page120_i147@chpset_lib.lbg_core_qat_ext_c(chips)!LBG_CORE_QAT_EXT_C_BGA1-IC,TBD!!!F2049!GPP_G2_FANTACH2_FANTACH2IE!!!!
S!FAN_TACH3!U7C1!AY7!@baseboard_fab2_lib.baseboard_fab2(sch_1):page120_i147@chpset_lib.lbg_core_qat_ext_c(chips)!LBG_CORE_QAT_EXT_C_BGA1-IC,TBD!!!F2049!GPP_G3_FANTACH3_FANTACH3IE!!!!
S!IRQ_PVCCIN_CPU0_VRHOT_LVC3_N!U7C1!BA9!@baseboard_fab2_lib.baseboard_fab2(sch_1):page120_i147@chpset_lib.lbg_core_qat_ext_c(chips)!LBG_CORE_QAT_EXT_C_BGA1-IC,TBD!!!F2049!GPP_G4_FANTACH4_FANTACH4IE!!!!
S!IRQ_PVCCIN_CPU1_VRHOT_LVC3_N!U7C1!AW20!@baseboard_fab2_lib.baseboard_fab2(sch_1):page120_i147@chpset_lib.lbg_core_qat_ext_c(chips)!LBG_CORE_QAT_EXT_C_BGA1-IC,TBD!!!F2049!GPP_G5_FANTACH5_FANTACH5IE!!!!
S!FM_CPU1_THERMTRIP_LATCH_LVT3_N!U7C1!AV18!@baseboard_fab2_lib.baseboard_fab2(sch_1):page120_i147@chpset_lib.lbg_core_qat_ext_c(chips)!LBG_CORE_QAT_EXT_C_BGA1-IC,TBD!!!F2049!GPP_G6_FANTACH6_FANTACH6IE!!!!
S!FM_THROTTLE_N!U7C1!AY15!@baseboard_fab2_lib.baseboard_fab2(sch_1):page120_i147@chpset_lib.lbg_core_qat_ext_c(chips)!LBG_CORE_QAT_EXT_C_BGA1-IC,TBD!!!F2049!GPP_G7_FANTACH7_FANTACH7IE!!!!
S!FAN_PWM_OUT_SYS0!U7C1!BG11!@baseboard_fab2_lib.baseboard_fab2(sch_1):page120_i147@chpset_lib.lbg_core_qat_ext_c(chips)!LBG_CORE_QAT_EXT_C_BGA1-IC,TBD!!!F2049!GPP_G8_FANPWM0_FANPWM0IE!!!!
S!FAN_PWM_OUT_SYS1!U7C1!AV11!@baseboard_fab2_lib.baseboard_fab2(sch_1):page120_i147@chpset_lib.lbg_core_qat_ext_c(chips)!LBG_CORE_QAT_EXT_C_BGA1-IC,TBD!!!F2049!GPP_G9_FANPWM1_FAMPWM1IE!!!!
S!FM_UARTSW_LSB_N!U7C1!AT4!@baseboard_fab2_lib.baseboard_fab2(sch_1):page120_i147@chpset_lib.lbg_core_qat_ext_c(chips)!LBG_CORE_QAT_EXT_C_BGA1-IC,TBD!!!F2049!GPP_H0_SRCCLKREQ6_N!!!!
S!SMB_VR_STBY_LVC3_SCL_R1!U7C1!BA4!@baseboard_fab2_lib.baseboard_fab2(sch_1):page120_i147@chpset_lib.lbg_core_qat_ext_c(chips)!LBG_CORE_QAT_EXT_C_BGA1-IC,TBD!!!F2049!GPP_H10_SML2CLK_IE!!!!
S!SMB_VR_STBY_LVC3_SDA_R1!U7C1!BD1!@baseboard_fab2_lib.baseboard_fab2(sch_1):page120_i147@chpset_lib.lbg_core_qat_ext_c(chips)!LBG_CORE_QAT_EXT_C_BGA1-IC,TBD!!!F2049!GPP_H11_SML2DATA_IE!!!!
S!FM_CPU0_RC_ERROR_N!U7C1!BB1!@baseboard_fab2_lib.baseboard_fab2(sch_1):page120_i147@chpset_lib.lbg_core_qat_ext_c(chips)!LBG_CORE_QAT_EXT_C_BGA1-IC,TBD!!!F2049!GPP_H12_SML2ALERT_N_IE_N!!!!
S!SMB_SENSOR_STBY_LVC3_SCL_R1!U7C1!AY1!@baseboard_fab2_lib.baseboard_fab2(sch_1):page120_i147@chpset_lib.lbg_core_qat_ext_c(chips)!LBG_CORE_QAT_EXT_C_BGA1-IC,TBD!!!F2049!GPP_H13_SML3CLK_IE!!!!
S!SMB_SENSOR_STBY_LVC3_SDA_R1!U7C1!BC2!@baseboard_fab2_lib.baseboard_fab2(sch_1):page120_i147@chpset_lib.lbg_core_qat_ext_c(chips)!LBG_CORE_QAT_EXT_C_BGA1-IC,TBD!!!F2049!GPP_H14_SML3DATA_IE!!!!
S!PU_ADR_TIMER_HOLD_OFF_N!U7C1!BB3!@baseboard_fab2_lib.baseboard_fab2(sch_1):page120_i147@chpset_lib.lbg_core_qat_ext_c(chips)!LBG_CORE_QAT_EXT_C_BGA1-IC,TBD!!!F2049!GPP_H15_SML3ALERT_N_IE_N!!!!
S!SMB_LAN_STBY_LVC3_SCL_R1!U7C1!BF1!@baseboard_fab2_lib.baseboard_fab2(sch_1):page120_i147@chpset_lib.lbg_core_qat_ext_c(chips)!LBG_CORE_QAT_EXT_C_BGA1-IC,TBD!!!F2049!GPP_H16_SML4CLK_IE!!!!
S!SMB_LAN_STBY_LVC3_SDA_R1!U7C1!BE4!@baseboard_fab2_lib.baseboard_fab2(sch_1):page120_i147@chpset_lib.lbg_core_qat_ext_c(chips)!LBG_CORE_QAT_EXT_C_BGA1-IC,TBD!!!F2049!GPP_H17_SML4DATA_IE!!!!
S!FM_OC_DETECT_EN_N!U7C1!BC4!@baseboard_fab2_lib.baseboard_fab2(sch_1):page120_i147@chpset_lib.lbg_core_qat_ext_c(chips)!LBG_CORE_QAT_EXT_C_BGA1-IC,TBD!!!F2049!GPP_H18_SML4ALERT_N_IE_N!!!!
S!FP_PWR_ID_LED_N!U7C1!BD3!@baseboard_fab2_lib.baseboard_fab2(sch_1):page120_i147@chpset_lib.lbg_core_qat_ext_c(chips)!LBG_CORE_QAT_EXT_C_BGA1-IC,TBD!!!F2049!GPP_H19_SSATAXPCIE1_SSATAGP1!!!!
S!FM_BACKUP_BIOS_SEL_N!U7C1!AW4!@baseboard_fab2_lib.baseboard_fab2(sch_1):page120_i147@chpset_lib.lbg_core_qat_ext_c(chips)!LBG_CORE_QAT_EXT_C_BGA1-IC,TBD!!!F2049!GPP_H1_SRCCLKREQ7_N!!!!
S!FM_BMC_NMI_N!U7C1!BF3!@baseboard_fab2_lib.baseboard_fab2(sch_1):page120_i147@chpset_lib.lbg_core_qat_ext_c(chips)!LBG_CORE_QAT_EXT_C_BGA1-IC,TBD!!!F2049!GPP_H20_SSATAXPCIE2_SSATAGP2!!!!
S!FM_BIOS_SMI_ACTIVE_N!U7C1!BA2!@baseboard_fab2_lib.baseboard_fab2(sch_1):page120_i147@chpset_lib.lbg_core_qat_ext_c(chips)!LBG_CORE_QAT_EXT_C_BGA1-IC,TBD!!!F2049!GPP_H21_SSATAXPCIE3_SSATAGP3!!!!
S!FM_PCH_BMC_THERMTRIP_N!U7C1!BH2!@baseboard_fab2_lib.baseboard_fab2(sch_1):page120_i147@chpset_lib.lbg_core_qat_ext_c(chips)!LBG_CORE_QAT_EXT_C_BGA1-IC,TBD!!!F2049!GPP_H22_SSATAXPCIE4_SSATAGP4!!!!
S!FM_SSATA_PCIE_M2_SEL!U7C1!BH4!@baseboard_fab2_lib.baseboard_fab2(sch_1):page120_i147@chpset_lib.lbg_core_qat_ext_c(chips)!LBG_CORE_QAT_EXT_C_BGA1-IC,TBD!!!F2049!GPP_H23_SSATAXPCIE5_SSATAGP5!!!!
S!LED_POSTCODE_0!U7C1!AV3!@baseboard_fab2_lib.baseboard_fab2(sch_1):page120_i147@chpset_lib.lbg_core_qat_ext_c(chips)!LBG_CORE_QAT_EXT_C_BGA1-IC,TBD!!!F2049!GPP_H2_SRCCLKREQ8_N!!!!
S!LED_POSTCODE_1!U7C1!AR1!@baseboard_fab2_lib.baseboard_fab2(sch_1):page120_i147@chpset_lib.lbg_core_qat_ext_c(chips)!LBG_CORE_QAT_EXT_C_BGA1-IC,TBD!!!F2049!GPP_H3_SRCCLKREQ9_N!!!!
S!LED_POSTCODE_2!U7C1!AT2!@baseboard_fab2_lib.baseboard_fab2(sch_1):page120_i147@chpset_lib.lbg_core_qat_ext_c(chips)!LBG_CORE_QAT_EXT_C_BGA1-IC,TBD!!!F2049!GPP_H4_SRCCLKREQ10_N!!!!
S!LED_POSTCODE_3!U7C1!AY3!@baseboard_fab2_lib.baseboard_fab2(sch_1):page120_i147@chpset_lib.lbg_core_qat_ext_c(chips)!LBG_CORE_QAT_EXT_C_BGA1-IC,TBD!!!F2049!GPP_H5_SRCCLKREQ11_N!!!!
S!LED_POSTCODE_4!U7C1!AW2!@baseboard_fab2_lib.baseboard_fab2(sch_1):page120_i147@chpset_lib.lbg_core_qat_ext_c(chips)!LBG_CORE_QAT_EXT_C_BGA1-IC,TBD!!!F2049!GPP_H6_SRCCLKREQ12_N!!!!
S!LED_POSTCODE_5!U7C1!AV1!@baseboard_fab2_lib.baseboard_fab2(sch_1):page120_i147@chpset_lib.lbg_core_qat_ext_c(chips)!LBG_CORE_QAT_EXT_C_BGA1-IC,TBD!!!F2049!GPP_H7_SRCCLKREQ13_N!!!!
S!LED_POSTCODE_6!U7C1!AR3!@baseboard_fab2_lib.baseboard_fab2(sch_1):page120_i147@chpset_lib.lbg_core_qat_ext_c(chips)!LBG_CORE_QAT_EXT_C_BGA1-IC,TBD!!!F2049!GPP_H8_SRCCLKREQ14_N!!!!
S!LED_POSTCODE_7!U7C1!BE2!@baseboard_fab2_lib.baseboard_fab2(sch_1):page120_i147@chpset_lib.lbg_core_qat_ext_c(chips)!LBG_CORE_QAT_EXT_C_BGA1-IC,TBD!!!F2049!GPP_H9_SRCCLKREQ15_N!!!!
S!JTAG_PCH_GBE_TDO!U7C1!CA20!@baseboard_fab2_lib.baseboard_fab2(sch_1):page120_i147@chpset_lib.lbg_core_qat_ext_c(chips)!LBG_CORE_QAT_EXT_C_BGA1-IC,TBD!!!F2049!GPP_I0_LAN_TDO!!!!
S!FM_BIOS_MRC_DEBUG_MSG_DIS_N!U7C1!BV25!@baseboard_fab2_lib.baseboard_fab2(sch_1):page120_i147@chpset_lib.lbg_core_qat_ext_c(chips)!LBG_CORE_QAT_EXT_C_BGA1-IC,TBD!!!F2049!GPP_I10!!!!
S!JTAG_PCH_GBE_CLK!U7C1!BV21!@baseboard_fab2_lib.baseboard_fab2(sch_1):page120_i147@chpset_lib.lbg_core_qat_ext_c(chips)!LBG_CORE_QAT_EXT_C_BGA1-IC,TBD!!!F2049!GPP_I1_LAN_TCK!!!!
S!JTAG_PCH_GBE_TMS!U7C1!CA22!@baseboard_fab2_lib.baseboard_fab2(sch_1):page120_i147@chpset_lib.lbg_core_qat_ext_c(chips)!LBG_CORE_QAT_EXT_C_BGA1-IC,TBD!!!F2049!GPP_I2_LAN_TMS!!!!
S!JTAG_PCH_GBE_TDI!U7C1!BY23!@baseboard_fab2_lib.baseboard_fab2(sch_1):page120_i147@chpset_lib.lbg_core_qat_ext_c(chips)!LBG_CORE_QAT_EXT_C_BGA1-IC,TBD!!!F2049!GPP_I3_LAN_TDI!!!!
S!IRQ_DIMM_SAVE_LVT3_N!U7C1!BW20!@baseboard_fab2_lib.baseboard_fab2(sch_1):page120_i147@chpset_lib.lbg_core_qat_ext_c(chips)!LBG_CORE_QAT_EXT_C_BGA1-IC,TBD!!!F2049!GPP_I4_DO_RESET_IN_N!!!!
S!IRQ_BOARD_BMC_ALERT_N!U7C1!BW24!@baseboard_fab2_lib.baseboard_fab2(sch_1):page120_i147@chpset_lib.lbg_core_qat_ext_c(chips)!LBG_CORE_QAT_EXT_C_BGA1-IC,TBD!!!F2049!GPP_I5_DO_RESET_OUT_N!!!!
S!FM_CPU1_RC_ERROR_N!U7C1!BV23!@baseboard_fab2_lib.baseboard_fab2(sch_1):page120_i147@chpset_lib.lbg_core_qat_ext_c(chips)!LBG_CORE_QAT_EXT_C_BGA1-IC,TBD!!!F2049!GPP_I6_RESET_DONE!!!!
S!JTAG_PCH_GBE_TRST_N!U7C1!CA24!@baseboard_fab2_lib.baseboard_fab2(sch_1):page120_i147@chpset_lib.lbg_core_qat_ext_c(chips)!LBG_CORE_QAT_EXT_C_BGA1-IC,TBD!!!F2049!GPP_I7_LAN_TRST_N!!!!
S!PU_10GBE_LOM_PCI_DISABLE_N!U7C1!BW22!@baseboard_fab2_lib.baseboard_fab2(sch_1):page120_i147@chpset_lib.lbg_core_qat_ext_c(chips)!LBG_CORE_QAT_EXT_C_BGA1-IC,TBD!!!F2049!GPP_I8_PCI_DIS_N!!!!
S!FM_10GBE_LOM_DISABLE_N!U7C1!BY21!@baseboard_fab2_lib.baseboard_fab2(sch_1):page120_i147@chpset_lib.lbg_core_qat_ext_c(chips)!LBG_CORE_QAT_EXT_C_BGA1-IC,TBD!!!F2049!GPP_I9_LAN_DIS_N!!!!
S!LED_GBE_P0_0!U7C1!BL1!@baseboard_fab2_lib.baseboard_fab2(sch_1):page120_i147@chpset_lib.lbg_core_qat_ext_c(chips)!LBG_CORE_QAT_EXT_C_BGA1-IC,TBD!!!F2049!GPP_J0_LAN_LED_P0_0!!!!
S!SMB_PCH_MEZZ_LOM1_SCL!U7C1!BW5!@baseboard_fab2_lib.baseboard_fab2(sch_1):page120_i147@chpset_lib.lbg_core_qat_ext_c(chips)!LBG_CORE_QAT_EXT_C_BGA1-IC,TBD!!!F2049!GPP_J10_LAN_I2C_SCL_MDC_P1!!!!
S!SMB_PCH_MEZZ_LOM1_SDA!U7C1!BV8!@baseboard_fab2_lib.baseboard_fab2(sch_1):page120_i147@chpset_lib.lbg_core_qat_ext_c(chips)!LBG_CORE_QAT_EXT_C_BGA1-IC,TBD!!!F2049!GPP_J11_LAN_I2C_SDA_MDIO_P1!!!!
S!SMB_PCH_MEZZ_LOM2_SCL!U7C1!BT5!@baseboard_fab2_lib.baseboard_fab2(sch_1):page120_i147@chpset_lib.lbg_core_qat_ext_c(chips)!LBG_CORE_QAT_EXT_C_BGA1-IC,TBD!!!F2049!GPP_J12_LAN_I2C_SCL_MDC_P2!!!!
S!SMB_PCH_MEZZ_LOM2_SDA!U7C1!BW11!@baseboard_fab2_lib.baseboard_fab2(sch_1):page120_i147@chpset_lib.lbg_core_qat_ext_c(chips)!LBG_CORE_QAT_EXT_C_BGA1-IC,TBD!!!F2049!GPP_J13_LAN_I2C_SDA_MDIO_P2!!!!
S!SMB_PCH_MEZZ_LOM3_SCL!U7C1!BW6!@baseboard_fab2_lib.baseboard_fab2(sch_1):page120_i147@chpset_lib.lbg_core_qat_ext_c(chips)!LBG_CORE_QAT_EXT_C_BGA1-IC,TBD!!!F2049!GPP_J14_LAN_I2C_SCL_MDC_P3!!!!
S!SMB_PCH_MEZZ_LOM3_SDA!U7C1!BW9!@baseboard_fab2_lib.baseboard_fab2(sch_1):page120_i147@chpset_lib.lbg_core_qat_ext_c(chips)!LBG_CORE_QAT_EXT_C_BGA1-IC,TBD!!!F2049!GPP_J15_LAN_I2C_SDA_MDIO_P3!!!!
S!FM_GBE0_LVC3_MOD_ABS!U7C1!BV10!@baseboard_fab2_lib.baseboard_fab2(sch_1):page120_i147@chpset_lib.lbg_core_qat_ext_c(chips)!LBG_CORE_QAT_EXT_C_BGA1-IC,TBD!!!F2049!GPP_J16_LAN_SDP_P0_0!!!!
S!TP_PCH_GPP_J17!U7C1!CA11!@baseboard_fab2_lib.baseboard_fab2(sch_1):page120_i147@chpset_lib.lbg_core_qat_ext_c(chips)!LBG_CORE_QAT_EXT_C_BGA1-IC,TBD!!!F2049!GPP_J17_LAN_SDP_P0_1!!!!
S!FM_GBE1_LVC3_MOD_ABS!U7C1!BY10!@baseboard_fab2_lib.baseboard_fab2(sch_1):page120_i147@chpset_lib.lbg_core_qat_ext_c(chips)!LBG_CORE_QAT_EXT_C_BGA1-IC,TBD!!!F2049!GPP_J18_LAN_SDP_P1_0!!!!
S!TP_PCH_GPP_J19!U7C1!BY14!@baseboard_fab2_lib.baseboard_fab2(sch_1):page120_i147@chpset_lib.lbg_core_qat_ext_c(chips)!LBG_CORE_QAT_EXT_C_BGA1-IC,TBD!!!F2049!GPP_J19_LAN_SDP_P1_1!!!!
S!LED_GBE_P0_1!U7C1!BK4!@baseboard_fab2_lib.baseboard_fab2(sch_1):page120_i147@chpset_lib.lbg_core_qat_ext_c(chips)!LBG_CORE_QAT_EXT_C_BGA1-IC,TBD!!!F2049!GPP_J1_LAN_LED_P0_1!!!!
S!FM_GBE2_LVC3_MOD_ABS!U7C1!BW13!@baseboard_fab2_lib.baseboard_fab2(sch_1):page120_i147@chpset_lib.lbg_core_qat_ext_c(chips)!LBG_CORE_QAT_EXT_C_BGA1-IC,TBD!!!F2049!GPP_J20_LAN_SDP_P2_0!!!!
S!TP_PCH_GPP_J21!U7C1!BV12!@baseboard_fab2_lib.baseboard_fab2(sch_1):page120_i147@chpset_lib.lbg_core_qat_ext_c(chips)!LBG_CORE_QAT_EXT_C_BGA1-IC,TBD!!!F2049!GPP_J21_LAN_SDP_P2_1!!!!
S!FM_GBE3_LVC3_MOD_ABS!U7C1!BY12!@baseboard_fab2_lib.baseboard_fab2(sch_1):page120_i147@chpset_lib.lbg_core_qat_ext_c(chips)!LBG_CORE_QAT_EXT_C_BGA1-IC,TBD!!!F2049!GPP_J22_LAN_SDP_P3_0!!!!
S!TP_PCH_GPP_J23!U7C1!BV14!@baseboard_fab2_lib.baseboard_fab2(sch_1):page120_i147@chpset_lib.lbg_core_qat_ext_c(chips)!LBG_CORE_QAT_EXT_C_BGA1-IC,TBD!!!F2049!GPP_J23_LAN_SDP_P3_1!!!!
S!LED_GBE_P1_0!U7C1!BP4!@baseboard_fab2_lib.baseboard_fab2(sch_1):page120_i147@chpset_lib.lbg_core_qat_ext_c(chips)!LBG_CORE_QAT_EXT_C_BGA1-IC,TBD!!!F2049!GPP_J2_LAN_LED_P1_0!!!!
S!LED_GBE_P1_1!U7C1!BK2!@baseboard_fab2_lib.baseboard_fab2(sch_1):page120_i147@chpset_lib.lbg_core_qat_ext_c(chips)!LBG_CORE_QAT_EXT_C_BGA1-IC,TBD!!!F2049!GPP_J3_LAN_LED_P1_1!!!!
S!LED_GBE_P2_0!U7C1!BL3!@baseboard_fab2_lib.baseboard_fab2(sch_1):page120_i147@chpset_lib.lbg_core_qat_ext_c(chips)!LBG_CORE_QAT_EXT_C_BGA1-IC,TBD!!!F2049!GPP_J4_LAN_LED_P2_0!!!!
S!LED_GBE_P2_1!U7C1!BU6!@baseboard_fab2_lib.baseboard_fab2(sch_1):page120_i147@chpset_lib.lbg_core_qat_ext_c(chips)!LBG_CORE_QAT_EXT_C_BGA1-IC,TBD!!!F2049!GPP_J5_LAN_LED_P2_1!!!!
S!LED_GBE_P3_0!U7C1!CA13!@baseboard_fab2_lib.baseboard_fab2(sch_1):page120_i147@chpset_lib.lbg_core_qat_ext_c(chips)!LBG_CORE_QAT_EXT_C_BGA1-IC,TBD!!!F2049!GPP_J6_LAN_LED_P3_0!!!!
S!LED_GBE_P3_1!U7C1!BM2!@baseboard_fab2_lib.baseboard_fab2(sch_1):page120_i147@chpset_lib.lbg_core_qat_ext_c(chips)!LBG_CORE_QAT_EXT_C_BGA1-IC,TBD!!!F2049!GPP_J7_LAN_LED_P3_1!!!!
S!SMB_PCH_MEZZ_LOM0_SCL!U7C1!BM4!@baseboard_fab2_lib.baseboard_fab2(sch_1):page120_i147@chpset_lib.lbg_core_qat_ext_c(chips)!LBG_CORE_QAT_EXT_C_BGA1-IC,TBD!!!F2049!GPP_J8_LAN_I2C_SCL_MDC_P0!!!!
S!SMB_PCH_MEZZ_LOM0_SDA!U7C1!BN3!@baseboard_fab2_lib.baseboard_fab2(sch_1):page120_i147@chpset_lib.lbg_core_qat_ext_c(chips)!LBG_CORE_QAT_EXT_C_BGA1-IC,TBD!!!F2049!GPP_J9_LAN_I2C_SDA_MDIO_P0!!!!
S!FM_PCH_PRSNT_N!U7C1!C70!@baseboard_fab2_lib.baseboard_fab2(sch_1):page121_i34@chpset_lib.lbg_core_qat_ext_c(chips)!LBG_CORE_QAT_EXT_C_BGA1-IC,TBD!!!F2048!CGC_DUT_DETECT_N!!!!
S!TP_PCH_DISPA_BCLK!U7C1!U20!@baseboard_fab2_lib.baseboard_fab2(sch_1):page121_i34@chpset_lib.lbg_core_qat_ext_c(chips)!LBG_CORE_QAT_EXT_C_BGA1-IC,TBD!!!F2048!RSVD(66)!!!!
S!TP_PCH_DISPA_SDI!U7C1!R20!@baseboard_fab2_lib.baseboard_fab2(sch_1):page121_i34@chpset_lib.lbg_core_qat_ext_c(chips)!LBG_CORE_QAT_EXT_C_BGA1-IC,TBD!!!F2048!RSVD(67)!!!!
S!TP_PCH_DISPA_SDO!U7C1!V22!@baseboard_fab2_lib.baseboard_fab2(sch_1):page121_i34@chpset_lib.lbg_core_qat_ext_c(chips)!LBG_CORE_QAT_EXT_C_BGA1-IC,TBD!!!F2048!RSVD(68)!!!!
S!A_1P8_3P3_RCOMP!U7C1!AM4!@baseboard_fab2_lib.baseboard_fab2(sch_1):page121_i34@chpset_lib.lbg_core_qat_ext_c(chips)!LBG_CORE_QAT_EXT_C_BGA1-IC,TBD!!!F2048!GPIO_RCOMP_1P8_3P3!!!!
S!CLK_50M_CKMNG_PCH_10GBE!U7C1!AJ1!@baseboard_fab2_lib.baseboard_fab2(sch_1):page121_i34@chpset_lib.lbg_core_qat_ext_c(chips)!LBG_CORE_QAT_EXT_C_BGA1-IC,TBD!!!F2048!GPP_K0_LAN_NCSI_CLK_IN!!!!
S!RST_PCIE_PCH_PERST_N!U7C1!AH4!@baseboard_fab2_lib.baseboard_fab2(sch_1):page121_i34@chpset_lib.lbg_core_qat_ext_c(chips)!LBG_CORE_QAT_EXT_C_BGA1-IC,TBD!!!F2048!GPP_K10_PE_RST_N!!!!
S!RMII_BMC_PCH_SPRNGVLLE_TXD0!U7C1!AL1!@baseboard_fab2_lib.baseboard_fab2(sch_1):page121_i34@chpset_lib.lbg_core_qat_ext_c(chips)!LBG_CORE_QAT_EXT_C_BGA1-IC,TBD!!!F2048!GPP_K5_LAN_NCSI_RXD0!!!!
S!RMII_BMC_PCH_SPRNGVLLE_TXD1!U7C1!AN1!@baseboard_fab2_lib.baseboard_fab2(sch_1):page121_i34@chpset_lib.lbg_core_qat_ext_c(chips)!LBG_CORE_QAT_EXT_C_BGA1-IC,TBD!!!F2048!GPP_K6_LAN_NCSI_RXD1!!!!
S!RMII_BMC_PCH_SPRNGVLLE_TXEN!U7C1!AN3!@baseboard_fab2_lib.baseboard_fab2(sch_1):page121_i34@chpset_lib.lbg_core_qat_ext_c(chips)!LBG_CORE_QAT_EXT_C_BGA1-IC,TBD!!!F2048!GPP_K4_LAN_NCSI_CRS_DV!!!!
S!RMII_BMC_PCH_SPRNGVLLE_CRSDV_R1!U7C1!AL3!@baseboard_fab2_lib.baseboard_fab2(sch_1):page121_i34@chpset_lib.lbg_core_qat_ext_c(chips)!LBG_CORE_QAT_EXT_C_BGA1-IC,TBD!!!F2048!GPP_K3_LAN_NCSI_TX_EN!!!!
S!RMII_SPRNGVLLE_BMC_PCH_RXD0_R1!U7C1!AM2!@baseboard_fab2_lib.baseboard_fab2(sch_1):page121_i34@chpset_lib.lbg_core_qat_ext_c(chips)!LBG_CORE_QAT_EXT_C_BGA1-IC,TBD!!!F2048!GPP_K1_LAN_NCSI_TXD0!!!!
S!RMII_SPRNGVLLE_BMC_PCH_RXD1_R1!U7C1!AK2!@baseboard_fab2_lib.baseboard_fab2(sch_1):page121_i34@chpset_lib.lbg_core_qat_ext_c(chips)!LBG_CORE_QAT_EXT_C_BGA1-IC,TBD!!!F2048!GPP_K2_LAN_NCSI_TXD1!!!!
S!RMII_BMC_PCH_SPRNGVLLE_RXER_R!U7C1!AH2!@baseboard_fab2_lib.baseboard_fab2(sch_1):page121_i34@chpset_lib.lbg_core_qat_ext_c(chips)!LBG_CORE_QAT_EXT_C_BGA1-IC,TBD!!!F2048!GPP_K7!!!!
S!RMII_PCH_SPRNGVLLE_ARB_IN!U7C1!AJ3!@baseboard_fab2_lib.baseboard_fab2(sch_1):page121_i34@chpset_lib.lbg_core_qat_ext_c(chips)!LBG_CORE_QAT_EXT_C_BGA1-IC,TBD!!!F2048!GPP_K8_LAN_NCSI_ARB_IN!!!!
S!RMII_PCH_SPRNGVLLE_ARB_OUT_R!U7C1!AK4!@baseboard_fab2_lib.baseboard_fab2(sch_1):page121_i34@chpset_lib.lbg_core_qat_ext_c(chips)!LBG_CORE_QAT_EXT_C_BGA1-IC,TBD!!!F2048!GPP_K9_LAN_NCSI_ARB_OUT!!!!
S!TP_PCH_GPP_L10!U7C1!AF20!@baseboard_fab2_lib.baseboard_fab2(sch_1):page121_i34@chpset_lib.lbg_core_qat_ext_c(chips)!LBG_CORE_QAT_EXT_C_BGA1-IC,TBD!!!F2048!GPP_L10_TESTCH0_CLK!!!!
S!TP_PCH_GPP_L11!U7C1!AD20!@baseboard_fab2_lib.baseboard_fab2(sch_1):page121_i34@chpset_lib.lbg_core_qat_ext_c(chips)!LBG_CORE_QAT_EXT_C_BGA1-IC,TBD!!!F2048!GPP_L11_TESTCH1_D0!!!!
S!H_CPU0_MEMABC_MEMHOT_PCH_N!U7C1!Y15!@baseboard_fab2_lib.baseboard_fab2(sch_1):page121_i34@chpset_lib.lbg_core_qat_ext_c(chips)!LBG_CORE_QAT_EXT_C_BGA1-IC,TBD!!!F2048!GPP_L12_TESTCH1_D1!!!!
S!H_CPU0_MEMDEF_MEMHOT_PCH_N!U7C1!AD13!@baseboard_fab2_lib.baseboard_fab2(sch_1):page121_i34@chpset_lib.lbg_core_qat_ext_c(chips)!LBG_CORE_QAT_EXT_C_BGA1-IC,TBD!!!F2048!GPP_L13_TESTCH1_D2!!!!
S!H_CPU1_MEMGHJ_MEMHOT_PCH_N!U7C1!AA13!@baseboard_fab2_lib.baseboard_fab2(sch_1):page121_i34@chpset_lib.lbg_core_qat_ext_c(chips)!LBG_CORE_QAT_EXT_C_BGA1-IC,TBD!!!F2048!GPP_L14_TESTCH1_D3!!!!
S!H_CPU1_MEMKLM_MEMHOT_PCH_N!U7C1!Y11!@baseboard_fab2_lib.baseboard_fab2(sch_1):page121_i34@chpset_lib.lbg_core_qat_ext_c(chips)!LBG_CORE_QAT_EXT_C_BGA1-IC,TBD!!!F2048!GPP_L15_TESTCH1_D4!!!!
S!FM_CPU0_PROCHOT_PCH_N!U7C1!Y7!@baseboard_fab2_lib.baseboard_fab2(sch_1):page121_i34@chpset_lib.lbg_core_qat_ext_c(chips)!LBG_CORE_QAT_EXT_C_BGA1-IC,TBD!!!F2048!GPP_L16_TESTCH1_D5!!!!
S!FM_CPU1_PROCHOT_PCH_N!U7C1!AA9!@baseboard_fab2_lib.baseboard_fab2(sch_1):page121_i34@chpset_lib.lbg_core_qat_ext_c(chips)!LBG_CORE_QAT_EXT_C_BGA1-IC,TBD!!!F2048!GPP_L17_TESTCH1_D6!!!!
S!FM_CPU_ERR0_PCH_N!U7C1!AE7!@baseboard_fab2_lib.baseboard_fab2(sch_1):page121_i34@chpset_lib.lbg_core_qat_ext_c(chips)!LBG_CORE_QAT_EXT_C_BGA1-IC,TBD!!!F2048!GPP_L18_TESTCH1_D7!!!!
S!FM_CPU_ERR1_PCH_N!U7C1!AG11!@baseboard_fab2_lib.baseboard_fab2(sch_1):page121_i34@chpset_lib.lbg_core_qat_ext_c(chips)!LBG_CORE_QAT_EXT_C_BGA1-IC,TBD!!!F2048!GPP_L19_TESTCH1_CLK!!!!
S!FM_PRSNT_2_1_N!U7C1!AE18!@baseboard_fab2_lib.baseboard_fab2(sch_1):page121_i34@chpset_lib.lbg_core_qat_ext_c(chips)!LBG_CORE_QAT_EXT_C_BGA1-IC,TBD!!!F2048!GPP_L2_TESTCH0_D0!!!!
S!FM_PRSNT_2_2_N!U7C1!AE15!@baseboard_fab2_lib.baseboard_fab2(sch_1):page121_i34@chpset_lib.lbg_core_qat_ext_c(chips)!LBG_CORE_QAT_EXT_C_BGA1-IC,TBD!!!F2048!GPP_L3_TESTCH0_D1!!!!
S!FM_PRSNT_2_3_N!U7C1!AE11!@baseboard_fab2_lib.baseboard_fab2(sch_1):page121_i34@chpset_lib.lbg_core_qat_ext_c(chips)!LBG_CORE_QAT_EXT_C_BGA1-IC,TBD!!!F2048!GPP_L4_TESTCH0_D2!!!!
S!FM_PRSNT_2_4_N!U7C1!Y18!@baseboard_fab2_lib.baseboard_fab2(sch_1):page121_i34@chpset_lib.lbg_core_qat_ext_c(chips)!LBG_CORE_QAT_EXT_C_BGA1-IC,TBD!!!F2048!GPP_L5_TESTCH0_D3!!!!
S!FM_PRSNT_2_5_N!U7C1!AA20!@baseboard_fab2_lib.baseboard_fab2(sch_1):page121_i34@chpset_lib.lbg_core_qat_ext_c(chips)!LBG_CORE_QAT_EXT_C_BGA1-IC,TBD!!!F2048!GPP_L6_TESTCH0_D4!!!!
S!FM_PRSNT_2_6_N!U7C1!AA17!@baseboard_fab2_lib.baseboard_fab2(sch_1):page121_i34@chpset_lib.lbg_core_qat_ext_c(chips)!LBG_CORE_QAT_EXT_C_BGA1-IC,TBD!!!F2048!GPP_L7_TESTCH0_D5!!!!
S!FM_OCP_MEZZB_PRES_N!U7C1!AD9!@baseboard_fab2_lib.baseboard_fab2(sch_1):page121_i34@chpset_lib.lbg_core_qat_ext_c(chips)!LBG_CORE_QAT_EXT_C_BGA1-IC,TBD!!!F2048!GPP_L8_TESTCH0_D6!!!!
S!FM_OCP_MEZZC_PRES_N!U7C1!AD17!@baseboard_fab2_lib.baseboard_fab2(sch_1):page121_i34@chpset_lib.lbg_core_qat_ext_c(chips)!LBG_CORE_QAT_EXT_C_BGA1-IC,TBD!!!F2048!GPP_L9_TESTCH0_D7!!!!
S!TP_PCH_HDA_BCLK!U7C1!P18!@baseboard_fab2_lib.baseboard_fab2(sch_1):page121_i34@chpset_lib.lbg_core_qat_ext_c(chips)!LBG_CORE_QAT_EXT_C_BGA1-IC,TBD!!!F2048!HDA_BCLK!!!!
S!TP_PCH_HSA_RST_N!U7C1!M18!@baseboard_fab2_lib.baseboard_fab2(sch_1):page121_i34@chpset_lib.lbg_core_qat_ext_c(chips)!LBG_CORE_QAT_EXT_C_BGA1-IC,TBD!!!F2048!HDA_RST_N!!!!
S!TP_PCH_HDA_SDI_0!U7C1!K20!@baseboard_fab2_lib.baseboard_fab2(sch_1):page121_i34@chpset_lib.lbg_core_qat_ext_c(chips)!LBG_CORE_QAT_EXT_C_BGA1-IC,TBD!!!F2048!HDA_SDI_0!!!!
S!TP_PCH_HDA_SDI_1!U7C1!V18!@baseboard_fab2_lib.baseboard_fab2(sch_1):page121_i34@chpset_lib.lbg_core_qat_ext_c(chips)!LBG_CORE_QAT_EXT_C_BGA1-IC,TBD!!!F2048!HDA_SDI_1!!!!
S!FM_FLASH_DESC_OVERRIDE!U7C1!U24!@baseboard_fab2_lib.baseboard_fab2(sch_1):page121_i34@chpset_lib.lbg_core_qat_ext_c(chips)!LBG_CORE_QAT_EXT_C_BGA1-IC,TBD!!!F2048!HDA_SDO!!!!
S!TP_PCH_HDA_SYNC!U7C1!H20!@baseboard_fab2_lib.baseboard_fab2(sch_1):page121_i34@chpset_lib.lbg_core_qat_ext_c(chips)!LBG_CORE_QAT_EXT_C_BGA1-IC,TBD!!!F2048!HDA_SYNC!!!!
S!FM_INTRUDER_HDR_PCH_N!U7C1!AG18!@baseboard_fab2_lib.baseboard_fab2(sch_1):page121_i34@chpset_lib.lbg_core_qat_ext_c(chips)!LBG_CORE_QAT_EXT_C_BGA1-IC,TBD!!!F2048!INTRUDER_N!!!!
S!TP_PCH_RSVD0!U7C1!AF61!@baseboard_fab2_lib.baseboard_fab2(sch_1):page121_i34@chpset_lib.lbg_core_qat_ext_c(chips)!LBG_CORE_QAT_EXT_C_BGA1-IC,TBD!!!F2048!RSVD(0)!!!!
S!FM_WBG_PRSNT_N!U7C1!D8!@baseboard_fab2_lib.baseboard_fab2(sch_1):page121_i34@chpset_lib.lbg_core_qat_ext_c(chips)!LBG_CORE_QAT_EXT_C_BGA1-IC,TBD!!!F2048!RSVD(10)!!!!
S!FM_SINT_PRSNT_N!U7C1!C18!@baseboard_fab2_lib.baseboard_fab2(sch_1):page121_i34@chpset_lib.lbg_core_qat_ext_c(chips)!LBG_CORE_QAT_EXT_C_BGA1-IC,TBD!!!F2048!RSVD(11)!!!!
S!TP_PCH_RSVD12!U7C1!C68!@baseboard_fab2_lib.baseboard_fab2(sch_1):page121_i34@chpset_lib.lbg_core_qat_ext_c(chips)!LBG_CORE_QAT_EXT_C_BGA1-IC,TBD!!!F2048!RSVD(12)!!!!
S!TP_PCH_RSVD13!U7C1!C67!@baseboard_fab2_lib.baseboard_fab2(sch_1):page121_i34@chpset_lib.lbg_core_qat_ext_c(chips)!LBG_CORE_QAT_EXT_C_BGA1-IC,TBD!!!F2048!RSVD(13)!!!!
S!TP_PCH_RSVD14!U7C1!E18!@baseboard_fab2_lib.baseboard_fab2(sch_1):page121_i34@chpset_lib.lbg_core_qat_ext_c(chips)!LBG_CORE_QAT_EXT_C_BGA1-IC,TBD!!!F2048!RSVD(14)!!!!
S!TP_PCH_RSVD15!U7C1!C6!@baseboard_fab2_lib.baseboard_fab2(sch_1):page121_i34@chpset_lib.lbg_core_qat_ext_c(chips)!LBG_CORE_QAT_EXT_C_BGA1-IC,TBD!!!F2048!RSVD(15)!!!!
S!TP_PCH_RSVD16!U7C1!C5!@baseboard_fab2_lib.baseboard_fab2(sch_1):page121_i34@chpset_lib.lbg_core_qat_ext_c(chips)!LBG_CORE_QAT_EXT_C_BGA1-IC,TBD!!!F2048!RSVD(16)!!!!
S!TP_PCH_RSVD17!U7C1!B10!@baseboard_fab2_lib.baseboard_fab2(sch_1):page121_i34@chpset_lib.lbg_core_qat_ext_c(chips)!LBG_CORE_QAT_EXT_C_BGA1-IC,TBD!!!F2048!RSVD(17)!!!!
S!TP_PCH_RSVD18!U7C1!C11!@baseboard_fab2_lib.baseboard_fab2(sch_1):page121_i34@chpset_lib.lbg_core_qat_ext_c(chips)!LBG_CORE_QAT_EXT_C_BGA1-IC,TBD!!!F2048!RSVD(18)!!!!
S!TP_PCH_RSVD19!U7C1!C9!@baseboard_fab2_lib.baseboard_fab2(sch_1):page121_i34@chpset_lib.lbg_core_qat_ext_c(chips)!LBG_CORE_QAT_EXT_C_BGA1-IC,TBD!!!F2048!RSVD(19)!!!!
S!TP_PCH_RSVD1!U7C1!AC56!@baseboard_fab2_lib.baseboard_fab2(sch_1):page121_i34@chpset_lib.lbg_core_qat_ext_c(chips)!LBG_CORE_QAT_EXT_C_BGA1-IC,TBD!!!F2048!RSVD(1)!!!!
S!TP_PCH_RSVD20!U7C1!D10!@baseboard_fab2_lib.baseboard_fab2(sch_1):page121_i34@chpset_lib.lbg_core_qat_ext_c(chips)!LBG_CORE_QAT_EXT_C_BGA1-IC,TBD!!!F2048!RSVD(20)!!!!
S!TP_PCH_RSVD21!U7C1!A11!@baseboard_fab2_lib.baseboard_fab2(sch_1):page121_i34@chpset_lib.lbg_core_qat_ext_c(chips)!LBG_CORE_QAT_EXT_C_BGA1-IC,TBD!!!F2048!RSVD(21)!!!!
S!TP_PCH_RSVD22!U7C1!AT71!@baseboard_fab2_lib.baseboard_fab2(sch_1):page121_i34@chpset_lib.lbg_core_qat_ext_c(chips)!LBG_CORE_QAT_EXT_C_BGA1-IC,TBD!!!F2048!RSVD(22)!!!!
S!TP_PCH_RSVD23!U7C1!P40!@baseboard_fab2_lib.baseboard_fab2(sch_1):page121_i34@chpset_lib.lbg_core_qat_ext_c(chips)!LBG_CORE_QAT_EXT_C_BGA1-IC,TBD!!!F2048!RSVD(23)!!!!
S!TP_PCH_RSVD24!U7C1!P44!@baseboard_fab2_lib.baseboard_fab2(sch_1):page121_i34@chpset_lib.lbg_core_qat_ext_c(chips)!LBG_CORE_QAT_EXT_C_BGA1-IC,TBD!!!F2048!RSVD(24)!!!!
S!TP_PCH_RSVD25!U7C1!P48!@baseboard_fab2_lib.baseboard_fab2(sch_1):page121_i34@chpset_lib.lbg_core_qat_ext_c(chips)!LBG_CORE_QAT_EXT_C_BGA1-IC,TBD!!!F2048!RSVD(25)!!!!
S!TP_PCH_RSVD26!U7C1!BH24!@baseboard_fab2_lib.baseboard_fab2(sch_1):page121_i34@chpset_lib.lbg_core_qat_ext_c(chips)!LBG_CORE_QAT_EXT_C_BGA1-IC,TBD!!!F2048!RSVD(26)!!!!
S!TP_PCH_RSVD27!U7C1!BG26!@baseboard_fab2_lib.baseboard_fab2(sch_1):page121_i34@chpset_lib.lbg_core_qat_ext_c(chips)!LBG_CORE_QAT_EXT_C_BGA1-IC,TBD!!!F2048!RSVD(27)!!!!
S!TP_PCH_RSVD2!U7C1!AA58!@baseboard_fab2_lib.baseboard_fab2(sch_1):page121_i34@chpset_lib.lbg_core_qat_ext_c(chips)!LBG_CORE_QAT_EXT_C_BGA1-IC,TBD!!!F2048!RSVD(2)!!!!
S!TP_PCH_RSVD3!U7C1!V11!@baseboard_fab2_lib.baseboard_fab2(sch_1):page121_i34@chpset_lib.lbg_core_qat_ext_c(chips)!LBG_CORE_QAT_EXT_C_BGA1-IC,TBD!!!F2048!RSVD(3)!!!!
S!TP_PCH_RSVD46!U7C1!BW3!@baseboard_fab2_lib.baseboard_fab2(sch_1):page121_i34@chpset_lib.lbg_core_qat_ext_c(chips)!LBG_CORE_QAT_EXT_C_BGA1-IC,TBD!!!F2048!RSVD(46)!!!!
S!TP_PCH_RSVD4!U7C1!P37!@baseboard_fab2_lib.baseboard_fab2(sch_1):page121_i34@chpset_lib.lbg_core_qat_ext_c(chips)!LBG_CORE_QAT_EXT_C_BGA1-IC,TBD!!!F2048!RSVD(4)!!!!
S!TP_PCH_RSVD5!U7C1!AG15!@baseboard_fab2_lib.baseboard_fab2(sch_1):page121_i34@chpset_lib.lbg_core_qat_ext_c(chips)!LBG_CORE_QAT_EXT_C_BGA1-IC,TBD!!!F2048!RSVD(5)!!!!
S!TP_PCH_RSVD6!U7C1!AT69!@baseboard_fab2_lib.baseboard_fab2(sch_1):page121_i34@chpset_lib.lbg_core_qat_ext_c(chips)!LBG_CORE_QAT_EXT_C_BGA1-IC,TBD!!!F2048!RSVD(6)!!!!
S!TP_PCH_RSVD7!U7C1!F8!@baseboard_fab2_lib.baseboard_fab2(sch_1):page121_i34@chpset_lib.lbg_core_qat_ext_c(chips)!LBG_CORE_QAT_EXT_C_BGA1-IC,TBD!!!F2048!RSVD(7)!!!!
S!TP_PCH_RSVD8!U7C1!F69!@baseboard_fab2_lib.baseboard_fab2(sch_1):page121_i34@chpset_lib.lbg_core_qat_ext_c(chips)!LBG_CORE_QAT_EXT_C_BGA1-IC,TBD!!!F2048!RSVD(8)!!!!
S!TP_PCH_RSVD9!U7C1!F66!@baseboard_fab2_lib.baseboard_fab2(sch_1):page121_i34@chpset_lib.lbg_core_qat_ext_c(chips)!LBG_CORE_QAT_EXT_C_BGA1-IC,TBD!!!F2048!RSVD(9)!!!!
S!RST_RTCRST_N!U7C1!P11!@baseboard_fab2_lib.baseboard_fab2(sch_1):page121_i34@chpset_lib.lbg_core_qat_ext_c(chips)!LBG_CORE_QAT_EXT_C_BGA1-IC,TBD!!!F2048!RTCRST_N!!!!
S!SPI_PCH_CLK!U7C1!K2!@baseboard_fab2_lib.baseboard_fab2(sch_1):page121_i34@chpset_lib.lbg_core_qat_ext_c(chips)!LBG_CORE_QAT_EXT_C_BGA1-IC,TBD!!!F2048!SPI0_CLK!!!!
S!SPI_PCH_CS0_R_N!U7C1!J3!@baseboard_fab2_lib.baseboard_fab2(sch_1):page121_i34@chpset_lib.lbg_core_qat_ext_c(chips)!LBG_CORE_QAT_EXT_C_BGA1-IC,TBD!!!F2048!SPI0_FLASH_CS0_N!!!!
S!TP_SPI_PCH_CS1_R1_N!U7C1!G7!@baseboard_fab2_lib.baseboard_fab2(sch_1):page121_i34@chpset_lib.lbg_core_qat_ext_c(chips)!LBG_CORE_QAT_EXT_C_BGA1-IC,TBD!!!F2048!SPI0_FLASH_CS1_N!!!!
S!SPI_PCH_IO2!U7C1!F5!@baseboard_fab2_lib.baseboard_fab2(sch_1):page121_i34@chpset_lib.lbg_core_qat_ext_c(chips)!LBG_CORE_QAT_EXT_C_BGA1-IC,TBD!!!F2048!SPI0_IO2!!!!
S!SPI_PCH_IO3!U7C1!L1!@baseboard_fab2_lib.baseboard_fab2(sch_1):page121_i34@chpset_lib.lbg_core_qat_ext_c(chips)!LBG_CORE_QAT_EXT_C_BGA1-IC,TBD!!!F2048!SPI0_IO3!!!!
S!SPI_PCH_MISO!U7C1!L3!@baseboard_fab2_lib.baseboard_fab2(sch_1):page121_i34@chpset_lib.lbg_core_qat_ext_c(chips)!LBG_CORE_QAT_EXT_C_BGA1-IC,TBD!!!F2048!SPI0_MISO_IO1!!!!
S!SPI_PCH_MOSI_R!U7C1!H4!@baseboard_fab2_lib.baseboard_fab2(sch_1):page121_i34@chpset_lib.lbg_core_qat_ext_c(chips)!LBG_CORE_QAT_EXT_C_BGA1-IC,TBD!!!F2048!SPI0_MOSI_IO0!!!!
S!SPI_PCH_TPM_CS_N!U7C1!K4!@baseboard_fab2_lib.baseboard_fab2(sch_1):page121_i34@chpset_lib.lbg_core_qat_ext_c(chips)!LBG_CORE_QAT_EXT_C_BGA1-IC,TBD!!!F2048!SPI0_TPM_CS_N!!!!
S!RST_SRTCRST_N!U7C1!G18!@baseboard_fab2_lib.baseboard_fab2(sch_1):page121_i34@chpset_lib.lbg_core_qat_ext_c(chips)!LBG_CORE_QAT_EXT_C_BGA1-IC,TBD!!!F2048!SRTCRST_N!!!!
S!TP_PCH_RSVD28!U7C1!R35!@baseboard_fab2_lib.baseboard_fab2(sch_1):page122_i63@chpset_lib.lbg_core_qat_ext_c(chips)!LBG_CORE_QAT_EXT_C_BGA1-IC,TBD!!!F2047!RSVD(28)!!!!
S!TP_PCH_RSVD29!U7C1!P33!@baseboard_fab2_lib.baseboard_fab2(sch_1):page122_i63@chpset_lib.lbg_core_qat_ext_c(chips)!LBG_CORE_QAT_EXT_C_BGA1-IC,TBD!!!F2047!RSVD(29)!!!!
S!TP_PCH_RSVD30!U7C1!R31!@baseboard_fab2_lib.baseboard_fab2(sch_1):page122_i63@chpset_lib.lbg_core_qat_ext_c(chips)!LBG_CORE_QAT_EXT_C_BGA1-IC,TBD!!!F2047!RSVD(30)!!!!
S!TP_PCH_RSVD31!U7C1!P29!@baseboard_fab2_lib.baseboard_fab2(sch_1):page122_i63@chpset_lib.lbg_core_qat_ext_c(chips)!LBG_CORE_QAT_EXT_C_BGA1-IC,TBD!!!F2047!RSVD(31)!!!!
S!TP_PCH_RSVD58!U7C1!AP27!@baseboard_fab2_lib.baseboard_fab2(sch_1):page122_i63@chpset_lib.lbg_core_qat_ext_c(chips)!LBG_CORE_QAT_EXT_C_BGA1-IC,TBD!!!F2047!RSVD(58)!!!!
S!TP_PCH_RSVD59!U7C1!AT27!@baseboard_fab2_lib.baseboard_fab2(sch_1):page122_i63@chpset_lib.lbg_core_qat_ext_c(chips)!LBG_CORE_QAT_EXT_C_BGA1-IC,TBD!!!F2047!RSVD(59)!!!!
S!P1V05_PCH_STBY_ISCLK_PLL!U7C1!W50!@baseboard_fab2_lib.baseboard_fab2(sch_1):page122_i63@chpset_lib.lbg_core_qat_ext_c(chips)!LBG_CORE_QAT_EXT_C_BGA1-IC,TBD!!!F2047!VCCA_CLKFILT_1P05(0)!!!!
S!P1V05_PCH_STBY_ISCLK_PLL!U7C1!AG45!@baseboard_fab2_lib.baseboard_fab2(sch_1):page122_i63@chpset_lib.lbg_core_qat_ext_c(chips)!LBG_CORE_QAT_EXT_C_BGA1-IC,TBD!!!F2047!VCCA_CLKFILT_1P05(1)!!!!
S!P1V05_PCH_STBY_ISCLK_PLL!U7C1!AJ46!@baseboard_fab2_lib.baseboard_fab2(sch_1):page122_i63@chpset_lib.lbg_core_qat_ext_c(chips)!LBG_CORE_QAT_EXT_C_BGA1-IC,TBD!!!F2047!VCCA_CLKFILT_1P05(2)!!!!
S!P1V05_PCH_STBY_ISCLK_PLL!U7C1!AJ48!@baseboard_fab2_lib.baseboard_fab2(sch_1):page122_i63@chpset_lib.lbg_core_qat_ext_c(chips)!LBG_CORE_QAT_EXT_C_BGA1-IC,TBD!!!F2047!VCCA_CLKFILT_1P05(3)!!!!
S!P1V05_PCH_STBY_ISCLK_PLL!U7C1!AE46!@baseboard_fab2_lib.baseboard_fab2(sch_1):page122_i63@chpset_lib.lbg_core_qat_ext_c(chips)!LBG_CORE_QAT_EXT_C_BGA1-IC,TBD!!!F2047!VCCA_CLKFILT_1P05(4)!!!!
S!P1V05_PCH_STBY_VCCA_PLL0!U7C1!AE45!@baseboard_fab2_lib.baseboard_fab2(sch_1):page122_i63@chpset_lib.lbg_core_qat_ext_c(chips)!LBG_CORE_QAT_EXT_C_BGA1-IC,TBD!!!F2047!VCCA_CLKPLL_1P05(0)!!!!
S!P1V05_PCH_STBY_VCCA_PLL1!U7C1!AG48!@baseboard_fab2_lib.baseboard_fab2(sch_1):page122_i63@chpset_lib.lbg_core_qat_ext_c(chips)!LBG_CORE_QAT_EXT_C_BGA1-IC,TBD!!!F2047!VCCA_CLKPLL_1P05(1)!!!!
S!P1V05_PCH_STBY!U7C1!AH50!@baseboard_fab2_lib.baseboard_fab2(sch_1):page122_i63@chpset_lib.lbg_core_qat_ext_c(chips)!LBG_CORE_QAT_EXT_C_BGA1-IC,TBD!!!F2047!VCCA_CLKUNF_1P05(0)!!!!
S!P1V05_PCH_STBY!U7C1!U50!@baseboard_fab2_lib.baseboard_fab2(sch_1):page122_i63@chpset_lib.lbg_core_qat_ext_c(chips)!LBG_CORE_QAT_EXT_C_BGA1-IC,TBD!!!F2047!VCCA_CLKUNF_1P05(1)!!!!
S!P1V05_PCH_STBY_VCCA_XTAL!U7C1!AD50!@baseboard_fab2_lib.baseboard_fab2(sch_1):page122_i63@chpset_lib.lbg_core_qat_ext_c(chips)!LBG_CORE_QAT_EXT_C_BGA1-IC,TBD!!!F2047!VCCA_CLKXTAL_1P05!!!!
S!P1V05_PCH_STBY!U7C1!AW45!@baseboard_fab2_lib.baseboard_fab2(sch_1):page122_i63@chpset_lib.lbg_core_qat_ext_c(chips)!LBG_CORE_QAT_EXT_C_BGA1-IC,TBD!!!F2047!VCCMPHY_1P05(0)!!!!
S!P1V05_PCH_STBY!U7C1!AM43!@baseboard_fab2_lib.baseboard_fab2(sch_1):page122_i63@chpset_lib.lbg_core_qat_ext_c(chips)!LBG_CORE_QAT_EXT_C_BGA1-IC,TBD!!!F2047!VCCMPHY_1P05(10)!!!!
S!P1V05_PCH_STBY!U7C1!AK45!@baseboard_fab2_lib.baseboard_fab2(sch_1):page122_i63@chpset_lib.lbg_core_qat_ext_c(chips)!LBG_CORE_QAT_EXT_C_BGA1-IC,TBD!!!F2047!VCCMPHY_1P05(11)!!!!
S!P1V05_PCH_STBY!U7C1!AK43!@baseboard_fab2_lib.baseboard_fab2(sch_1):page122_i63@chpset_lib.lbg_core_qat_ext_c(chips)!LBG_CORE_QAT_EXT_C_BGA1-IC,TBD!!!F2047!VCCMPHY_1P05(12)!!!!
S!P1V05_PCH_STBY!U7C1!AW43!@baseboard_fab2_lib.baseboard_fab2(sch_1):page122_i63@chpset_lib.lbg_core_qat_ext_c(chips)!LBG_CORE_QAT_EXT_C_BGA1-IC,TBD!!!F2047!VCCMPHY_1P05(1)!!!!
S!P1V05_PCH_STBY!U7C1!AJ43!@baseboard_fab2_lib.baseboard_fab2(sch_1):page122_i63@chpset_lib.lbg_core_qat_ext_c(chips)!LBG_CORE_QAT_EXT_C_BGA1-IC,TBD!!!F2047!VCCMPHY_1P05(2)!!!!
S!P1V05_PCH_STBY!U7C1!AU45!@baseboard_fab2_lib.baseboard_fab2(sch_1):page122_i63@chpset_lib.lbg_core_qat_ext_c(chips)!LBG_CORE_QAT_EXT_C_BGA1-IC,TBD!!!F2047!VCCMPHY_1P05(3)!!!!
S!P1V05_PCH_STBY!U7C1!AU43!@baseboard_fab2_lib.baseboard_fab2(sch_1):page122_i63@chpset_lib.lbg_core_qat_ext_c(chips)!LBG_CORE_QAT_EXT_C_BGA1-IC,TBD!!!F2047!VCCMPHY_1P05(4)!!!!
S!P1V05_PCH_STBY!U7C1!AT45!@baseboard_fab2_lib.baseboard_fab2(sch_1):page122_i63@chpset_lib.lbg_core_qat_ext_c(chips)!LBG_CORE_QAT_EXT_C_BGA1-IC,TBD!!!F2047!VCCMPHY_1P05(5)!!!!
S!P1V05_PCH_STBY!U7C1!AT43!@baseboard_fab2_lib.baseboard_fab2(sch_1):page122_i63@chpset_lib.lbg_core_qat_ext_c(chips)!LBG_CORE_QAT_EXT_C_BGA1-IC,TBD!!!F2047!VCCMPHY_1P05(6)!!!!
S!P1V05_PCH_STBY!U7C1!AP45!@baseboard_fab2_lib.baseboard_fab2(sch_1):page122_i63@chpset_lib.lbg_core_qat_ext_c(chips)!LBG_CORE_QAT_EXT_C_BGA1-IC,TBD!!!F2047!VCCMPHY_1P05(7)!!!!
S!P1V05_PCH_STBY!U7C1!AP43!@baseboard_fab2_lib.baseboard_fab2(sch_1):page122_i63@chpset_lib.lbg_core_qat_ext_c(chips)!LBG_CORE_QAT_EXT_C_BGA1-IC,TBD!!!F2047!VCCMPHY_1P05(8)!!!!
S!P1V05_PCH_STBY!U7C1!AM45!@baseboard_fab2_lib.baseboard_fab2(sch_1):page122_i63@chpset_lib.lbg_core_qat_ext_c(chips)!LBG_CORE_QAT_EXT_C_BGA1-IC,TBD!!!F2047!VCCMPHY_1P05(9)!!!!
S!P1V05_PCH_STBY_KR_PLL!U7C1!BD38!@baseboard_fab2_lib.baseboard_fab2(sch_1):page122_i63@chpset_lib.lbg_core_qat_ext_c(chips)!LBG_CORE_QAT_EXT_C_BGA1-IC,TBD!!!F2047!VCCP10GBEPLL_1P05(0)!!!!
S!P1V05_PCH_STBY_KR_PLL!U7C1!BB40!@baseboard_fab2_lib.baseboard_fab2(sch_1):page122_i63@chpset_lib.lbg_core_qat_ext_c(chips)!LBG_CORE_QAT_EXT_C_BGA1-IC,TBD!!!F2047!VCCP10GBEPLL_1P05(1)!!!!
S!P1V05_PCH_STBY_KR_PLL!U7C1!BA41!@baseboard_fab2_lib.baseboard_fab2(sch_1):page122_i63@chpset_lib.lbg_core_qat_ext_c(chips)!LBG_CORE_QAT_EXT_C_BGA1-IC,TBD!!!F2047!VCCP10GBEPLL_1P05(2)!!!!
S!P1V05_PCH_STBY_KR_PLL!U7C1!BA39!@baseboard_fab2_lib.baseboard_fab2(sch_1):page122_i63@chpset_lib.lbg_core_qat_ext_c(chips)!LBG_CORE_QAT_EXT_C_BGA1-IC,TBD!!!F2047!VCCP10GBEPLL_1P05(3)!!!!
S!P1V8_PCH_STBY!U7C1!BA29!@baseboard_fab2_lib.baseboard_fab2(sch_1):page122_i63@chpset_lib.lbg_core_qat_ext_c(chips)!LBG_CORE_QAT_EXT_C_BGA1-IC,TBD!!!F2047!VCCP10GBE_HV_1P8(0)!!!!
S!P1V8_PCH_STBY!U7C1!BA27!@baseboard_fab2_lib.baseboard_fab2(sch_1):page122_i63@chpset_lib.lbg_core_qat_ext_c(chips)!LBG_CORE_QAT_EXT_C_BGA1-IC,TBD!!!F2047!VCCP10GBE_HV_1P8(1)!!!!
S!P1V05_PCH_STBY!U7C1!BB37!@baseboard_fab2_lib.baseboard_fab2(sch_1):page122_i63@chpset_lib.lbg_core_qat_ext_c(chips)!LBG_CORE_QAT_EXT_C_BGA1-IC,TBD!!!F2047!VCCP10GBE_LV_1P05(0)!!!!
S!P1V05_PCH_STBY!U7C1!BB33!@baseboard_fab2_lib.baseboard_fab2(sch_1):page122_i63@chpset_lib.lbg_core_qat_ext_c(chips)!LBG_CORE_QAT_EXT_C_BGA1-IC,TBD!!!F2047!VCCP10GBE_LV_1P05(1)!!!!
S!P1V05_PCH_STBY!U7C1!BA37!@baseboard_fab2_lib.baseboard_fab2(sch_1):page122_i63@chpset_lib.lbg_core_qat_ext_c(chips)!LBG_CORE_QAT_EXT_C_BGA1-IC,TBD!!!F2047!VCCP10GBE_LV_1P05(2)!!!!
S!P1V05_PCH_STBY!U7C1!BA36!@baseboard_fab2_lib.baseboard_fab2(sch_1):page122_i63@chpset_lib.lbg_core_qat_ext_c(chips)!LBG_CORE_QAT_EXT_C_BGA1-IC,TBD!!!F2047!VCCP10GBE_LV_1P05(3)!!!!
S!P1V05_PCH_STBY!U7C1!BA34!@baseboard_fab2_lib.baseboard_fab2(sch_1):page122_i63@chpset_lib.lbg_core_qat_ext_c(chips)!LBG_CORE_QAT_EXT_C_BGA1-IC,TBD!!!F2047!VCCP10GBE_LV_1P05(4)!!!!
S!P1V05_PCH_STBY!U7C1!BA32!@baseboard_fab2_lib.baseboard_fab2(sch_1):page122_i63@chpset_lib.lbg_core_qat_ext_c(chips)!LBG_CORE_QAT_EXT_C_BGA1-IC,TBD!!!F2047!VCCP10GBE_LV_1P05(5)!!!!
S!P1V05_PCH_STBY!U7C1!BA30!@baseboard_fab2_lib.baseboard_fab2(sch_1):page122_i63@chpset_lib.lbg_core_qat_ext_c(chips)!LBG_CORE_QAT_EXT_C_BGA1-IC,TBD!!!F2047!VCCP10GBE_LV_1P05(6)!!!!
S!P3V3_STBY!U7C1!AH24!@baseboard_fab2_lib.baseboard_fab2(sch_1):page122_i63@chpset_lib.lbg_core_qat_ext_c(chips)!LBG_CORE_QAT_EXT_C_BGA1-IC,TBD!!!F2047!VCCPDSW_3P3!!!!
S!P3V3_STBY!U7C1!AW24!@baseboard_fab2_lib.baseboard_fab2(sch_1):page122_i63@chpset_lib.lbg_core_qat_ext_c(chips)!LBG_CORE_QAT_EXT_C_BGA1-IC,TBD!!!F2047!VCCPGPPA!!!!
S!P3V3_STBY!U7C1!BE26!@baseboard_fab2_lib.baseboard_fab2(sch_1):page122_i63@chpset_lib.lbg_core_qat_ext_c(chips)!LBG_CORE_QAT_EXT_C_BGA1-IC,TBD!!!F2047!VCCPGPPB!!!!
S!P3V3_STBY!U7C1!BE40!@baseboard_fab2_lib.baseboard_fab2(sch_1):page122_i63@chpset_lib.lbg_core_qat_ext_c(chips)!LBG_CORE_QAT_EXT_C_BGA1-IC,TBD!!!F2047!VCCPGPPC!!!!
S!P3V3_STBY!U7C1!BA43!@baseboard_fab2_lib.baseboard_fab2(sch_1):page122_i63@chpset_lib.lbg_core_qat_ext_c(chips)!LBG_CORE_QAT_EXT_C_BGA1-IC,TBD!!!F2047!VCCPGPPD!!!!
S!P3V3_STBY!U7C1!BE44!@baseboard_fab2_lib.baseboard_fab2(sch_1):page122_i63@chpset_lib.lbg_core_qat_ext_c(chips)!LBG_CORE_QAT_EXT_C_BGA1-IC,TBD!!!F2047!VCCPGPPE!!!!
S!P3V3_STBY!U7C1!AU27!@baseboard_fab2_lib.baseboard_fab2(sch_1):page122_i63@chpset_lib.lbg_core_qat_ext_c(chips)!LBG_CORE_QAT_EXT_C_BGA1-IC,TBD!!!F2047!VCCPGPPF!!!!
S!P3V3_STBY!U7C1!BA26!@baseboard_fab2_lib.baseboard_fab2(sch_1):page122_i63@chpset_lib.lbg_core_qat_ext_c(chips)!LBG_CORE_QAT_EXT_C_BGA1-IC,TBD!!!F2047!VCCPGPPG!!!!
S!P3V3_STBY!U7C1!BA24!@baseboard_fab2_lib.baseboard_fab2(sch_1):page122_i63@chpset_lib.lbg_core_qat_ext_c(chips)!LBG_CORE_QAT_EXT_C_BGA1-IC,TBD!!!F2047!VCCPGPPH!!!!
S!P3V3_STBY!U7C1!BB26!@baseboard_fab2_lib.baseboard_fab2(sch_1):page122_i63@chpset_lib.lbg_core_qat_ext_c(chips)!LBG_CORE_QAT_EXT_C_BGA1-IC,TBD!!!F2047!VCCPGPPJ!!!!
S!P3V3_STBY!U7C1!AU24!@baseboard_fab2_lib.baseboard_fab2(sch_1):page122_i63@chpset_lib.lbg_core_qat_ext_c(chips)!LBG_CORE_QAT_EXT_C_BGA1-IC,TBD!!!F2047!VCCPGPPK!!!!
S!P1V8_PCH_STBY!U7C1!AU29!@baseboard_fab2_lib.baseboard_fab2(sch_1):page122_i63@chpset_lib.lbg_core_qat_ext_c(chips)!LBG_CORE_QAT_EXT_C_BGA1-IC,TBD!!!F2047!VCCPGPP_1P8(0)!!!!
S!P1V8_PCH_STBY!U7C1!AW29!@baseboard_fab2_lib.baseboard_fab2(sch_1):page122_i63@chpset_lib.lbg_core_qat_ext_c(chips)!LBG_CORE_QAT_EXT_C_BGA1-IC,TBD!!!F2047!VCCPGPP_1P8(1)!!!!
S!P1V8_PCH_STBY!U7C1!AT29!@baseboard_fab2_lib.baseboard_fab2(sch_1):page122_i63@chpset_lib.lbg_core_qat_ext_c(chips)!LBG_CORE_QAT_EXT_C_BGA1-IC,TBD!!!F2047!VCCPGPP_1P8(2)!!!!
S!P1V8_PCH_STBY!U7C1!AM29!@baseboard_fab2_lib.baseboard_fab2(sch_1):page122_i63@chpset_lib.lbg_core_qat_ext_c(chips)!LBG_CORE_QAT_EXT_C_BGA1-IC,TBD!!!F2047!VCCPGPP_1P8(3)!!!!
S!P1V8_PCH_STBY!U7C1!AP29!@baseboard_fab2_lib.baseboard_fab2(sch_1):page122_i63@chpset_lib.lbg_core_qat_ext_c(chips)!LBG_CORE_QAT_EXT_C_BGA1-IC,TBD!!!F2047!VCCPGPP_1P8(4)!!!!
S!P1V8_PCH_STBY!U7C1!AW27!@baseboard_fab2_lib.baseboard_fab2(sch_1):page122_i63@chpset_lib.lbg_core_qat_ext_c(chips)!LBG_CORE_QAT_EXT_C_BGA1-IC,TBD!!!F2047!VCCPGPP_1P8(5)!!!!
S!P1V8_PCH_STBY!U7C1!AK24!@baseboard_fab2_lib.baseboard_fab2(sch_1):page122_i63@chpset_lib.lbg_core_qat_ext_c(chips)!LBG_CORE_QAT_EXT_C_BGA1-IC,TBD!!!F2047!VCCPGPP_1P8(6)!!!!
S!P1V8_PCH_STBY!U7C1!AG27!@baseboard_fab2_lib.baseboard_fab2(sch_1):page122_i63@chpset_lib.lbg_core_qat_ext_c(chips)!LBG_CORE_QAT_EXT_C_BGA1-IC,TBD!!!F2047!VCCPHDA_1P8!!!!
S!P1V05_PCH_STBY!U7C1!BF46!@baseboard_fab2_lib.baseboard_fab2(sch_1):page122_i63@chpset_lib.lbg_core_qat_ext_c(chips)!LBG_CORE_QAT_EXT_C_BGA1-IC,TBD!!!F2047!VCCPRIM_1P05(0)!!!!
S!P1V05_PCH_STBY!U7C1!Y46!@baseboard_fab2_lib.baseboard_fab2(sch_1):page122_i63@chpset_lib.lbg_core_qat_ext_c(chips)!LBG_CORE_QAT_EXT_C_BGA1-IC,TBD!!!F2047!VCCPRIM_1P05(10)!!!!
S!P1V05_PCH_STBY!U7C1!Y45!@baseboard_fab2_lib.baseboard_fab2(sch_1):page122_i63@chpset_lib.lbg_core_qat_ext_c(chips)!LBG_CORE_QAT_EXT_C_BGA1-IC,TBD!!!F2047!VCCPRIM_1P05(11)!!!!
S!P1V05_PCH_STBY!U7C1!V44!@baseboard_fab2_lib.baseboard_fab2(sch_1):page122_i63@chpset_lib.lbg_core_qat_ext_c(chips)!LBG_CORE_QAT_EXT_C_BGA1-IC,TBD!!!F2047!VCCPRIM_1P05(12)!!!!
S!P1V05_PCH_STBY!U7C1!U46!@baseboard_fab2_lib.baseboard_fab2(sch_1):page122_i63@chpset_lib.lbg_core_qat_ext_c(chips)!LBG_CORE_QAT_EXT_C_BGA1-IC,TBD!!!F2047!VCCPRIM_1P05(13)!!!!
S!P1V05_PCH_STBY!U7C1!T44!@baseboard_fab2_lib.baseboard_fab2(sch_1):page122_i63@chpset_lib.lbg_core_qat_ext_c(chips)!LBG_CORE_QAT_EXT_C_BGA1-IC,TBD!!!F2047!VCCPRIM_1P05(14)!!!!
S!P1V05_PCH_STBY!U7C1!R46!@baseboard_fab2_lib.baseboard_fab2(sch_1):page122_i63@chpset_lib.lbg_core_qat_ext_c(chips)!LBG_CORE_QAT_EXT_C_BGA1-IC,TBD!!!F2047!VCCPRIM_1P05(15)!!!!
S!P1V05_PCH_STBY!U7C1!R42!@baseboard_fab2_lib.baseboard_fab2(sch_1):page122_i63@chpset_lib.lbg_core_qat_ext_c(chips)!LBG_CORE_QAT_EXT_C_BGA1-IC,TBD!!!F2047!VCCPRIM_1P05(16)!!!!
S!P1V05_PCH_STBY!U7C1!AK27!@baseboard_fab2_lib.baseboard_fab2(sch_1):page122_i63@chpset_lib.lbg_core_qat_ext_c(chips)!LBG_CORE_QAT_EXT_C_BGA1-IC,TBD!!!F2047!VCCPRIM_1P05(17)!!!!
S!P1V05_PCH_STBY!U7C1!AA24!@baseboard_fab2_lib.baseboard_fab2(sch_1):page122_i63@chpset_lib.lbg_core_qat_ext_c(chips)!LBG_CORE_QAT_EXT_C_BGA1-IC,TBD!!!F2047!VCCPRIM_1P05(18)!!!!
S!P1V05_PCH_STBY!U7C1!Y26!@baseboard_fab2_lib.baseboard_fab2(sch_1):page122_i63@chpset_lib.lbg_core_qat_ext_c(chips)!LBG_CORE_QAT_EXT_C_BGA1-IC,TBD!!!F2047!VCCPRIM_1P05(19)!!!!
S!P1V05_PCH_STBY!U7C1!BE48!@baseboard_fab2_lib.baseboard_fab2(sch_1):page122_i63@chpset_lib.lbg_core_qat_ext_c(chips)!LBG_CORE_QAT_EXT_C_BGA1-IC,TBD!!!F2047!VCCPRIM_1P05(1)!!!!
S!P1V05_PCH_STBY!U7C1!AU39!@baseboard_fab2_lib.baseboard_fab2(sch_1):page122_i63@chpset_lib.lbg_core_qat_ext_c(chips)!LBG_CORE_QAT_EXT_C_BGA1-IC,TBD!!!F2047!VCCPRIM_1P05(2)!!!!
S!P1V05_PCH_STBY!U7C1!AU37!@baseboard_fab2_lib.baseboard_fab2(sch_1):page122_i63@chpset_lib.lbg_core_qat_ext_c(chips)!LBG_CORE_QAT_EXT_C_BGA1-IC,TBD!!!F2047!VCCPRIM_1P05(3)!!!!
S!P1V05_PCH_STBY!U7C1!AT39!@baseboard_fab2_lib.baseboard_fab2(sch_1):page122_i63@chpset_lib.lbg_core_qat_ext_c(chips)!LBG_CORE_QAT_EXT_C_BGA1-IC,TBD!!!F2047!VCCPRIM_1P05(4)!!!!
S!P1V05_PCH_STBY!U7C1!AM27!@baseboard_fab2_lib.baseboard_fab2(sch_1):page122_i63@chpset_lib.lbg_core_qat_ext_c(chips)!LBG_CORE_QAT_EXT_C_BGA1-IC,TBD!!!F2047!VCCPRIM_1P05(5)!!!!
S!P1V05_PCH_STBY!U7C1!AJ29!@baseboard_fab2_lib.baseboard_fab2(sch_1):page122_i63@chpset_lib.lbg_core_qat_ext_c(chips)!LBG_CORE_QAT_EXT_C_BGA1-IC,TBD!!!F2047!VCCPRIM_1P05(6)!!!!
S!P1V05_PCH_STBY!U7C1!AC26!@baseboard_fab2_lib.baseboard_fab2(sch_1):page122_i63@chpset_lib.lbg_core_qat_ext_c(chips)!LBG_CORE_QAT_EXT_C_BGA1-IC,TBD!!!F2047!VCCPRIM_1P05(7)!!!!
S!P1V05_PCH_STBY!U7C1!AA46!@baseboard_fab2_lib.baseboard_fab2(sch_1):page122_i63@chpset_lib.lbg_core_qat_ext_c(chips)!LBG_CORE_QAT_EXT_C_BGA1-IC,TBD!!!F2047!VCCPRIM_1P05(8)!!!!
S!P1V05_PCH_STBY!U7C1!AA45!@baseboard_fab2_lib.baseboard_fab2(sch_1):page122_i63@chpset_lib.lbg_core_qat_ext_c(chips)!LBG_CORE_QAT_EXT_C_BGA1-IC,TBD!!!F2047!VCCPRIM_1P05(9)!!!!
S!P3V3_RTC_STBY!U7C1!AJ27!@baseboard_fab2_lib.baseboard_fab2(sch_1):page122_i63@chpset_lib.lbg_core_qat_ext_c(chips)!LBG_CORE_QAT_EXT_C_BGA1-IC,TBD!!!F2047!VCCPRTC!!!!
S!P3V3_STBY!U7C1!AG29!@baseboard_fab2_lib.baseboard_fab2(sch_1):page122_i63@chpset_lib.lbg_core_qat_ext_c(chips)!LBG_CORE_QAT_EXT_C_BGA1-IC,TBD!!!F2047!VCCPRTCPRIM_3P3!!!!
S!P3V3_STBY!U7C1!AR24!@baseboard_fab2_lib.baseboard_fab2(sch_1):page122_i63@chpset_lib.lbg_core_qat_ext_c(chips)!LBG_CORE_QAT_EXT_C_BGA1-IC,TBD!!!F2047!VCCPSPI!!!!
S!P1V8_PCH_STBY!U7C1!AK29!@baseboard_fab2_lib.baseboard_fab2(sch_1):page122_i63@chpset_lib.lbg_core_qat_ext_c(chips)!LBG_CORE_QAT_EXT_C_BGA1-IC,TBD!!!F2047!VCCPSPI_1P8!!!!
S!P3V3_STBY!U7C1!BA48!@baseboard_fab2_lib.baseboard_fab2(sch_1):page122_i63@chpset_lib.lbg_core_qat_ext_c(chips)!LBG_CORE_QAT_EXT_C_BGA1-IC,TBD!!!F2047!VCCPUSBDSW_3P3!!!!
S!P1V8_PCH_STBY!U7C1!BD46!@baseboard_fab2_lib.baseboard_fab2(sch_1):page122_i63@chpset_lib.lbg_core_qat_ext_c(chips)!LBG_CORE_QAT_EXT_C_BGA1-IC,TBD!!!F2047!VCCP_1P8(0)!!!!
S!P1V8_PCH_STBY!U7C1!AE26!@baseboard_fab2_lib.baseboard_fab2(sch_1):page122_i63@chpset_lib.lbg_core_qat_ext_c(chips)!LBG_CORE_QAT_EXT_C_BGA1-IC,TBD!!!F2047!VCCP_1P8(1)!!!!
S!P3V3_STBY!U7C1!BA46!@baseboard_fab2_lib.baseboard_fab2(sch_1):page122_i63@chpset_lib.lbg_core_qat_ext_c(chips)!LBG_CORE_QAT_EXT_C_BGA1-IC,TBD!!!F2047!VCCP_3P3(0)!!!!
S!P3V3_STBY!U7C1!BA45!@baseboard_fab2_lib.baseboard_fab2(sch_1):page122_i63@chpset_lib.lbg_core_qat_ext_c(chips)!LBG_CORE_QAT_EXT_C_BGA1-IC,TBD!!!F2047!VCCP_3P3(1)!!!!
S!P3V3_STBY!U7C1!AD24!@baseboard_fab2_lib.baseboard_fab2(sch_1):page122_i63@chpset_lib.lbg_core_qat_ext_c(chips)!LBG_CORE_QAT_EXT_C_BGA1-IC,TBD!!!F2047!VCCP_3P3(2)!!!!
S!P3V3_STBY!U7C1!AN24!@baseboard_fab2_lib.baseboard_fab2(sch_1):page122_i63@chpset_lib.lbg_core_qat_ext_c(chips)!LBG_CORE_QAT_EXT_C_BGA1-IC,TBD!!!F2047!VCCP_3P3(5)!!!!
S!P1V05_PCH_STBY_WM26_PLL!U7C1!AW48!@baseboard_fab2_lib.baseboard_fab2(sch_1):page122_i63@chpset_lib.lbg_core_qat_ext_c(chips)!LBG_CORE_QAT_EXT_C_BGA1-IC,TBD!!!F2047!VCCP_HSIOPLL_1P05(0)!!!!
S!P1V05_PCH_STBY!U7C1!AT48!@baseboard_fab2_lib.baseboard_fab2(sch_1):page122_i63@chpset_lib.lbg_core_qat_ext_c(chips)!LBG_CORE_QAT_EXT_C_BGA1-IC,TBD!!!F2047!VCCP_HSIOPLLUNF_1P05!!!!
S!P1V05_PCH_STBY_WM26_PLL!U7C1!AU48!@baseboard_fab2_lib.baseboard_fab2(sch_1):page122_i63@chpset_lib.lbg_core_qat_ext_c(chips)!LBG_CORE_QAT_EXT_C_BGA1-IC,TBD!!!F2047!VCCP_HSIOPLL_1P05(2)!!!!
S!P1V05_PCH_STBY_WM26_PLL!U7C1!AP48!@baseboard_fab2_lib.baseboard_fab2(sch_1):page122_i63@chpset_lib.lbg_core_qat_ext_c(chips)!LBG_CORE_QAT_EXT_C_BGA1-IC,TBD!!!F2047!VCCP_HSIOPLL_1P05(3)!!!!
S!P1V05_PCH_STBY_WM20_PLL!U7C1!AN50!@baseboard_fab2_lib.baseboard_fab2(sch_1):page122_i63@chpset_lib.lbg_core_qat_ext_c(chips)!LBG_CORE_QAT_EXT_C_BGA1-IC,TBD!!!F2047!VCCP_UPPLL_1P05(0)!!!!
S!P1V05_PCH_STBY!U7C1!AM48!@baseboard_fab2_lib.baseboard_fab2(sch_1):page122_i63@chpset_lib.lbg_core_qat_ext_c(chips)!LBG_CORE_QAT_EXT_C_BGA1-IC,TBD!!!F2047!VCCP_UPPLLUNF_1P05!!!!
S!P1V05_PCH_STBY_WM20_PLL!U7C1!AK50!@baseboard_fab2_lib.baseboard_fab2(sch_1):page122_i63@chpset_lib.lbg_core_qat_ext_c(chips)!LBG_CORE_QAT_EXT_C_BGA1-IC,TBD!!!F2047!VCCP_UPPLL_1P05(2)!!!!
S!A_PVCCRTC_EXT_CAP!U7C1!AG22!@baseboard_fab2_lib.baseboard_fab2(sch_1):page122_i63@chpset_lib.lbg_core_qat_ext_c(chips)!LBG_CORE_QAT_EXT_C_BGA1-IC,TBD!!!F2047!VCCRTCEXT!!!!
S!P1V05_PCH_STBY!U7C1!AE27!@baseboard_fab2_lib.baseboard_fab2(sch_1):page123_i21@chpset_lib.lbg_core_qat_ext_c(chips)!LBG_CORE_QAT_EXT_C_BGA1-IC,TBD!!!F2046!VCCMPHY_1P05(13)!!!!
S!PVNN_PCH_STBY!U7C1!AU36!@baseboard_fab2_lib.baseboard_fab2(sch_1):page123_i21@chpset_lib.lbg_core_qat_ext_c(chips)!LBG_CORE_QAT_EXT_C_BGA1-IC,TBD!!!F2046!VCCPRIM_AVID(0)!!!!
S!PVNN_PCH_STBY!U7C1!AP32!@baseboard_fab2_lib.baseboard_fab2(sch_1):page123_i21@chpset_lib.lbg_core_qat_ext_c(chips)!LBG_CORE_QAT_EXT_C_BGA1-IC,TBD!!!F2046!VCCPRIM_AVID(10)!!!!
S!PVNN_PCH_STBY!U7C1!AM39!@baseboard_fab2_lib.baseboard_fab2(sch_1):page123_i21@chpset_lib.lbg_core_qat_ext_c(chips)!LBG_CORE_QAT_EXT_C_BGA1-IC,TBD!!!F2046!VCCPRIM_AVID(11)!!!!
S!PVNN_PCH_STBY!U7C1!AM37!@baseboard_fab2_lib.baseboard_fab2(sch_1):page123_i21@chpset_lib.lbg_core_qat_ext_c(chips)!LBG_CORE_QAT_EXT_C_BGA1-IC,TBD!!!F2046!VCCPRIM_AVID(12)!!!!
S!PVNN_PCH_STBY!U7C1!AM36!@baseboard_fab2_lib.baseboard_fab2(sch_1):page123_i21@chpset_lib.lbg_core_qat_ext_c(chips)!LBG_CORE_QAT_EXT_C_BGA1-IC,TBD!!!F2046!VCCPRIM_AVID(13)!!!!
S!PVNN_PCH_STBY!U7C1!AM34!@baseboard_fab2_lib.baseboard_fab2(sch_1):page123_i21@chpset_lib.lbg_core_qat_ext_c(chips)!LBG_CORE_QAT_EXT_C_BGA1-IC,TBD!!!F2046!VCCPRIM_AVID(14)!!!!
S!PVNN_PCH_STBY!U7C1!AM32!@baseboard_fab2_lib.baseboard_fab2(sch_1):page123_i21@chpset_lib.lbg_core_qat_ext_c(chips)!LBG_CORE_QAT_EXT_C_BGA1-IC,TBD!!!F2046!VCCPRIM_AVID(15)!!!!
S!PVNN_PCH_STBY!U7C1!AK39!@baseboard_fab2_lib.baseboard_fab2(sch_1):page123_i21@chpset_lib.lbg_core_qat_ext_c(chips)!LBG_CORE_QAT_EXT_C_BGA1-IC,TBD!!!F2046!VCCPRIM_AVID(16)!!!!
S!PVNN_PCH_STBY!U7C1!AK37!@baseboard_fab2_lib.baseboard_fab2(sch_1):page123_i21@chpset_lib.lbg_core_qat_ext_c(chips)!LBG_CORE_QAT_EXT_C_BGA1-IC,TBD!!!F2046!VCCPRIM_AVID(17)!!!!
S!PVNN_PCH_STBY!U7C1!AK34!@baseboard_fab2_lib.baseboard_fab2(sch_1):page123_i21@chpset_lib.lbg_core_qat_ext_c(chips)!LBG_CORE_QAT_EXT_C_BGA1-IC,TBD!!!F2046!VCCPRIM_AVID(18)!!!!
S!PVNN_PCH_STBY!U7C1!AG39!@baseboard_fab2_lib.baseboard_fab2(sch_1):page123_i21@chpset_lib.lbg_core_qat_ext_c(chips)!LBG_CORE_QAT_EXT_C_BGA1-IC,TBD!!!F2046!VCCPRIM_AVID(19)!!!!
S!PVNN_PCH_STBY!U7C1!AU34!@baseboard_fab2_lib.baseboard_fab2(sch_1):page123_i21@chpset_lib.lbg_core_qat_ext_c(chips)!LBG_CORE_QAT_EXT_C_BGA1-IC,TBD!!!F2046!VCCPRIM_AVID(1)!!!!
S!PVNN_PCH_STBY!U7C1!AG37!@baseboard_fab2_lib.baseboard_fab2(sch_1):page123_i21@chpset_lib.lbg_core_qat_ext_c(chips)!LBG_CORE_QAT_EXT_C_BGA1-IC,TBD!!!F2046!VCCPRIM_AVID(20)!!!!
S!PVNN_PCH_STBY!U7C1!AG36!@baseboard_fab2_lib.baseboard_fab2(sch_1):page123_i21@chpset_lib.lbg_core_qat_ext_c(chips)!LBG_CORE_QAT_EXT_C_BGA1-IC,TBD!!!F2046!VCCPRIM_AVID(21)!!!!
S!PVNN_PCH_STBY!U7C1!AG34!@baseboard_fab2_lib.baseboard_fab2(sch_1):page123_i21@chpset_lib.lbg_core_qat_ext_c(chips)!LBG_CORE_QAT_EXT_C_BGA1-IC,TBD!!!F2046!VCCPRIM_AVID(22)!!!!
S!PVNN_PCH_STBY!U7C1!AG32!@baseboard_fab2_lib.baseboard_fab2(sch_1):page123_i21@chpset_lib.lbg_core_qat_ext_c(chips)!LBG_CORE_QAT_EXT_C_BGA1-IC,TBD!!!F2046!VCCPRIM_AVID(23)!!!!
S!PVNN_PCH_STBY!U7C1!AE41!@baseboard_fab2_lib.baseboard_fab2(sch_1):page123_i21@chpset_lib.lbg_core_qat_ext_c(chips)!LBG_CORE_QAT_EXT_C_BGA1-IC,TBD!!!F2046!VCCPRIM_AVID(24)!!!!
S!PVNN_PCH_STBY!U7C1!AE39!@baseboard_fab2_lib.baseboard_fab2(sch_1):page123_i21@chpset_lib.lbg_core_qat_ext_c(chips)!LBG_CORE_QAT_EXT_C_BGA1-IC,TBD!!!F2046!VCCPRIM_AVID(25)!!!!
S!PVNN_PCH_STBY!U7C1!AE37!@baseboard_fab2_lib.baseboard_fab2(sch_1):page123_i21@chpset_lib.lbg_core_qat_ext_c(chips)!LBG_CORE_QAT_EXT_C_BGA1-IC,TBD!!!F2046!VCCPRIM_AVID(26)!!!!
S!PVNN_PCH_STBY!U7C1!AE36!@baseboard_fab2_lib.baseboard_fab2(sch_1):page123_i21@chpset_lib.lbg_core_qat_ext_c(chips)!LBG_CORE_QAT_EXT_C_BGA1-IC,TBD!!!F2046!VCCPRIM_AVID(27)!!!!
S!PVNN_PCH_STBY!U7C1!AE34!@baseboard_fab2_lib.baseboard_fab2(sch_1):page123_i21@chpset_lib.lbg_core_qat_ext_c(chips)!LBG_CORE_QAT_EXT_C_BGA1-IC,TBD!!!F2046!VCCPRIM_AVID(28)!!!!
S!PVNN_PCH_STBY!U7C1!AE32!@baseboard_fab2_lib.baseboard_fab2(sch_1):page123_i21@chpset_lib.lbg_core_qat_ext_c(chips)!LBG_CORE_QAT_EXT_C_BGA1-IC,TBD!!!F2046!VCCPRIM_AVID(29)!!!!
S!PVNN_PCH_STBY!U7C1!AU32!@baseboard_fab2_lib.baseboard_fab2(sch_1):page123_i21@chpset_lib.lbg_core_qat_ext_c(chips)!LBG_CORE_QAT_EXT_C_BGA1-IC,TBD!!!F2046!VCCPRIM_AVID(2)!!!!
S!PVNN_PCH_STBY!U7C1!AE30!@baseboard_fab2_lib.baseboard_fab2(sch_1):page123_i21@chpset_lib.lbg_core_qat_ext_c(chips)!LBG_CORE_QAT_EXT_C_BGA1-IC,TBD!!!F2046!VCCPRIM_AVID(30)!!!!
S!PVNN_PCH_STBY!U7C1!U27!@baseboard_fab2_lib.baseboard_fab2(sch_1):page123_i21@chpset_lib.lbg_core_qat_ext_c(chips)!LBG_CORE_QAT_EXT_C_BGA1-IC,TBD!!!F2046!VCCPRIM_AVID(31)!!!!
S!PVNN_PCH_STBY!U7C1!AC41!@baseboard_fab2_lib.baseboard_fab2(sch_1):page123_i21@chpset_lib.lbg_core_qat_ext_c(chips)!LBG_CORE_QAT_EXT_C_BGA1-IC,TBD!!!F2046!VCCPRIM_AVID(32)!!!!
S!PVNN_PCH_STBY!U7C1!AC39!@baseboard_fab2_lib.baseboard_fab2(sch_1):page123_i21@chpset_lib.lbg_core_qat_ext_c(chips)!LBG_CORE_QAT_EXT_C_BGA1-IC,TBD!!!F2046!VCCPRIM_AVID(33)!!!!
S!PVNN_PCH_STBY!U7C1!AC37!@baseboard_fab2_lib.baseboard_fab2(sch_1):page123_i21@chpset_lib.lbg_core_qat_ext_c(chips)!LBG_CORE_QAT_EXT_C_BGA1-IC,TBD!!!F2046!VCCPRIM_AVID(34)!!!!
S!PVNN_PCH_STBY!U7C1!AC36!@baseboard_fab2_lib.baseboard_fab2(sch_1):page123_i21@chpset_lib.lbg_core_qat_ext_c(chips)!LBG_CORE_QAT_EXT_C_BGA1-IC,TBD!!!F2046!VCCPRIM_AVID(35)!!!!
S!PVNN_PCH_STBY!U7C1!AC34!@baseboard_fab2_lib.baseboard_fab2(sch_1):page123_i21@chpset_lib.lbg_core_qat_ext_c(chips)!LBG_CORE_QAT_EXT_C_BGA1-IC,TBD!!!F2046!VCCPRIM_AVID(36)!!!!
S!PVNN_PCH_STBY!U7C1!AC32!@baseboard_fab2_lib.baseboard_fab2(sch_1):page123_i21@chpset_lib.lbg_core_qat_ext_c(chips)!LBG_CORE_QAT_EXT_C_BGA1-IC,TBD!!!F2046!VCCPRIM_AVID(37)!!!!
S!PVNN_PCH_STBY!U7C1!AC30!@baseboard_fab2_lib.baseboard_fab2(sch_1):page123_i21@chpset_lib.lbg_core_qat_ext_c(chips)!LBG_CORE_QAT_EXT_C_BGA1-IC,TBD!!!F2046!VCCPRIM_AVID(38)!!!!
S!PVNN_PCH_STBY!U7C1!AC29!@baseboard_fab2_lib.baseboard_fab2(sch_1):page123_i21@chpset_lib.lbg_core_qat_ext_c(chips)!LBG_CORE_QAT_EXT_C_BGA1-IC,TBD!!!F2046!VCCPRIM_AVID(39)!!!!
S!PVNN_PCH_STBY!U7C1!AT36!@baseboard_fab2_lib.baseboard_fab2(sch_1):page123_i21@chpset_lib.lbg_core_qat_ext_c(chips)!LBG_CORE_QAT_EXT_C_BGA1-IC,TBD!!!F2046!VCCPRIM_AVID(3)!!!!
S!PVNN_PCH_STBY!U7C1!AA41!@baseboard_fab2_lib.baseboard_fab2(sch_1):page123_i21@chpset_lib.lbg_core_qat_ext_c(chips)!LBG_CORE_QAT_EXT_C_BGA1-IC,TBD!!!F2046!VCCPRIM_AVID(40)!!!!
S!PVNN_PCH_STBY!U7C1!AA39!@baseboard_fab2_lib.baseboard_fab2(sch_1):page123_i21@chpset_lib.lbg_core_qat_ext_c(chips)!LBG_CORE_QAT_EXT_C_BGA1-IC,TBD!!!F2046!VCCPRIM_AVID(41)!!!!
S!PVNN_PCH_STBY!U7C1!AA37!@baseboard_fab2_lib.baseboard_fab2(sch_1):page123_i21@chpset_lib.lbg_core_qat_ext_c(chips)!LBG_CORE_QAT_EXT_C_BGA1-IC,TBD!!!F2046!VCCPRIM_AVID(42)!!!!
S!PVNN_PCH_STBY!U7C1!AA36!@baseboard_fab2_lib.baseboard_fab2(sch_1):page123_i21@chpset_lib.lbg_core_qat_ext_c(chips)!LBG_CORE_QAT_EXT_C_BGA1-IC,TBD!!!F2046!VCCPRIM_AVID(43)!!!!
S!PVNN_PCH_STBY!U7C1!AA34!@baseboard_fab2_lib.baseboard_fab2(sch_1):page123_i21@chpset_lib.lbg_core_qat_ext_c(chips)!LBG_CORE_QAT_EXT_C_BGA1-IC,TBD!!!F2046!VCCPRIM_AVID(44)!!!!
S!PVNN_PCH_STBY!U7C1!AA32!@baseboard_fab2_lib.baseboard_fab2(sch_1):page123_i21@chpset_lib.lbg_core_qat_ext_c(chips)!LBG_CORE_QAT_EXT_C_BGA1-IC,TBD!!!F2046!VCCPRIM_AVID(45)!!!!
S!PVNN_PCH_STBY!U7C1!AA30!@baseboard_fab2_lib.baseboard_fab2(sch_1):page123_i21@chpset_lib.lbg_core_qat_ext_c(chips)!LBG_CORE_QAT_EXT_C_BGA1-IC,TBD!!!F2046!VCCPRIM_AVID(46)!!!!
S!PVNN_PCH_STBY!U7C1!AA29!@baseboard_fab2_lib.baseboard_fab2(sch_1):page123_i21@chpset_lib.lbg_core_qat_ext_c(chips)!LBG_CORE_QAT_EXT_C_BGA1-IC,TBD!!!F2046!VCCPRIM_AVID(47)!!!!
S!PVNN_PCH_STBY!U7C1!Y41!@baseboard_fab2_lib.baseboard_fab2(sch_1):page123_i21@chpset_lib.lbg_core_qat_ext_c(chips)!LBG_CORE_QAT_EXT_C_BGA1-IC,TBD!!!F2046!VCCPRIM_AVID(48)!!!!
S!PVNN_PCH_STBY!U7C1!Y39!@baseboard_fab2_lib.baseboard_fab2(sch_1):page123_i21@chpset_lib.lbg_core_qat_ext_c(chips)!LBG_CORE_QAT_EXT_C_BGA1-IC,TBD!!!F2046!VCCPRIM_AVID(49)!!!!
S!PVNN_PCH_STBY!U7C1!AT34!@baseboard_fab2_lib.baseboard_fab2(sch_1):page123_i21@chpset_lib.lbg_core_qat_ext_c(chips)!LBG_CORE_QAT_EXT_C_BGA1-IC,TBD!!!F2046!VCCPRIM_AVID(4)!!!!
S!PVNN_PCH_STBY!U7C1!Y37!@baseboard_fab2_lib.baseboard_fab2(sch_1):page123_i21@chpset_lib.lbg_core_qat_ext_c(chips)!LBG_CORE_QAT_EXT_C_BGA1-IC,TBD!!!F2046!VCCPRIM_AVID(50)!!!!
S!PVNN_PCH_STBY!U7C1!Y36!@baseboard_fab2_lib.baseboard_fab2(sch_1):page123_i21@chpset_lib.lbg_core_qat_ext_c(chips)!LBG_CORE_QAT_EXT_C_BGA1-IC,TBD!!!F2046!VCCPRIM_AVID(51)!!!!
S!PVNN_PCH_STBY!U7C1!Y34!@baseboard_fab2_lib.baseboard_fab2(sch_1):page123_i21@chpset_lib.lbg_core_qat_ext_c(chips)!LBG_CORE_QAT_EXT_C_BGA1-IC,TBD!!!F2046!VCCPRIM_AVID(52)!!!!
S!PVNN_PCH_STBY!U7C1!Y32!@baseboard_fab2_lib.baseboard_fab2(sch_1):page123_i21@chpset_lib.lbg_core_qat_ext_c(chips)!LBG_CORE_QAT_EXT_C_BGA1-IC,TBD!!!F2046!VCCPRIM_AVID(53)!!!!
S!PVNN_PCH_STBY!U7C1!Y30!@baseboard_fab2_lib.baseboard_fab2(sch_1):page123_i21@chpset_lib.lbg_core_qat_ext_c(chips)!LBG_CORE_QAT_EXT_C_BGA1-IC,TBD!!!F2046!VCCPRIM_AVID(54)!!!!
S!PVNN_PCH_STBY!U7C1!Y29!@baseboard_fab2_lib.baseboard_fab2(sch_1):page123_i21@chpset_lib.lbg_core_qat_ext_c(chips)!LBG_CORE_QAT_EXT_C_BGA1-IC,TBD!!!F2046!VCCPRIM_AVID(55)!!!!
S!PVNN_PCH_STBY!U7C1!V40!@baseboard_fab2_lib.baseboard_fab2(sch_1):page123_i21@chpset_lib.lbg_core_qat_ext_c(chips)!LBG_CORE_QAT_EXT_C_BGA1-IC,TBD!!!F2046!VCCPRIM_AVID(56)!!!!
S!PVNN_PCH_STBY!U7C1!V33!@baseboard_fab2_lib.baseboard_fab2(sch_1):page123_i21@chpset_lib.lbg_core_qat_ext_c(chips)!LBG_CORE_QAT_EXT_C_BGA1-IC,TBD!!!F2046!VCCPRIM_AVID(57)!!!!
S!PVNN_PCH_STBY!U7C1!V29!@baseboard_fab2_lib.baseboard_fab2(sch_1):page123_i21@chpset_lib.lbg_core_qat_ext_c(chips)!LBG_CORE_QAT_EXT_C_BGA1-IC,TBD!!!F2046!VCCPRIM_AVID(58)!!!!
S!PVNN_PCH_STBY!U7C1!U38!@baseboard_fab2_lib.baseboard_fab2(sch_1):page123_i21@chpset_lib.lbg_core_qat_ext_c(chips)!LBG_CORE_QAT_EXT_C_BGA1-IC,TBD!!!F2046!VCCPRIM_AVID(59)!!!!
S!PVNN_PCH_STBY!U7C1!AT32!@baseboard_fab2_lib.baseboard_fab2(sch_1):page123_i21@chpset_lib.lbg_core_qat_ext_c(chips)!LBG_CORE_QAT_EXT_C_BGA1-IC,TBD!!!F2046!VCCPRIM_AVID(5)!!!!
S!PVNN_PCH_STBY!U7C1!U35!@baseboard_fab2_lib.baseboard_fab2(sch_1):page123_i21@chpset_lib.lbg_core_qat_ext_c(chips)!LBG_CORE_QAT_EXT_C_BGA1-IC,TBD!!!F2046!VCCPRIM_AVID(60)!!!!
S!PVNN_PCH_STBY!U7C1!U31!@baseboard_fab2_lib.baseboard_fab2(sch_1):page123_i21@chpset_lib.lbg_core_qat_ext_c(chips)!LBG_CORE_QAT_EXT_C_BGA1-IC,TBD!!!F2046!VCCPRIM_AVID(61)!!!!
S!PVNN_PCH_STBY!U7C1!AK32!@baseboard_fab2_lib.baseboard_fab2(sch_1):page123_i21@chpset_lib.lbg_core_qat_ext_c(chips)!LBG_CORE_QAT_EXT_C_BGA1-IC,TBD!!!F2046!VCCPRIM_AVID(62)!!!!
S!PVNN_PCH_STBY!U7C1!AP39!@baseboard_fab2_lib.baseboard_fab2(sch_1):page123_i21@chpset_lib.lbg_core_qat_ext_c(chips)!LBG_CORE_QAT_EXT_C_BGA1-IC,TBD!!!F2046!VCCPRIM_AVID(6)!!!!
S!PVNN_PCH_STBY!U7C1!AP37!@baseboard_fab2_lib.baseboard_fab2(sch_1):page123_i21@chpset_lib.lbg_core_qat_ext_c(chips)!LBG_CORE_QAT_EXT_C_BGA1-IC,TBD!!!F2046!VCCPRIM_AVID(7)!!!!
S!PVNN_PCH_STBY!U7C1!AP36!@baseboard_fab2_lib.baseboard_fab2(sch_1):page123_i21@chpset_lib.lbg_core_qat_ext_c(chips)!LBG_CORE_QAT_EXT_C_BGA1-IC,TBD!!!F2046!VCCPRIM_AVID(8)!!!!
S!PVNN_PCH_STBY!U7C1!AP34!@baseboard_fab2_lib.baseboard_fab2(sch_1):page123_i21@chpset_lib.lbg_core_qat_ext_c(chips)!LBG_CORE_QAT_EXT_C_BGA1-IC,TBD!!!F2046!VCCPRIM_AVID(9)!!!!
S!VSENSE_PVNN_PCH_STBY_QAT!U7C1!V37!@baseboard_fab2_lib.baseboard_fab2(sch_1):page123_i21@chpset_lib.lbg_core_qat_ext_c(chips)!LBG_CORE_QAT_EXT_C_BGA1-IC,TBD!!!F2046!VCCPRIM_AVID_QAT_SENSE!!!!
S!VSENSE_PVNN_PCH_STBY_FPK!U7C1!AK36!@baseboard_fab2_lib.baseboard_fab2(sch_1):page123_i21@chpset_lib.lbg_core_qat_ext_c(chips)!LBG_CORE_QAT_EXT_C_BGA1-IC,TBD!!!F2046!VCCPRIM_AVID_SENSE!!!!
S!GND!U7C1!N31!@baseboard_fab2_lib.baseboard_fab2(sch_1):page123_i13@chpset_lib.lbg_core_qat_ext_c(chips)!LBG_CORE_QAT_EXT_C_BGA1-IC,TBD!!!F2045!VSS(355)!!!!
S!GND!U7C1!N27!@baseboard_fab2_lib.baseboard_fab2(sch_1):page123_i13@chpset_lib.lbg_core_qat_ext_c(chips)!LBG_CORE_QAT_EXT_C_BGA1-IC,TBD!!!F2045!VSS(356)!!!!
S!GND!U7C1!N24!@baseboard_fab2_lib.baseboard_fab2(sch_1):page123_i13@chpset_lib.lbg_core_qat_ext_c(chips)!LBG_CORE_QAT_EXT_C_BGA1-IC,TBD!!!F2045!VSS(357)!!!!
S!GND!U7C1!N20!@baseboard_fab2_lib.baseboard_fab2(sch_1):page123_i13@chpset_lib.lbg_core_qat_ext_c(chips)!LBG_CORE_QAT_EXT_C_BGA1-IC,TBD!!!F2045!VSS(358)!!!!
S!GND!U7C1!N17!@baseboard_fab2_lib.baseboard_fab2(sch_1):page123_i13@chpset_lib.lbg_core_qat_ext_c(chips)!LBG_CORE_QAT_EXT_C_BGA1-IC,TBD!!!F2045!VSS(359)!!!!
S!GND!U7C1!N13!@baseboard_fab2_lib.baseboard_fab2(sch_1):page123_i13@chpset_lib.lbg_core_qat_ext_c(chips)!LBG_CORE_QAT_EXT_C_BGA1-IC,TBD!!!F2045!VSS(360)!!!!
S!GND!U7C1!M48!@baseboard_fab2_lib.baseboard_fab2(sch_1):page123_i13@chpset_lib.lbg_core_qat_ext_c(chips)!LBG_CORE_QAT_EXT_C_BGA1-IC,TBD!!!F2045!VSS(361)!!!!
S!GND!U7C1!M44!@baseboard_fab2_lib.baseboard_fab2(sch_1):page123_i13@chpset_lib.lbg_core_qat_ext_c(chips)!LBG_CORE_QAT_EXT_C_BGA1-IC,TBD!!!F2045!VSS(362)!!!!
S!GND!U7C1!N50!@baseboard_fab2_lib.baseboard_fab2(sch_1):page123_i13@chpset_lib.lbg_core_qat_ext_c(chips)!LBG_CORE_QAT_EXT_C_BGA1-IC,TBD!!!F2045!VSS(363)!!!!
S!GND!U7C1!N42!@baseboard_fab2_lib.baseboard_fab2(sch_1):page123_i13@chpset_lib.lbg_core_qat_ext_c(chips)!LBG_CORE_QAT_EXT_C_BGA1-IC,TBD!!!F2045!VSS(364)!!!!
S!GND!U7C1!M40!@baseboard_fab2_lib.baseboard_fab2(sch_1):page123_i13@chpset_lib.lbg_core_qat_ext_c(chips)!LBG_CORE_QAT_EXT_C_BGA1-IC,TBD!!!F2045!VSS(365)!!!!
S!GND!U7C1!M4!@baseboard_fab2_lib.baseboard_fab2(sch_1):page123_i13@chpset_lib.lbg_core_qat_ext_c(chips)!LBG_CORE_QAT_EXT_C_BGA1-IC,TBD!!!F2045!VSS(366)!!!!
S!GND!U7C1!M37!@baseboard_fab2_lib.baseboard_fab2(sch_1):page123_i13@chpset_lib.lbg_core_qat_ext_c(chips)!LBG_CORE_QAT_EXT_C_BGA1-IC,TBD!!!F2045!VSS(367)!!!!
S!GND!U7C1!M33!@baseboard_fab2_lib.baseboard_fab2(sch_1):page123_i13@chpset_lib.lbg_core_qat_ext_c(chips)!LBG_CORE_QAT_EXT_C_BGA1-IC,TBD!!!F2045!VSS(368)!!!!
S!GND!U7C1!M29!@baseboard_fab2_lib.baseboard_fab2(sch_1):page123_i13@chpset_lib.lbg_core_qat_ext_c(chips)!LBG_CORE_QAT_EXT_C_BGA1-IC,TBD!!!F2045!VSS(369)!!!!
S!GND!U7C1!M26!@baseboard_fab2_lib.baseboard_fab2(sch_1):page123_i13@chpset_lib.lbg_core_qat_ext_c(chips)!LBG_CORE_QAT_EXT_C_BGA1-IC,TBD!!!F2045!VSS(370)!!!!
S!GND!U7C1!M22!@baseboard_fab2_lib.baseboard_fab2(sch_1):page123_i13@chpset_lib.lbg_core_qat_ext_c(chips)!LBG_CORE_QAT_EXT_C_BGA1-IC,TBD!!!F2045!VSS(371)!!!!
S!GND!U7C1!M2!@baseboard_fab2_lib.baseboard_fab2(sch_1):page123_i13@chpset_lib.lbg_core_qat_ext_c(chips)!LBG_CORE_QAT_EXT_C_BGA1-IC,TBD!!!F2045!VSS(372)!!!!
S!GND!U7C1!L68!@baseboard_fab2_lib.baseboard_fab2(sch_1):page123_i13@chpset_lib.lbg_core_qat_ext_c(chips)!LBG_CORE_QAT_EXT_C_BGA1-IC,TBD!!!F2045!VSS(373)!!!!
S!GND!U7C1!L5!@baseboard_fab2_lib.baseboard_fab2(sch_1):page123_i13@chpset_lib.lbg_core_qat_ext_c(chips)!LBG_CORE_QAT_EXT_C_BGA1-IC,TBD!!!F2045!VSS(374)!!!!
S!GND!U7C1!K71!@baseboard_fab2_lib.baseboard_fab2(sch_1):page123_i13@chpset_lib.lbg_core_qat_ext_c(chips)!LBG_CORE_QAT_EXT_C_BGA1-IC,TBD!!!F2045!VSS(375)!!!!
S!GND!U7C1!K69!@baseboard_fab2_lib.baseboard_fab2(sch_1):page123_i13@chpset_lib.lbg_core_qat_ext_c(chips)!LBG_CORE_QAT_EXT_C_BGA1-IC,TBD!!!F2045!VSS(376)!!!!
S!GND!U7C1!K54!@baseboard_fab2_lib.baseboard_fab2(sch_1):page123_i13@chpset_lib.lbg_core_qat_ext_c(chips)!LBG_CORE_QAT_EXT_C_BGA1-IC,TBD!!!F2045!VSS(377)!!!!
S!GND!U7C1!J70!@baseboard_fab2_lib.baseboard_fab2(sch_1):page123_i13@chpset_lib.lbg_core_qat_ext_c(chips)!LBG_CORE_QAT_EXT_C_BGA1-IC,TBD!!!F2045!VSS(378)!!!!
S!GND!U7C1!J68!@baseboard_fab2_lib.baseboard_fab2(sch_1):page123_i13@chpset_lib.lbg_core_qat_ext_c(chips)!LBG_CORE_QAT_EXT_C_BGA1-IC,TBD!!!F2045!VSS(379)!!!!
S!GND!U7C1!J59!@baseboard_fab2_lib.baseboard_fab2(sch_1):page123_i13@chpset_lib.lbg_core_qat_ext_c(chips)!LBG_CORE_QAT_EXT_C_BGA1-IC,TBD!!!F2045!VSS(380)!!!!
S!GND!U7C1!J44!@baseboard_fab2_lib.baseboard_fab2(sch_1):page123_i13@chpset_lib.lbg_core_qat_ext_c(chips)!LBG_CORE_QAT_EXT_C_BGA1-IC,TBD!!!F2045!VSS(381)!!!!
S!GND!U7C1!J37!@baseboard_fab2_lib.baseboard_fab2(sch_1):page123_i13@chpset_lib.lbg_core_qat_ext_c(chips)!LBG_CORE_QAT_EXT_C_BGA1-IC,TBD!!!F2045!VSS(382)!!!!
S!GND!U7C1!J22!@baseboard_fab2_lib.baseboard_fab2(sch_1):page123_i13@chpset_lib.lbg_core_qat_ext_c(chips)!LBG_CORE_QAT_EXT_C_BGA1-IC,TBD!!!F2045!VSS(383)!!!!
S!GND!U7C1!J15!@baseboard_fab2_lib.baseboard_fab2(sch_1):page123_i13@chpset_lib.lbg_core_qat_ext_c(chips)!LBG_CORE_QAT_EXT_C_BGA1-IC,TBD!!!F2045!VSS(384)!!!!
S!GND!U7C1!J11!@baseboard_fab2_lib.baseboard_fab2(sch_1):page123_i13@chpset_lib.lbg_core_qat_ext_c(chips)!LBG_CORE_QAT_EXT_C_BGA1-IC,TBD!!!F2045!VSS(385)!!!!
S!GND!U7C1!H65!@baseboard_fab2_lib.baseboard_fab2(sch_1):page123_i13@chpset_lib.lbg_core_qat_ext_c(chips)!LBG_CORE_QAT_EXT_C_BGA1-IC,TBD!!!F2045!VSS(386)!!!!
S!GND!U7C1!J7!@baseboard_fab2_lib.baseboard_fab2(sch_1):page123_i13@chpset_lib.lbg_core_qat_ext_c(chips)!LBG_CORE_QAT_EXT_C_BGA1-IC,TBD!!!F2045!VSS(387)!!!!
S!GND!U7C1!J5!@baseboard_fab2_lib.baseboard_fab2(sch_1):page123_i13@chpset_lib.lbg_core_qat_ext_c(chips)!LBG_CORE_QAT_EXT_C_BGA1-IC,TBD!!!F2045!VSS(388)!!!!
S!GND!U7C1!J29!@baseboard_fab2_lib.baseboard_fab2(sch_1):page123_i13@chpset_lib.lbg_core_qat_ext_c(chips)!LBG_CORE_QAT_EXT_C_BGA1-IC,TBD!!!F2045!VSS(389)!!!!
S!GND!U7C1!H58!@baseboard_fab2_lib.baseboard_fab2(sch_1):page123_i13@chpset_lib.lbg_core_qat_ext_c(chips)!LBG_CORE_QAT_EXT_C_BGA1-IC,TBD!!!F2045!VSS(390)!!!!
S!GND!U7C1!G66!@baseboard_fab2_lib.baseboard_fab2(sch_1):page123_i13@chpset_lib.lbg_core_qat_ext_c(chips)!LBG_CORE_QAT_EXT_C_BGA1-IC,TBD!!!F2045!VSS(391)!!!!
S!GND!U7C1!G63!@baseboard_fab2_lib.baseboard_fab2(sch_1):page123_i13@chpset_lib.lbg_core_qat_ext_c(chips)!LBG_CORE_QAT_EXT_C_BGA1-IC,TBD!!!F2045!VSS(392)!!!!
S!GND!U7C1!G6!@baseboard_fab2_lib.baseboard_fab2(sch_1):page123_i13@chpset_lib.lbg_core_qat_ext_c(chips)!LBG_CORE_QAT_EXT_C_BGA1-IC,TBD!!!F2045!VSS(393)!!!!
S!GND!U7C1!G48!@baseboard_fab2_lib.baseboard_fab2(sch_1):page123_i13@chpset_lib.lbg_core_qat_ext_c(chips)!LBG_CORE_QAT_EXT_C_BGA1-IC,TBD!!!F2045!VSS(394)!!!!
S!GND!U7C1!G37!@baseboard_fab2_lib.baseboard_fab2(sch_1):page123_i13@chpset_lib.lbg_core_qat_ext_c(chips)!LBG_CORE_QAT_EXT_C_BGA1-IC,TBD!!!F2045!VSS(395)!!!!
S!GND!U7C1!G29!@baseboard_fab2_lib.baseboard_fab2(sch_1):page123_i13@chpset_lib.lbg_core_qat_ext_c(chips)!LBG_CORE_QAT_EXT_C_BGA1-IC,TBD!!!F2045!VSS(396)!!!!
S!GND!U7C1!G22!@baseboard_fab2_lib.baseboard_fab2(sch_1):page123_i13@chpset_lib.lbg_core_qat_ext_c(chips)!LBG_CORE_QAT_EXT_C_BGA1-IC,TBD!!!F2045!VSS(397)!!!!
S!GND!U7C1!E9!@baseboard_fab2_lib.baseboard_fab2(sch_1):page123_i13@chpset_lib.lbg_core_qat_ext_c(chips)!LBG_CORE_QAT_EXT_C_BGA1-IC,TBD!!!F2045!VSS(398)!!!!
S!GND!U7C1!G59!@baseboard_fab2_lib.baseboard_fab2(sch_1):page123_i13@chpset_lib.lbg_core_qat_ext_c(chips)!LBG_CORE_QAT_EXT_C_BGA1-IC,TBD!!!F2045!VSS(399)!!!!
S!GND!U7C1!E63!@baseboard_fab2_lib.baseboard_fab2(sch_1):page123_i13@chpset_lib.lbg_core_qat_ext_c(chips)!LBG_CORE_QAT_EXT_C_BGA1-IC,TBD!!!F2045!VSS(400)!!!!
S!GND!U7C1!E61!@baseboard_fab2_lib.baseboard_fab2(sch_1):page123_i13@chpset_lib.lbg_core_qat_ext_c(chips)!LBG_CORE_QAT_EXT_C_BGA1-IC,TBD!!!F2045!VSS(401)!!!!
S!GND!U7C1!E6!@baseboard_fab2_lib.baseboard_fab2(sch_1):page123_i13@chpset_lib.lbg_core_qat_ext_c(chips)!LBG_CORE_QAT_EXT_C_BGA1-IC,TBD!!!F2045!VSS(402)!!!!
S!GND!U7C1!E57!@baseboard_fab2_lib.baseboard_fab2(sch_1):page123_i13@chpset_lib.lbg_core_qat_ext_c(chips)!LBG_CORE_QAT_EXT_C_BGA1-IC,TBD!!!F2045!VSS(403)!!!!
S!GND!U7C1!E54!@baseboard_fab2_lib.baseboard_fab2(sch_1):page123_i13@chpset_lib.lbg_core_qat_ext_c(chips)!LBG_CORE_QAT_EXT_C_BGA1-IC,TBD!!!F2045!VSS(404)!!!!
S!GND!U7C1!E52!@baseboard_fab2_lib.baseboard_fab2(sch_1):page123_i13@chpset_lib.lbg_core_qat_ext_c(chips)!LBG_CORE_QAT_EXT_C_BGA1-IC,TBD!!!F2045!VSS(405)!!!!
S!GND!U7C1!E50!@baseboard_fab2_lib.baseboard_fab2(sch_1):page123_i13@chpset_lib.lbg_core_qat_ext_c(chips)!LBG_CORE_QAT_EXT_C_BGA1-IC,TBD!!!F2045!VSS(406)!!!!
S!GND!U7C1!E48!@baseboard_fab2_lib.baseboard_fab2(sch_1):page123_i13@chpset_lib.lbg_core_qat_ext_c(chips)!LBG_CORE_QAT_EXT_C_BGA1-IC,TBD!!!F2045!VSS(407)!!!!
S!GND!U7C1!E45!@baseboard_fab2_lib.baseboard_fab2(sch_1):page123_i13@chpset_lib.lbg_core_qat_ext_c(chips)!LBG_CORE_QAT_EXT_C_BGA1-IC,TBD!!!F2045!VSS(408)!!!!
S!GND!U7C1!E43!@baseboard_fab2_lib.baseboard_fab2(sch_1):page123_i13@chpset_lib.lbg_core_qat_ext_c(chips)!LBG_CORE_QAT_EXT_C_BGA1-IC,TBD!!!F2045!VSS(409)!!!!
S!GND!U7C1!E41!@baseboard_fab2_lib.baseboard_fab2(sch_1):page123_i13@chpset_lib.lbg_core_qat_ext_c(chips)!LBG_CORE_QAT_EXT_C_BGA1-IC,TBD!!!F2045!VSS(410)!!!!
S!GND!U7C1!E39!@baseboard_fab2_lib.baseboard_fab2(sch_1):page123_i13@chpset_lib.lbg_core_qat_ext_c(chips)!LBG_CORE_QAT_EXT_C_BGA1-IC,TBD!!!F2045!VSS(411)!!!!
S!GND!U7C1!E37!@baseboard_fab2_lib.baseboard_fab2(sch_1):page123_i13@chpset_lib.lbg_core_qat_ext_c(chips)!LBG_CORE_QAT_EXT_C_BGA1-IC,TBD!!!F2045!VSS(412)!!!!
S!GND!U7C1!E34!@baseboard_fab2_lib.baseboard_fab2(sch_1):page123_i13@chpset_lib.lbg_core_qat_ext_c(chips)!LBG_CORE_QAT_EXT_C_BGA1-IC,TBD!!!F2045!VSS(413)!!!!
S!GND!U7C1!E32!@baseboard_fab2_lib.baseboard_fab2(sch_1):page123_i13@chpset_lib.lbg_core_qat_ext_c(chips)!LBG_CORE_QAT_EXT_C_BGA1-IC,TBD!!!F2045!VSS(414)!!!!
S!GND!U7C1!E30!@baseboard_fab2_lib.baseboard_fab2(sch_1):page123_i13@chpset_lib.lbg_core_qat_ext_c(chips)!LBG_CORE_QAT_EXT_C_BGA1-IC,TBD!!!F2045!VSS(415)!!!!
S!GND!U7C1!E28!@baseboard_fab2_lib.baseboard_fab2(sch_1):page123_i13@chpset_lib.lbg_core_qat_ext_c(chips)!LBG_CORE_QAT_EXT_C_BGA1-IC,TBD!!!F2045!VSS(416)!!!!
S!GND!U7C1!E26!@baseboard_fab2_lib.baseboard_fab2(sch_1):page123_i13@chpset_lib.lbg_core_qat_ext_c(chips)!LBG_CORE_QAT_EXT_C_BGA1-IC,TBD!!!F2045!VSS(417)!!!!
S!GND!U7C1!E24!@baseboard_fab2_lib.baseboard_fab2(sch_1):page123_i13@chpset_lib.lbg_core_qat_ext_c(chips)!LBG_CORE_QAT_EXT_C_BGA1-IC,TBD!!!F2045!VSS(418)!!!!
S!GND!U7C1!E22!@baseboard_fab2_lib.baseboard_fab2(sch_1):page123_i13@chpset_lib.lbg_core_qat_ext_c(chips)!LBG_CORE_QAT_EXT_C_BGA1-IC,TBD!!!F2045!VSS(419)!!!!
S!GND!U7C1!E20!@baseboard_fab2_lib.baseboard_fab2(sch_1):page123_i13@chpset_lib.lbg_core_qat_ext_c(chips)!LBG_CORE_QAT_EXT_C_BGA1-IC,TBD!!!F2045!VSS(420)!!!!
S!GND!U7C1!E15!@baseboard_fab2_lib.baseboard_fab2(sch_1):page123_i13@chpset_lib.lbg_core_qat_ext_c(chips)!LBG_CORE_QAT_EXT_C_BGA1-IC,TBD!!!F2045!VSS(421)!!!!
S!GND!U7C1!E13!@baseboard_fab2_lib.baseboard_fab2(sch_1):page123_i13@chpset_lib.lbg_core_qat_ext_c(chips)!LBG_CORE_QAT_EXT_C_BGA1-IC,TBD!!!F2045!VSS(422)!!!!
S!GND!U7C1!E11!@baseboard_fab2_lib.baseboard_fab2(sch_1):page123_i13@chpset_lib.lbg_core_qat_ext_c(chips)!LBG_CORE_QAT_EXT_C_BGA1-IC,TBD!!!F2045!VSS(423)!!!!
S!GND!U7C1!D47!@baseboard_fab2_lib.baseboard_fab2(sch_1):page123_i13@chpset_lib.lbg_core_qat_ext_c(chips)!LBG_CORE_QAT_EXT_C_BGA1-IC,TBD!!!F2045!VSS(424)!!!!
S!GND!U7C1!E65!@baseboard_fab2_lib.baseboard_fab2(sch_1):page123_i13@chpset_lib.lbg_core_qat_ext_c(chips)!LBG_CORE_QAT_EXT_C_BGA1-IC,TBD!!!F2045!VSS(425)!!!!
S!GND!U7C1!E59!@baseboard_fab2_lib.baseboard_fab2(sch_1):page123_i13@chpset_lib.lbg_core_qat_ext_c(chips)!LBG_CORE_QAT_EXT_C_BGA1-IC,TBD!!!F2045!VSS(426)!!!!
S!GND!U7C1!D27!@baseboard_fab2_lib.baseboard_fab2(sch_1):page123_i13@chpset_lib.lbg_core_qat_ext_c(chips)!LBG_CORE_QAT_EXT_C_BGA1-IC,TBD!!!F2045!VSS(427)!!!!
S!GND!U7C1!D25!@baseboard_fab2_lib.baseboard_fab2(sch_1):page123_i13@chpset_lib.lbg_core_qat_ext_c(chips)!LBG_CORE_QAT_EXT_C_BGA1-IC,TBD!!!F2045!VSS(428)!!!!
S!GND!U7C1!D19!@baseboard_fab2_lib.baseboard_fab2(sch_1):page123_i13@chpset_lib.lbg_core_qat_ext_c(chips)!LBG_CORE_QAT_EXT_C_BGA1-IC,TBD!!!F2045!VSS(429)!!!!
S!GND!U7C1!D16!@baseboard_fab2_lib.baseboard_fab2(sch_1):page123_i13@chpset_lib.lbg_core_qat_ext_c(chips)!LBG_CORE_QAT_EXT_C_BGA1-IC,TBD!!!F2045!VSS(430)!!!!
S!GND!U7C1!D12!@baseboard_fab2_lib.baseboard_fab2(sch_1):page123_i13@chpset_lib.lbg_core_qat_ext_c(chips)!LBG_CORE_QAT_EXT_C_BGA1-IC,TBD!!!F2045!VSS(431)!!!!
S!GND!U7C1!C65!@baseboard_fab2_lib.baseboard_fab2(sch_1):page123_i13@chpset_lib.lbg_core_qat_ext_c(chips)!LBG_CORE_QAT_EXT_C_BGA1-IC,TBD!!!F2045!VSS(432)!!!!
S!GND!U7C1!C41!@baseboard_fab2_lib.baseboard_fab2(sch_1):page123_i13@chpset_lib.lbg_core_qat_ext_c(chips)!LBG_CORE_QAT_EXT_C_BGA1-IC,TBD!!!F2045!VSS(433)!!!!
S!GND!U7C1!C37!@baseboard_fab2_lib.baseboard_fab2(sch_1):page123_i13@chpset_lib.lbg_core_qat_ext_c(chips)!LBG_CORE_QAT_EXT_C_BGA1-IC,TBD!!!F2045!VSS(434)!!!!
S!GND!U7C1!C34!@baseboard_fab2_lib.baseboard_fab2(sch_1):page123_i13@chpset_lib.lbg_core_qat_ext_c(chips)!LBG_CORE_QAT_EXT_C_BGA1-IC,TBD!!!F2045!VSS(435)!!!!
S!GND!U7C1!C30!@baseboard_fab2_lib.baseboard_fab2(sch_1):page123_i13@chpset_lib.lbg_core_qat_ext_c(chips)!LBG_CORE_QAT_EXT_C_BGA1-IC,TBD!!!F2045!VSS(436)!!!!
S!GND!U7C1!C22!@baseboard_fab2_lib.baseboard_fab2(sch_1):page123_i13@chpset_lib.lbg_core_qat_ext_c(chips)!LBG_CORE_QAT_EXT_C_BGA1-IC,TBD!!!F2045!VSS(437)!!!!
S!GND!U7C1!B47!@baseboard_fab2_lib.baseboard_fab2(sch_1):page123_i13@chpset_lib.lbg_core_qat_ext_c(chips)!LBG_CORE_QAT_EXT_C_BGA1-IC,TBD!!!F2045!VSS(438)!!!!
S!GND!U7C1!B27!@baseboard_fab2_lib.baseboard_fab2(sch_1):page123_i13@chpset_lib.lbg_core_qat_ext_c(chips)!LBG_CORE_QAT_EXT_C_BGA1-IC,TBD!!!F2045!VSS(439)!!!!
S!GND!U7C1!B25!@baseboard_fab2_lib.baseboard_fab2(sch_1):page123_i13@chpset_lib.lbg_core_qat_ext_c(chips)!LBG_CORE_QAT_EXT_C_BGA1-IC,TBD!!!F2045!VSS(440)!!!!
S!GND!U7C1!B19!@baseboard_fab2_lib.baseboard_fab2(sch_1):page123_i13@chpset_lib.lbg_core_qat_ext_c(chips)!LBG_CORE_QAT_EXT_C_BGA1-IC,TBD!!!F2045!VSS(441)!!!!
S!GND!U7C1!B12!@baseboard_fab2_lib.baseboard_fab2(sch_1):page123_i13@chpset_lib.lbg_core_qat_ext_c(chips)!LBG_CORE_QAT_EXT_C_BGA1-IC,TBD!!!F2045!VSS(442)!!!!
S!GND!U7C1!A41!@baseboard_fab2_lib.baseboard_fab2(sch_1):page123_i13@chpset_lib.lbg_core_qat_ext_c(chips)!LBG_CORE_QAT_EXT_C_BGA1-IC,TBD!!!F2045!VSS(443)!!!!
S!GND!U7C1!A37!@baseboard_fab2_lib.baseboard_fab2(sch_1):page123_i13@chpset_lib.lbg_core_qat_ext_c(chips)!LBG_CORE_QAT_EXT_C_BGA1-IC,TBD!!!F2045!VSS(444)!!!!
S!GND!U7C1!A34!@baseboard_fab2_lib.baseboard_fab2(sch_1):page123_i13@chpset_lib.lbg_core_qat_ext_c(chips)!LBG_CORE_QAT_EXT_C_BGA1-IC,TBD!!!F2045!VSS(445)!!!!
S!GND!U7C1!A30!@baseboard_fab2_lib.baseboard_fab2(sch_1):page123_i13@chpset_lib.lbg_core_qat_ext_c(chips)!LBG_CORE_QAT_EXT_C_BGA1-IC,TBD!!!F2045!VSS(446)!!!!
S!GND!U7C1!A22!@baseboard_fab2_lib.baseboard_fab2(sch_1):page123_i13@chpset_lib.lbg_core_qat_ext_c(chips)!LBG_CORE_QAT_EXT_C_BGA1-IC,TBD!!!F2045!VSS(447)!!!!
S!GND!U7C1!A18!@baseboard_fab2_lib.baseboard_fab2(sch_1):page123_i13@chpset_lib.lbg_core_qat_ext_c(chips)!LBG_CORE_QAT_EXT_C_BGA1-IC,TBD!!!F2045!VSS(448)!!!!
S!GND!U7C1!Y70!@baseboard_fab2_lib.baseboard_fab2(sch_1):page123_i13@chpset_lib.lbg_core_qat_ext_c(chips)!LBG_CORE_QAT_EXT_C_BGA1-IC,TBD!!!F2045!VSS(449)!!!!
S!GND!U7C1!Y72!@baseboard_fab2_lib.baseboard_fab2(sch_1):page123_i13@chpset_lib.lbg_core_qat_ext_c(chips)!LBG_CORE_QAT_EXT_C_BGA1-IC,TBD!!!F2045!VSS(450)!!!!
S!GND!U7C1!AT37!@baseboard_fab2_lib.baseboard_fab2(sch_1):page123_i13@chpset_lib.lbg_core_qat_ext_c(chips)!LBG_CORE_QAT_EXT_C_BGA1-IC,TBD!!!F2045!VSS(451)!!!!
S!GND!U7C1!BB48!@baseboard_fab2_lib.baseboard_fab2(sch_1):page123_i13@chpset_lib.lbg_core_qat_ext_c(chips)!LBG_CORE_QAT_EXT_C_BGA1-IC,TBD!!!F2045!VSS(452)!!!!
S!GND!U7C1!CA70!@baseboard_fab2_lib.baseboard_fab2(sch_1):page123_i13@chpset_lib.lbg_core_qat_ext_c(chips)!LBG_CORE_QAT_EXT_C_BGA1-IC,TBD!!!F2045!VSS(453)!!!!
S!GND!U7C1!BW72!@baseboard_fab2_lib.baseboard_fab2(sch_1):page123_i13@chpset_lib.lbg_core_qat_ext_c(chips)!LBG_CORE_QAT_EXT_C_BGA1-IC,TBD!!!F2045!VSS(454)!!!!
S!GND!U7C1!BW70!@baseboard_fab2_lib.baseboard_fab2(sch_1):page123_i13@chpset_lib.lbg_core_qat_ext_c(chips)!LBG_CORE_QAT_EXT_C_BGA1-IC,TBD!!!F2045!VSS(455)!!!!
S!GND!U7C1!BU72!@baseboard_fab2_lib.baseboard_fab2(sch_1):page123_i13@chpset_lib.lbg_core_qat_ext_c(chips)!LBG_CORE_QAT_EXT_C_BGA1-IC,TBD!!!F2045!VSS(456)!!!!
S!GND!U7C1!BR72!@baseboard_fab2_lib.baseboard_fab2(sch_1):page123_i13@chpset_lib.lbg_core_qat_ext_c(chips)!LBG_CORE_QAT_EXT_C_BGA1-IC,TBD!!!F2045!VSS(457)!!!!
S!GND!U7C1!G72!@baseboard_fab2_lib.baseboard_fab2(sch_1):page123_i13@chpset_lib.lbg_core_qat_ext_c(chips)!LBG_CORE_QAT_EXT_C_BGA1-IC,TBD!!!F2045!VSS(458)!!!!
S!GND!U7C1!G1!@baseboard_fab2_lib.baseboard_fab2(sch_1):page123_i13@chpset_lib.lbg_core_qat_ext_c(chips)!LBG_CORE_QAT_EXT_C_BGA1-IC,TBD!!!F2045!VSS(459)!!!!
S!GND!U7C1!E72!@baseboard_fab2_lib.baseboard_fab2(sch_1):page123_i13@chpset_lib.lbg_core_qat_ext_c(chips)!LBG_CORE_QAT_EXT_C_BGA1-IC,TBD!!!F2045!VSS(460)!!!!
S!GND!U7C1!E1!@baseboard_fab2_lib.baseboard_fab2(sch_1):page123_i13@chpset_lib.lbg_core_qat_ext_c(chips)!LBG_CORE_QAT_EXT_C_BGA1-IC,TBD!!!F2045!VSS(461)!!!!
S!GND!U7C1!C72!@baseboard_fab2_lib.baseboard_fab2(sch_1):page123_i13@chpset_lib.lbg_core_qat_ext_c(chips)!LBG_CORE_QAT_EXT_C_BGA1-IC,TBD!!!F2045!VSS(462)!!!!
S!GND!U7C1!C3!@baseboard_fab2_lib.baseboard_fab2(sch_1):page123_i13@chpset_lib.lbg_core_qat_ext_c(chips)!LBG_CORE_QAT_EXT_C_BGA1-IC,TBD!!!F2045!VSS(463)!!!!
S!GND!U7C1!BR1!@baseboard_fab2_lib.baseboard_fab2(sch_1):page123_i13@chpset_lib.lbg_core_qat_ext_c(chips)!LBG_CORE_QAT_EXT_C_BGA1-IC,TBD!!!F2045!VSS(464)!!!!
S!GND!U7C1!BU1!@baseboard_fab2_lib.baseboard_fab2(sch_1):page123_i13@chpset_lib.lbg_core_qat_ext_c(chips)!LBG_CORE_QAT_EXT_C_BGA1-IC,TBD!!!F2045!VSS(465)!!!!
S!GND!U7C1!BW1!@baseboard_fab2_lib.baseboard_fab2(sch_1):page123_i13@chpset_lib.lbg_core_qat_ext_c(chips)!LBG_CORE_QAT_EXT_C_BGA1-IC,TBD!!!F2045!VSS(466)!!!!
S!GND!U7C1!CA3!@baseboard_fab2_lib.baseboard_fab2(sch_1):page123_i13@chpset_lib.lbg_core_qat_ext_c(chips)!LBG_CORE_QAT_EXT_C_BGA1-IC,TBD!!!F2045!VSS(467)!!!!
S!GND!U7C1!A70!@baseboard_fab2_lib.baseboard_fab2(sch_1):page123_i13@chpset_lib.lbg_core_qat_ext_c(chips)!LBG_CORE_QAT_EXT_C_BGA1-IC,TBD!!!F2045!VSS(468)!!!!
S!GND!U7C1!CA5!@baseboard_fab2_lib.baseboard_fab2(sch_1):page123_i13@chpset_lib.lbg_core_qat_ext_c(chips)!LBG_CORE_QAT_EXT_C_BGA1-IC,TBD!!!F2045!VSS(469)!!!!
S!GND!U7C1!CA7!@baseboard_fab2_lib.baseboard_fab2(sch_1):page123_i13@chpset_lib.lbg_core_qat_ext_c(chips)!LBG_CORE_QAT_EXT_C_BGA1-IC,TBD!!!F2045!VSS(470)!!!!
S!GND!U7C1!CA9!@baseboard_fab2_lib.baseboard_fab2(sch_1):page123_i13@chpset_lib.lbg_core_qat_ext_c(chips)!LBG_CORE_QAT_EXT_C_BGA1-IC,TBD!!!F2045!VSS(471)!!!!
S!GND!U7C1!CA65!@baseboard_fab2_lib.baseboard_fab2(sch_1):page123_i13@chpset_lib.lbg_core_qat_ext_c(chips)!LBG_CORE_QAT_EXT_C_BGA1-IC,TBD!!!F2045!VSS(472)!!!!
S!GND!U7C1!CA66!@baseboard_fab2_lib.baseboard_fab2(sch_1):page123_i13@chpset_lib.lbg_core_qat_ext_c(chips)!LBG_CORE_QAT_EXT_C_BGA1-IC,TBD!!!F2045!VSS(473)!!!!
S!GND!U7C1!CA68!@baseboard_fab2_lib.baseboard_fab2(sch_1):page123_i13@chpset_lib.lbg_core_qat_ext_c(chips)!LBG_CORE_QAT_EXT_C_BGA1-IC,TBD!!!F2045!VSS(474)!!!!
S!GND!U7C1!BN72!@baseboard_fab2_lib.baseboard_fab2(sch_1):page123_i13@chpset_lib.lbg_core_qat_ext_c(chips)!LBG_CORE_QAT_EXT_C_BGA1-IC,TBD!!!F2045!VSS(475)!!!!
S!GND!U7C1!BN1!@baseboard_fab2_lib.baseboard_fab2(sch_1):page123_i13@chpset_lib.lbg_core_qat_ext_c(chips)!LBG_CORE_QAT_EXT_C_BGA1-IC,TBD!!!F2045!VSS(476)!!!!
S!GND!U7C1!J72!@baseboard_fab2_lib.baseboard_fab2(sch_1):page123_i13@chpset_lib.lbg_core_qat_ext_c(chips)!LBG_CORE_QAT_EXT_C_BGA1-IC,TBD!!!F2045!VSS(477)!!!!
S!GND!U7C1!J1!@baseboard_fab2_lib.baseboard_fab2(sch_1):page123_i13@chpset_lib.lbg_core_qat_ext_c(chips)!LBG_CORE_QAT_EXT_C_BGA1-IC,TBD!!!F2045!VSS(478)!!!!
S!GND!U7C1!A68!@baseboard_fab2_lib.baseboard_fab2(sch_1):page123_i13@chpset_lib.lbg_core_qat_ext_c(chips)!LBG_CORE_QAT_EXT_C_BGA1-IC,TBD!!!F2045!VSS(479)!!!!
S!GND!U7C1!A66!@baseboard_fab2_lib.baseboard_fab2(sch_1):page123_i13@chpset_lib.lbg_core_qat_ext_c(chips)!LBG_CORE_QAT_EXT_C_BGA1-IC,TBD!!!F2045!VSS(480)!!!!
S!GND!U7C1!A65!@baseboard_fab2_lib.baseboard_fab2(sch_1):page123_i13@chpset_lib.lbg_core_qat_ext_c(chips)!LBG_CORE_QAT_EXT_C_BGA1-IC,TBD!!!F2045!VSS(481)!!!!
S!GND!U7C1!A9!@baseboard_fab2_lib.baseboard_fab2(sch_1):page123_i13@chpset_lib.lbg_core_qat_ext_c(chips)!LBG_CORE_QAT_EXT_C_BGA1-IC,TBD!!!F2045!VSS(482)!!!!
S!GND!U7C1!A7!@baseboard_fab2_lib.baseboard_fab2(sch_1):page123_i13@chpset_lib.lbg_core_qat_ext_c(chips)!LBG_CORE_QAT_EXT_C_BGA1-IC,TBD!!!F2045!VSS(483)!!!!
S!GND!U7C1!A5!@baseboard_fab2_lib.baseboard_fab2(sch_1):page123_i13@chpset_lib.lbg_core_qat_ext_c(chips)!LBG_CORE_QAT_EXT_C_BGA1-IC,TBD!!!F2045!VSS(484)!!!!
S!GND!U7C1!E3!@baseboard_fab2_lib.baseboard_fab2(sch_1):page123_i13@chpset_lib.lbg_core_qat_ext_c(chips)!LBG_CORE_QAT_EXT_C_BGA1-IC,TBD!!!F2045!VSS(485)!!!!
S!GND!U7C1!F3!@baseboard_fab2_lib.baseboard_fab2(sch_1):page123_i13@chpset_lib.lbg_core_qat_ext_c(chips)!LBG_CORE_QAT_EXT_C_BGA1-IC,TBD!!!F2045!VSS(486)!!!!
S!GND!U7C1!BR3!@baseboard_fab2_lib.baseboard_fab2(sch_1):page123_i13@chpset_lib.lbg_core_qat_ext_c(chips)!LBG_CORE_QAT_EXT_C_BGA1-IC,TBD!!!F2045!VSS(487)!!!!
S!GND!U7C1!BU3!@baseboard_fab2_lib.baseboard_fab2(sch_1):page123_i13@chpset_lib.lbg_core_qat_ext_c(chips)!LBG_CORE_QAT_EXT_C_BGA1-IC,TBD!!!F2045!VSS(488)!!!!
S!GND!U7C1!E70!@baseboard_fab2_lib.baseboard_fab2(sch_1):page123_i13@chpset_lib.lbg_core_qat_ext_c(chips)!LBG_CORE_QAT_EXT_C_BGA1-IC,TBD!!!F2045!VSS(489)!!!!
S!GND!U7C1!F70!@baseboard_fab2_lib.baseboard_fab2(sch_1):page123_i13@chpset_lib.lbg_core_qat_ext_c(chips)!LBG_CORE_QAT_EXT_C_BGA1-IC,TBD!!!F2045!VSS(490)!!!!
S!GND!U7C1!BR70!@baseboard_fab2_lib.baseboard_fab2(sch_1):page123_i13@chpset_lib.lbg_core_qat_ext_c(chips)!LBG_CORE_QAT_EXT_C_BGA1-IC,TBD!!!F2045!VSS(491)!!!!
S!GND!U7C1!BU70!@baseboard_fab2_lib.baseboard_fab2(sch_1):page123_i13@chpset_lib.lbg_core_qat_ext_c(chips)!LBG_CORE_QAT_EXT_C_BGA1-IC,TBD!!!F2045!VSS(492)!!!!
S!GND!U7C1!BT69!@baseboard_fab2_lib.baseboard_fab2(sch_1):page123_i13@chpset_lib.lbg_core_qat_ext_c(chips)!LBG_CORE_QAT_EXT_C_BGA1-IC,TBD!!!F2045!VSS(493)!!!!
S!GND!U7C1!BP69!@baseboard_fab2_lib.baseboard_fab2(sch_1):page123_i13@chpset_lib.lbg_core_qat_ext_c(chips)!LBG_CORE_QAT_EXT_C_BGA1-IC,TBD!!!F2045!VSS(494)!!!!
S!GND!U7C1!AL59!@baseboard_fab2_lib.baseboard_fab2(sch_1):page124_i17@chpset_lib.lbg_core_qat_ext_c(chips)!LBG_CORE_QAT_EXT_C_BGA1-IC,TBD!!!F2044!VSS(215)!!!!
S!GND!U7C1!AL52!@baseboard_fab2_lib.baseboard_fab2(sch_1):page124_i17@chpset_lib.lbg_core_qat_ext_c(chips)!LBG_CORE_QAT_EXT_C_BGA1-IC,TBD!!!F2044!VSS(216)!!!!
S!GND!U7C1!AL5!@baseboard_fab2_lib.baseboard_fab2(sch_1):page124_i17@chpset_lib.lbg_core_qat_ext_c(chips)!LBG_CORE_QAT_EXT_C_BGA1-IC,TBD!!!F2044!VSS(217)!!!!
S!GND!U7C1!AL22!@baseboard_fab2_lib.baseboard_fab2(sch_1):page124_i17@chpset_lib.lbg_core_qat_ext_c(chips)!LBG_CORE_QAT_EXT_C_BGA1-IC,TBD!!!F2044!VSS(218)!!!!
S!GND!U7C1!AK71!@baseboard_fab2_lib.baseboard_fab2(sch_1):page124_i17@chpset_lib.lbg_core_qat_ext_c(chips)!LBG_CORE_QAT_EXT_C_BGA1-IC,TBD!!!F2044!VSS(219)!!!!
S!GND!U7C1!AK69!@baseboard_fab2_lib.baseboard_fab2(sch_1):page124_i17@chpset_lib.lbg_core_qat_ext_c(chips)!LBG_CORE_QAT_EXT_C_BGA1-IC,TBD!!!F2044!VSS(220)!!!!
S!GND!U7C1!AK61!@baseboard_fab2_lib.baseboard_fab2(sch_1):page124_i17@chpset_lib.lbg_core_qat_ext_c(chips)!LBG_CORE_QAT_EXT_C_BGA1-IC,TBD!!!F2044!VSS(221)!!!!
S!GND!U7C1!AK58!@baseboard_fab2_lib.baseboard_fab2(sch_1):page124_i17@chpset_lib.lbg_core_qat_ext_c(chips)!LBG_CORE_QAT_EXT_C_BGA1-IC,TBD!!!F2044!VSS(222)!!!!
S!GND!U7C1!AK48!@baseboard_fab2_lib.baseboard_fab2(sch_1):page124_i17@chpset_lib.lbg_core_qat_ext_c(chips)!LBG_CORE_QAT_EXT_C_BGA1-IC,TBD!!!F2044!VSS(223)!!!!
S!GND!U7C1!AK46!@baseboard_fab2_lib.baseboard_fab2(sch_1):page124_i17@chpset_lib.lbg_core_qat_ext_c(chips)!LBG_CORE_QAT_EXT_C_BGA1-IC,TBD!!!F2044!VSS(224)!!!!
S!GND!U7C1!AK41!@baseboard_fab2_lib.baseboard_fab2(sch_1):page124_i17@chpset_lib.lbg_core_qat_ext_c(chips)!LBG_CORE_QAT_EXT_C_BGA1-IC,TBD!!!F2044!VSS(225)!!!!
S!GND!U7C1!AK26!@baseboard_fab2_lib.baseboard_fab2(sch_1):page124_i17@chpset_lib.lbg_core_qat_ext_c(chips)!LBG_CORE_QAT_EXT_C_BGA1-IC,TBD!!!F2044!VSS(226)!!!!
S!GND!U7C1!AJ7!@baseboard_fab2_lib.baseboard_fab2(sch_1):page124_i17@chpset_lib.lbg_core_qat_ext_c(chips)!LBG_CORE_QAT_EXT_C_BGA1-IC,TBD!!!F2044!VSS(227)!!!!
S!GND!U7C1!AJ68!@baseboard_fab2_lib.baseboard_fab2(sch_1):page124_i17@chpset_lib.lbg_core_qat_ext_c(chips)!LBG_CORE_QAT_EXT_C_BGA1-IC,TBD!!!F2044!VSS(228)!!!!
S!GND!U7C1!AJ66!@baseboard_fab2_lib.baseboard_fab2(sch_1):page124_i17@chpset_lib.lbg_core_qat_ext_c(chips)!LBG_CORE_QAT_EXT_C_BGA1-IC,TBD!!!F2044!VSS(229)!!!!
S!GND!U7C1!AJ59!@baseboard_fab2_lib.baseboard_fab2(sch_1):page124_i17@chpset_lib.lbg_core_qat_ext_c(chips)!LBG_CORE_QAT_EXT_C_BGA1-IC,TBD!!!F2044!VSS(230)!!!!
S!GND!U7C1!AJ52!@baseboard_fab2_lib.baseboard_fab2(sch_1):page124_i17@chpset_lib.lbg_core_qat_ext_c(chips)!LBG_CORE_QAT_EXT_C_BGA1-IC,TBD!!!F2044!VSS(231)!!!!
S!GND!U7C1!AJ5!@baseboard_fab2_lib.baseboard_fab2(sch_1):page124_i17@chpset_lib.lbg_core_qat_ext_c(chips)!LBG_CORE_QAT_EXT_C_BGA1-IC,TBD!!!F2044!VSS(232)!!!!
S!GND!U7C1!AJ41!@baseboard_fab2_lib.baseboard_fab2(sch_1):page124_i17@chpset_lib.lbg_core_qat_ext_c(chips)!LBG_CORE_QAT_EXT_C_BGA1-IC,TBD!!!F2044!VSS(233)!!!!
S!GND!U7C1!AJ39!@baseboard_fab2_lib.baseboard_fab2(sch_1):page124_i17@chpset_lib.lbg_core_qat_ext_c(chips)!LBG_CORE_QAT_EXT_C_BGA1-IC,TBD!!!F2044!VSS(234)!!!!
S!GND!U7C1!AJ37!@baseboard_fab2_lib.baseboard_fab2(sch_1):page124_i17@chpset_lib.lbg_core_qat_ext_c(chips)!LBG_CORE_QAT_EXT_C_BGA1-IC,TBD!!!F2044!VSS(235)!!!!
S!GND!U7C1!AJ36!@baseboard_fab2_lib.baseboard_fab2(sch_1):page124_i17@chpset_lib.lbg_core_qat_ext_c(chips)!LBG_CORE_QAT_EXT_C_BGA1-IC,TBD!!!F2044!VSS(236)!!!!
S!GND!U7C1!AJ34!@baseboard_fab2_lib.baseboard_fab2(sch_1):page124_i17@chpset_lib.lbg_core_qat_ext_c(chips)!LBG_CORE_QAT_EXT_C_BGA1-IC,TBD!!!F2044!VSS(237)!!!!
S!GND!U7C1!AJ30!@baseboard_fab2_lib.baseboard_fab2(sch_1):page124_i17@chpset_lib.lbg_core_qat_ext_c(chips)!LBG_CORE_QAT_EXT_C_BGA1-IC,TBD!!!F2044!VSS(238)!!!!
S!GND!U7C1!AJ26!@baseboard_fab2_lib.baseboard_fab2(sch_1):page124_i17@chpset_lib.lbg_core_qat_ext_c(chips)!LBG_CORE_QAT_EXT_C_BGA1-IC,TBD!!!F2044!VSS(239)!!!!
S!GND!U7C1!AJ22!@baseboard_fab2_lib.baseboard_fab2(sch_1):page124_i17@chpset_lib.lbg_core_qat_ext_c(chips)!LBG_CORE_QAT_EXT_C_BGA1-IC,TBD!!!F2044!VSS(240)!!!!
S!GND!U7C1!AJ18!@baseboard_fab2_lib.baseboard_fab2(sch_1):page124_i17@chpset_lib.lbg_core_qat_ext_c(chips)!LBG_CORE_QAT_EXT_C_BGA1-IC,TBD!!!F2044!VSS(241)!!!!
S!GND!U7C1!AJ15!@baseboard_fab2_lib.baseboard_fab2(sch_1):page124_i17@chpset_lib.lbg_core_qat_ext_c(chips)!LBG_CORE_QAT_EXT_C_BGA1-IC,TBD!!!F2044!VSS(242)!!!!
S!GND!U7C1!AK30!@baseboard_fab2_lib.baseboard_fab2(sch_1):page124_i17@chpset_lib.lbg_core_qat_ext_c(chips)!LBG_CORE_QAT_EXT_C_BGA1-IC,TBD!!!F2044!VSS(243)!!!!
S!GND!U7C1!AJ56!@baseboard_fab2_lib.baseboard_fab2(sch_1):page124_i17@chpset_lib.lbg_core_qat_ext_c(chips)!LBG_CORE_QAT_EXT_C_BGA1-IC,TBD!!!F2044!VSS(244)!!!!
S!GND!U7C1!AJ32!@baseboard_fab2_lib.baseboard_fab2(sch_1):page124_i17@chpset_lib.lbg_core_qat_ext_c(chips)!LBG_CORE_QAT_EXT_C_BGA1-IC,TBD!!!F2044!VSS(245)!!!!
S!GND!U7C1!AJ11!@baseboard_fab2_lib.baseboard_fab2(sch_1):page124_i17@chpset_lib.lbg_core_qat_ext_c(chips)!LBG_CORE_QAT_EXT_C_BGA1-IC,TBD!!!F2044!VSS(246)!!!!
S!GND!U7C1!AH20!@baseboard_fab2_lib.baseboard_fab2(sch_1):page124_i17@chpset_lib.lbg_core_qat_ext_c(chips)!LBG_CORE_QAT_EXT_C_BGA1-IC,TBD!!!F2044!VSS(247)!!!!
S!GND!U7C1!AG66!@baseboard_fab2_lib.baseboard_fab2(sch_1):page124_i17@chpset_lib.lbg_core_qat_ext_c(chips)!LBG_CORE_QAT_EXT_C_BGA1-IC,TBD!!!F2044!VSS(248)!!!!
S!GND!U7C1!AG59!@baseboard_fab2_lib.baseboard_fab2(sch_1):page124_i17@chpset_lib.lbg_core_qat_ext_c(chips)!LBG_CORE_QAT_EXT_C_BGA1-IC,TBD!!!F2044!VSS(249)!!!!
S!GND!U7C1!AG56!@baseboard_fab2_lib.baseboard_fab2(sch_1):page124_i17@chpset_lib.lbg_core_qat_ext_c(chips)!LBG_CORE_QAT_EXT_C_BGA1-IC,TBD!!!F2044!VSS(250)!!!!
S!GND!U7C1!AG52!@baseboard_fab2_lib.baseboard_fab2(sch_1):page124_i17@chpset_lib.lbg_core_qat_ext_c(chips)!LBG_CORE_QAT_EXT_C_BGA1-IC,TBD!!!F2044!VSS(251)!!!!
S!GND!U7C1!AG43!@baseboard_fab2_lib.baseboard_fab2(sch_1):page124_i17@chpset_lib.lbg_core_qat_ext_c(chips)!LBG_CORE_QAT_EXT_C_BGA1-IC,TBD!!!F2044!VSS(252)!!!!
S!GND!U7C1!AG41!@baseboard_fab2_lib.baseboard_fab2(sch_1):page124_i17@chpset_lib.lbg_core_qat_ext_c(chips)!LBG_CORE_QAT_EXT_C_BGA1-IC,TBD!!!F2044!VSS(253)!!!!
S!GND!U7C1!AG30!@baseboard_fab2_lib.baseboard_fab2(sch_1):page124_i17@chpset_lib.lbg_core_qat_ext_c(chips)!LBG_CORE_QAT_EXT_C_BGA1-IC,TBD!!!F2044!VSS(254)!!!!
S!GND!U7C1!AG26!@baseboard_fab2_lib.baseboard_fab2(sch_1):page124_i17@chpset_lib.lbg_core_qat_ext_c(chips)!LBG_CORE_QAT_EXT_C_BGA1-IC,TBD!!!F2044!VSS(255)!!!!
S!GND!U7C1!AF68!@baseboard_fab2_lib.baseboard_fab2(sch_1):page124_i17@chpset_lib.lbg_core_qat_ext_c(chips)!LBG_CORE_QAT_EXT_C_BGA1-IC,TBD!!!F2044!VSS(256)!!!!
S!GND!U7C1!AF3!@baseboard_fab2_lib.baseboard_fab2(sch_1):page124_i17@chpset_lib.lbg_core_qat_ext_c(chips)!LBG_CORE_QAT_EXT_C_BGA1-IC,TBD!!!F2044!VSS(257)!!!!
S!GND!U7C1!AF24!@baseboard_fab2_lib.baseboard_fab2(sch_1):page124_i17@chpset_lib.lbg_core_qat_ext_c(chips)!LBG_CORE_QAT_EXT_C_BGA1-IC,TBD!!!F2044!VSS(258)!!!!
S!GND!U7C1!AF17!@baseboard_fab2_lib.baseboard_fab2(sch_1):page124_i17@chpset_lib.lbg_core_qat_ext_c(chips)!LBG_CORE_QAT_EXT_C_BGA1-IC,TBD!!!F2044!VSS(259)!!!!
S!GND!U7C1!AF9!@baseboard_fab2_lib.baseboard_fab2(sch_1):page124_i17@chpset_lib.lbg_core_qat_ext_c(chips)!LBG_CORE_QAT_EXT_C_BGA1-IC,TBD!!!F2044!VSS(260)!!!!
S!GND!U7C1!AF5!@baseboard_fab2_lib.baseboard_fab2(sch_1):page124_i17@chpset_lib.lbg_core_qat_ext_c(chips)!LBG_CORE_QAT_EXT_C_BGA1-IC,TBD!!!F2044!VSS(261)!!!!
S!GND!U7C1!AF13!@baseboard_fab2_lib.baseboard_fab2(sch_1):page124_i17@chpset_lib.lbg_core_qat_ext_c(chips)!LBG_CORE_QAT_EXT_C_BGA1-IC,TBD!!!F2044!VSS(262)!!!!
S!GND!U7C1!AF1!@baseboard_fab2_lib.baseboard_fab2(sch_1):page124_i17@chpset_lib.lbg_core_qat_ext_c(chips)!LBG_CORE_QAT_EXT_C_BGA1-IC,TBD!!!F2044!VSS(263)!!!!
S!GND!U7C1!AE66!@baseboard_fab2_lib.baseboard_fab2(sch_1):page124_i17@chpset_lib.lbg_core_qat_ext_c(chips)!LBG_CORE_QAT_EXT_C_BGA1-IC,TBD!!!F2044!VSS(264)!!!!
S!GND!U7C1!AE63!@baseboard_fab2_lib.baseboard_fab2(sch_1):page124_i17@chpset_lib.lbg_core_qat_ext_c(chips)!LBG_CORE_QAT_EXT_C_BGA1-IC,TBD!!!F2044!VSS(265)!!!!
S!GND!U7C1!AE59!@baseboard_fab2_lib.baseboard_fab2(sch_1):page124_i17@chpset_lib.lbg_core_qat_ext_c(chips)!LBG_CORE_QAT_EXT_C_BGA1-IC,TBD!!!F2044!VSS(266)!!!!
S!GND!U7C1!AE56!@baseboard_fab2_lib.baseboard_fab2(sch_1):page124_i17@chpset_lib.lbg_core_qat_ext_c(chips)!LBG_CORE_QAT_EXT_C_BGA1-IC,TBD!!!F2044!VSS(267)!!!!
S!GND!U7C1!AE52!@baseboard_fab2_lib.baseboard_fab2(sch_1):page124_i17@chpset_lib.lbg_core_qat_ext_c(chips)!LBG_CORE_QAT_EXT_C_BGA1-IC,TBD!!!F2044!VSS(268)!!!!
S!GND!U7C1!AE48!@baseboard_fab2_lib.baseboard_fab2(sch_1):page124_i17@chpset_lib.lbg_core_qat_ext_c(chips)!LBG_CORE_QAT_EXT_C_BGA1-IC,TBD!!!F2044!VSS(269)!!!!
S!GND!U7C1!J18!@baseboard_fab2_lib.baseboard_fab2(sch_1):page124_i17@chpset_lib.lbg_core_qat_ext_c(chips)!LBG_CORE_QAT_EXT_C_BGA1-IC,TBD!!!F2044!VSS(270)!!!!
S!GND!U7C1!AE29!@baseboard_fab2_lib.baseboard_fab2(sch_1):page124_i17@chpset_lib.lbg_core_qat_ext_c(chips)!LBG_CORE_QAT_EXT_C_BGA1-IC,TBD!!!F2044!VSS(271)!!!!
S!GND!U7C1!AD68!@baseboard_fab2_lib.baseboard_fab2(sch_1):page124_i17@chpset_lib.lbg_core_qat_ext_c(chips)!LBG_CORE_QAT_EXT_C_BGA1-IC,TBD!!!F2044!VSS(272)!!!!
S!GND!U7C1!AD65!@baseboard_fab2_lib.baseboard_fab2(sch_1):page124_i17@chpset_lib.lbg_core_qat_ext_c(chips)!LBG_CORE_QAT_EXT_C_BGA1-IC,TBD!!!F2044!VSS(273)!!!!
S!GND!U7C1!AD5!@baseboard_fab2_lib.baseboard_fab2(sch_1):page124_i17@chpset_lib.lbg_core_qat_ext_c(chips)!LBG_CORE_QAT_EXT_C_BGA1-IC,TBD!!!F2044!VSS(274)!!!!
S!GND!U7C1!AC7!@baseboard_fab2_lib.baseboard_fab2(sch_1):page124_i17@chpset_lib.lbg_core_qat_ext_c(chips)!LBG_CORE_QAT_EXT_C_BGA1-IC,TBD!!!F2044!VSS(275)!!!!
S!GND!U7C1!AC66!@baseboard_fab2_lib.baseboard_fab2(sch_1):page124_i17@chpset_lib.lbg_core_qat_ext_c(chips)!LBG_CORE_QAT_EXT_C_BGA1-IC,TBD!!!F2044!VSS(276)!!!!
S!GND!U7C1!AC63!@baseboard_fab2_lib.baseboard_fab2(sch_1):page124_i17@chpset_lib.lbg_core_qat_ext_c(chips)!LBG_CORE_QAT_EXT_C_BGA1-IC,TBD!!!F2044!VSS(277)!!!!
S!GND!U7C1!AC59!@baseboard_fab2_lib.baseboard_fab2(sch_1):page124_i17@chpset_lib.lbg_core_qat_ext_c(chips)!LBG_CORE_QAT_EXT_C_BGA1-IC,TBD!!!F2044!VSS(278)!!!!
S!GND!U7C1!AC52!@baseboard_fab2_lib.baseboard_fab2(sch_1):page124_i17@chpset_lib.lbg_core_qat_ext_c(chips)!LBG_CORE_QAT_EXT_C_BGA1-IC,TBD!!!F2044!VSS(279)!!!!
S!GND!U7C1!AC48!@baseboard_fab2_lib.baseboard_fab2(sch_1):page124_i17@chpset_lib.lbg_core_qat_ext_c(chips)!LBG_CORE_QAT_EXT_C_BGA1-IC,TBD!!!F2044!VSS(280)!!!!
S!GND!U7C1!AC46!@baseboard_fab2_lib.baseboard_fab2(sch_1):page124_i17@chpset_lib.lbg_core_qat_ext_c(chips)!LBG_CORE_QAT_EXT_C_BGA1-IC,TBD!!!F2044!VSS(281)!!!!
S!GND!U7C1!AC43!@baseboard_fab2_lib.baseboard_fab2(sch_1):page124_i17@chpset_lib.lbg_core_qat_ext_c(chips)!LBG_CORE_QAT_EXT_C_BGA1-IC,TBD!!!F2044!VSS(282)!!!!
S!GND!U7C1!AC27!@baseboard_fab2_lib.baseboard_fab2(sch_1):page124_i17@chpset_lib.lbg_core_qat_ext_c(chips)!LBG_CORE_QAT_EXT_C_BGA1-IC,TBD!!!F2044!VSS(283)!!!!
S!GND!U7C1!AD58!@baseboard_fab2_lib.baseboard_fab2(sch_1):page124_i17@chpset_lib.lbg_core_qat_ext_c(chips)!LBG_CORE_QAT_EXT_C_BGA1-IC,TBD!!!F2044!VSS(284)!!!!
S!GND!U7C1!AC45!@baseboard_fab2_lib.baseboard_fab2(sch_1):page124_i17@chpset_lib.lbg_core_qat_ext_c(chips)!LBG_CORE_QAT_EXT_C_BGA1-IC,TBD!!!F2044!VSS(285)!!!!
S!GND!U7C1!AC22!@baseboard_fab2_lib.baseboard_fab2(sch_1):page124_i17@chpset_lib.lbg_core_qat_ext_c(chips)!LBG_CORE_QAT_EXT_C_BGA1-IC,TBD!!!F2044!VSS(286)!!!!
S!GND!U7C1!AC18!@baseboard_fab2_lib.baseboard_fab2(sch_1):page124_i17@chpset_lib.lbg_core_qat_ext_c(chips)!LBG_CORE_QAT_EXT_C_BGA1-IC,TBD!!!F2044!VSS(287)!!!!
S!GND!U7C1!AC15!@baseboard_fab2_lib.baseboard_fab2(sch_1):page124_i17@chpset_lib.lbg_core_qat_ext_c(chips)!LBG_CORE_QAT_EXT_C_BGA1-IC,TBD!!!F2044!VSS(288)!!!!
S!GND!U7C1!AC11!@baseboard_fab2_lib.baseboard_fab2(sch_1):page124_i17@chpset_lib.lbg_core_qat_ext_c(chips)!LBG_CORE_QAT_EXT_C_BGA1-IC,TBD!!!F2044!VSS(289)!!!!
S!GND!U7C1!AB72!@baseboard_fab2_lib.baseboard_fab2(sch_1):page124_i17@chpset_lib.lbg_core_qat_ext_c(chips)!LBG_CORE_QAT_EXT_C_BGA1-IC,TBD!!!F2044!VSS(290)!!!!
S!GND!U7C1!AB70!@baseboard_fab2_lib.baseboard_fab2(sch_1):page124_i17@chpset_lib.lbg_core_qat_ext_c(chips)!LBG_CORE_QAT_EXT_C_BGA1-IC,TBD!!!F2044!VSS(291)!!!!
S!GND!U7C1!AB68!@baseboard_fab2_lib.baseboard_fab2(sch_1):page124_i17@chpset_lib.lbg_core_qat_ext_c(chips)!LBG_CORE_QAT_EXT_C_BGA1-IC,TBD!!!F2044!VSS(292)!!!!
S!GND!U7C1!AB5!@baseboard_fab2_lib.baseboard_fab2(sch_1):page124_i17@chpset_lib.lbg_core_qat_ext_c(chips)!LBG_CORE_QAT_EXT_C_BGA1-IC,TBD!!!F2044!VSS(293)!!!!
S!GND!U7C1!AA48!@baseboard_fab2_lib.baseboard_fab2(sch_1):page124_i17@chpset_lib.lbg_core_qat_ext_c(chips)!LBG_CORE_QAT_EXT_C_BGA1-IC,TBD!!!F2044!VSS(294)!!!!
S!GND!U7C1!AA43!@baseboard_fab2_lib.baseboard_fab2(sch_1):page124_i17@chpset_lib.lbg_core_qat_ext_c(chips)!LBG_CORE_QAT_EXT_C_BGA1-IC,TBD!!!F2044!VSS(295)!!!!
S!GND!U7C1!AA27!@baseboard_fab2_lib.baseboard_fab2(sch_1):page124_i17@chpset_lib.lbg_core_qat_ext_c(chips)!LBG_CORE_QAT_EXT_C_BGA1-IC,TBD!!!F2044!VSS(296)!!!!
S!GND!U7C1!AA26!@baseboard_fab2_lib.baseboard_fab2(sch_1):page124_i17@chpset_lib.lbg_core_qat_ext_c(chips)!LBG_CORE_QAT_EXT_C_BGA1-IC,TBD!!!F2044!VSS(297)!!!!
S!GND!U7C1!Y68!@baseboard_fab2_lib.baseboard_fab2(sch_1):page124_i17@chpset_lib.lbg_core_qat_ext_c(chips)!LBG_CORE_QAT_EXT_C_BGA1-IC,TBD!!!F2044!VSS(298)!!!!
S!GND!U7C1!Y63!@baseboard_fab2_lib.baseboard_fab2(sch_1):page124_i17@chpset_lib.lbg_core_qat_ext_c(chips)!LBG_CORE_QAT_EXT_C_BGA1-IC,TBD!!!F2044!VSS(299)!!!!
S!GND!U7C1!Y59!@baseboard_fab2_lib.baseboard_fab2(sch_1):page124_i17@chpset_lib.lbg_core_qat_ext_c(chips)!LBG_CORE_QAT_EXT_C_BGA1-IC,TBD!!!F2044!VSS(300)!!!!
S!GND!U7C1!Y52!@baseboard_fab2_lib.baseboard_fab2(sch_1):page124_i17@chpset_lib.lbg_core_qat_ext_c(chips)!LBG_CORE_QAT_EXT_C_BGA1-IC,TBD!!!F2044!VSS(301)!!!!
S!GND!U7C1!Y5!@baseboard_fab2_lib.baseboard_fab2(sch_1):page124_i17@chpset_lib.lbg_core_qat_ext_c(chips)!LBG_CORE_QAT_EXT_C_BGA1-IC,TBD!!!F2044!VSS(302)!!!!
S!GND!U7C1!Y48!@baseboard_fab2_lib.baseboard_fab2(sch_1):page124_i17@chpset_lib.lbg_core_qat_ext_c(chips)!LBG_CORE_QAT_EXT_C_BGA1-IC,TBD!!!F2044!VSS(303)!!!!
S!GND!U7C1!Y27!@baseboard_fab2_lib.baseboard_fab2(sch_1):page124_i17@chpset_lib.lbg_core_qat_ext_c(chips)!LBG_CORE_QAT_EXT_C_BGA1-IC,TBD!!!F2044!VSS(304)!!!!
S!GND!U7C1!Y22!@baseboard_fab2_lib.baseboard_fab2(sch_1):page124_i17@chpset_lib.lbg_core_qat_ext_c(chips)!LBG_CORE_QAT_EXT_C_BGA1-IC,TBD!!!F2044!VSS(305)!!!!
S!GND!U7C1!W9!@baseboard_fab2_lib.baseboard_fab2(sch_1):page124_i17@chpset_lib.lbg_core_qat_ext_c(chips)!LBG_CORE_QAT_EXT_C_BGA1-IC,TBD!!!F2044!VSS(306)!!!!
S!GND!U7C1!W61!@baseboard_fab2_lib.baseboard_fab2(sch_1):page124_i17@chpset_lib.lbg_core_qat_ext_c(chips)!LBG_CORE_QAT_EXT_C_BGA1-IC,TBD!!!F2044!VSS(307)!!!!
S!GND!U7C1!Y43!@baseboard_fab2_lib.baseboard_fab2(sch_1):page124_i17@chpset_lib.lbg_core_qat_ext_c(chips)!LBG_CORE_QAT_EXT_C_BGA1-IC,TBD!!!F2044!VSS(308)!!!!
S!GND!U7C1!AA50!@baseboard_fab2_lib.baseboard_fab2(sch_1):page124_i17@chpset_lib.lbg_core_qat_ext_c(chips)!LBG_CORE_QAT_EXT_C_BGA1-IC,TBD!!!F2044!VSS(309)!!!!
S!GND!U7C1!W24!@baseboard_fab2_lib.baseboard_fab2(sch_1):page124_i17@chpset_lib.lbg_core_qat_ext_c(chips)!LBG_CORE_QAT_EXT_C_BGA1-IC,TBD!!!F2044!VSS(310)!!!!
S!GND!U7C1!W20!@baseboard_fab2_lib.baseboard_fab2(sch_1):page124_i17@chpset_lib.lbg_core_qat_ext_c(chips)!LBG_CORE_QAT_EXT_C_BGA1-IC,TBD!!!F2044!VSS(311)!!!!
S!GND!U7C1!W17!@baseboard_fab2_lib.baseboard_fab2(sch_1):page124_i17@chpset_lib.lbg_core_qat_ext_c(chips)!LBG_CORE_QAT_EXT_C_BGA1-IC,TBD!!!F2044!VSS(312)!!!!
S!GND!U7C1!W13!@baseboard_fab2_lib.baseboard_fab2(sch_1):page124_i17@chpset_lib.lbg_core_qat_ext_c(chips)!LBG_CORE_QAT_EXT_C_BGA1-IC,TBD!!!F2044!VSS(313)!!!!
S!GND!U7C1!V68!@baseboard_fab2_lib.baseboard_fab2(sch_1):page124_i17@chpset_lib.lbg_core_qat_ext_c(chips)!LBG_CORE_QAT_EXT_C_BGA1-IC,TBD!!!F2044!VSS(314)!!!!
S!GND!U7C1!V66!@baseboard_fab2_lib.baseboard_fab2(sch_1):page124_i17@chpset_lib.lbg_core_qat_ext_c(chips)!LBG_CORE_QAT_EXT_C_BGA1-IC,TBD!!!F2044!VSS(315)!!!!
S!GND!U7C1!W58!@baseboard_fab2_lib.baseboard_fab2(sch_1):page124_i17@chpset_lib.lbg_core_qat_ext_c(chips)!LBG_CORE_QAT_EXT_C_BGA1-IC,TBD!!!F2044!VSS(316)!!!!
S!GND!U7C1!V52!@baseboard_fab2_lib.baseboard_fab2(sch_1):page124_i17@chpset_lib.lbg_core_qat_ext_c(chips)!LBG_CORE_QAT_EXT_C_BGA1-IC,TBD!!!F2044!VSS(317)!!!!
S!GND!U7C1!V5!@baseboard_fab2_lib.baseboard_fab2(sch_1):page124_i17@chpset_lib.lbg_core_qat_ext_c(chips)!LBG_CORE_QAT_EXT_C_BGA1-IC,TBD!!!F2044!VSS(318)!!!!
S!GND!U7C1!V48!@baseboard_fab2_lib.baseboard_fab2(sch_1):page124_i17@chpset_lib.lbg_core_qat_ext_c(chips)!LBG_CORE_QAT_EXT_C_BGA1-IC,TBD!!!F2044!VSS(319)!!!!
S!GND!U7C1!V26!@baseboard_fab2_lib.baseboard_fab2(sch_1):page124_i17@chpset_lib.lbg_core_qat_ext_c(chips)!LBG_CORE_QAT_EXT_C_BGA1-IC,TBD!!!F2044!VSS(320)!!!!
S!GND!U7C1!U58!@baseboard_fab2_lib.baseboard_fab2(sch_1):page124_i17@chpset_lib.lbg_core_qat_ext_c(chips)!LBG_CORE_QAT_EXT_C_BGA1-IC,TBD!!!F2044!VSS(321)!!!!
S!GND!U7C1!AG46!@baseboard_fab2_lib.baseboard_fab2(sch_1):page124_i17@chpset_lib.lbg_core_qat_ext_c(chips)!LBG_CORE_QAT_EXT_C_BGA1-IC,TBD!!!F2044!VSS(322)!!!!
S!GND!U7C1!AF50!@baseboard_fab2_lib.baseboard_fab2(sch_1):page124_i17@chpset_lib.lbg_core_qat_ext_c(chips)!LBG_CORE_QAT_EXT_C_BGA1-IC,TBD!!!F2044!VSS(323)!!!!
S!GND!U7C1!T7!@baseboard_fab2_lib.baseboard_fab2(sch_1):page124_i17@chpset_lib.lbg_core_qat_ext_c(chips)!LBG_CORE_QAT_EXT_C_BGA1-IC,TBD!!!F2044!VSS(324)!!!!
S!GND!U7C1!T66!@baseboard_fab2_lib.baseboard_fab2(sch_1):page124_i17@chpset_lib.lbg_core_qat_ext_c(chips)!LBG_CORE_QAT_EXT_C_BGA1-IC,TBD!!!F2044!VSS(325)!!!!
S!GND!U7C1!T52!@baseboard_fab2_lib.baseboard_fab2(sch_1):page124_i17@chpset_lib.lbg_core_qat_ext_c(chips)!LBG_CORE_QAT_EXT_C_BGA1-IC,TBD!!!F2044!VSS(326)!!!!
S!GND!U7C1!T48!@baseboard_fab2_lib.baseboard_fab2(sch_1):page124_i17@chpset_lib.lbg_core_qat_ext_c(chips)!LBG_CORE_QAT_EXT_C_BGA1-IC,TBD!!!F2044!VSS(327)!!!!
S!GND!U7C1!AJ45!@baseboard_fab2_lib.baseboard_fab2(sch_1):page124_i17@chpset_lib.lbg_core_qat_ext_c(chips)!LBG_CORE_QAT_EXT_C_BGA1-IC,TBD!!!F2044!VSS(328)!!!!
S!GND!U7C1!T40!@baseboard_fab2_lib.baseboard_fab2(sch_1):page124_i17@chpset_lib.lbg_core_qat_ext_c(chips)!LBG_CORE_QAT_EXT_C_BGA1-IC,TBD!!!F2044!VSS(329)!!!!
S!GND!U7C1!T37!@baseboard_fab2_lib.baseboard_fab2(sch_1):page124_i17@chpset_lib.lbg_core_qat_ext_c(chips)!LBG_CORE_QAT_EXT_C_BGA1-IC,TBD!!!F2044!VSS(330)!!!!
S!GND!U7C1!T33!@baseboard_fab2_lib.baseboard_fab2(sch_1):page124_i17@chpset_lib.lbg_core_qat_ext_c(chips)!LBG_CORE_QAT_EXT_C_BGA1-IC,TBD!!!F2044!VSS(331)!!!!
S!GND!U7C1!T29!@baseboard_fab2_lib.baseboard_fab2(sch_1):page124_i17@chpset_lib.lbg_core_qat_ext_c(chips)!LBG_CORE_QAT_EXT_C_BGA1-IC,TBD!!!F2044!VSS(332)!!!!
S!GND!U7C1!T26!@baseboard_fab2_lib.baseboard_fab2(sch_1):page124_i17@chpset_lib.lbg_core_qat_ext_c(chips)!LBG_CORE_QAT_EXT_C_BGA1-IC,TBD!!!F2044!VSS(333)!!!!
S!GND!U7C1!T22!@baseboard_fab2_lib.baseboard_fab2(sch_1):page124_i17@chpset_lib.lbg_core_qat_ext_c(chips)!LBG_CORE_QAT_EXT_C_BGA1-IC,TBD!!!F2044!VSS(334)!!!!
S!GND!U7C1!T18!@baseboard_fab2_lib.baseboard_fab2(sch_1):page124_i17@chpset_lib.lbg_core_qat_ext_c(chips)!LBG_CORE_QAT_EXT_C_BGA1-IC,TBD!!!F2044!VSS(335)!!!!
S!GND!U7C1!T15!@baseboard_fab2_lib.baseboard_fab2(sch_1):page124_i17@chpset_lib.lbg_core_qat_ext_c(chips)!LBG_CORE_QAT_EXT_C_BGA1-IC,TBD!!!F2044!VSS(336)!!!!
S!GND!U7C1!T11!@baseboard_fab2_lib.baseboard_fab2(sch_1):page124_i17@chpset_lib.lbg_core_qat_ext_c(chips)!LBG_CORE_QAT_EXT_C_BGA1-IC,TBD!!!F2044!VSS(337)!!!!
S!GND!U7C1!R68!@baseboard_fab2_lib.baseboard_fab2(sch_1):page124_i17@chpset_lib.lbg_core_qat_ext_c(chips)!LBG_CORE_QAT_EXT_C_BGA1-IC,TBD!!!F2044!VSS(338)!!!!
S!GND!U7C1!R58!@baseboard_fab2_lib.baseboard_fab2(sch_1):page124_i17@chpset_lib.lbg_core_qat_ext_c(chips)!LBG_CORE_QAT_EXT_C_BGA1-IC,TBD!!!F2044!VSS(339)!!!!
S!GND!U7C1!T56!@baseboard_fab2_lib.baseboard_fab2(sch_1):page124_i17@chpset_lib.lbg_core_qat_ext_c(chips)!LBG_CORE_QAT_EXT_C_BGA1-IC,TBD!!!F2044!VSS(340)!!!!
S!GND!U7C1!R54!@baseboard_fab2_lib.baseboard_fab2(sch_1):page124_i17@chpset_lib.lbg_core_qat_ext_c(chips)!LBG_CORE_QAT_EXT_C_BGA1-IC,TBD!!!F2044!VSS(341)!!!!
S!GND!U7C1!R50!@baseboard_fab2_lib.baseboard_fab2(sch_1):page124_i17@chpset_lib.lbg_core_qat_ext_c(chips)!LBG_CORE_QAT_EXT_C_BGA1-IC,TBD!!!F2044!VSS(342)!!!!
S!GND!U7C1!R5!@baseboard_fab2_lib.baseboard_fab2(sch_1):page124_i17@chpset_lib.lbg_core_qat_ext_c(chips)!LBG_CORE_QAT_EXT_C_BGA1-IC,TBD!!!F2044!VSS(343)!!!!
S!GND!U7C1!U42!@baseboard_fab2_lib.baseboard_fab2(sch_1):page124_i17@chpset_lib.lbg_core_qat_ext_c(chips)!LBG_CORE_QAT_EXT_C_BGA1-IC,TBD!!!F2044!VSS(344)!!!!
S!GND!U7C1!R27!@baseboard_fab2_lib.baseboard_fab2(sch_1):page124_i17@chpset_lib.lbg_core_qat_ext_c(chips)!LBG_CORE_QAT_EXT_C_BGA1-IC,TBD!!!F2044!VSS(345)!!!!
S!GND!U7C1!P63!@baseboard_fab2_lib.baseboard_fab2(sch_1):page124_i17@chpset_lib.lbg_core_qat_ext_c(chips)!LBG_CORE_QAT_EXT_C_BGA1-IC,TBD!!!F2044!VSS(346)!!!!
S!GND!U7C1!AE43!@baseboard_fab2_lib.baseboard_fab2(sch_1):page124_i17@chpset_lib.lbg_core_qat_ext_c(chips)!LBG_CORE_QAT_EXT_C_BGA1-IC,TBD!!!F2044!VSS(347)!!!!
S!GND!U7C1!N9!@baseboard_fab2_lib.baseboard_fab2(sch_1):page124_i17@chpset_lib.lbg_core_qat_ext_c(chips)!LBG_CORE_QAT_EXT_C_BGA1-IC,TBD!!!F2044!VSS(348)!!!!
S!GND!U7C1!N68!@baseboard_fab2_lib.baseboard_fab2(sch_1):page124_i17@chpset_lib.lbg_core_qat_ext_c(chips)!LBG_CORE_QAT_EXT_C_BGA1-IC,TBD!!!F2044!VSS(349)!!!!
S!GND!U7C1!R38!@baseboard_fab2_lib.baseboard_fab2(sch_1):page124_i17@chpset_lib.lbg_core_qat_ext_c(chips)!LBG_CORE_QAT_EXT_C_BGA1-IC,TBD!!!F2044!VSS(350)!!!!
S!GND!U7C1!N5!@baseboard_fab2_lib.baseboard_fab2(sch_1):page124_i17@chpset_lib.lbg_core_qat_ext_c(chips)!LBG_CORE_QAT_EXT_C_BGA1-IC,TBD!!!F2044!VSS(351)!!!!
S!GND!U7C1!N46!@baseboard_fab2_lib.baseboard_fab2(sch_1):page124_i17@chpset_lib.lbg_core_qat_ext_c(chips)!LBG_CORE_QAT_EXT_C_BGA1-IC,TBD!!!F2044!VSS(352)!!!!
S!GND!U7C1!N38!@baseboard_fab2_lib.baseboard_fab2(sch_1):page124_i17@chpset_lib.lbg_core_qat_ext_c(chips)!LBG_CORE_QAT_EXT_C_BGA1-IC,TBD!!!F2044!VSS(353)!!!!
S!GND!U7C1!N35!@baseboard_fab2_lib.baseboard_fab2(sch_1):page124_i17@chpset_lib.lbg_core_qat_ext_c(chips)!LBG_CORE_QAT_EXT_C_BGA1-IC,TBD!!!F2044!VSS(354)!!!!
S!GND!U7C1!BF50!@baseboard_fab2_lib.baseboard_fab2(sch_1):page124_i16@chpset_lib.lbg_core_qat_ext_c(chips)!LBG_CORE_QAT_EXT_C_BGA1-IC,TBD!!!F2043!VSS(100)!!!!
S!GND!U7C1!BF5!@baseboard_fab2_lib.baseboard_fab2(sch_1):page124_i16@chpset_lib.lbg_core_qat_ext_c(chips)!LBG_CORE_QAT_EXT_C_BGA1-IC,TBD!!!F2043!VSS(101)!!!!
S!GND!U7C1!BF42!@baseboard_fab2_lib.baseboard_fab2(sch_1):page124_i16@chpset_lib.lbg_core_qat_ext_c(chips)!LBG_CORE_QAT_EXT_C_BGA1-IC,TBD!!!F2043!VSS(102)!!!!
S!GND!U7C1!BF38!@baseboard_fab2_lib.baseboard_fab2(sch_1):page124_i16@chpset_lib.lbg_core_qat_ext_c(chips)!LBG_CORE_QAT_EXT_C_BGA1-IC,TBD!!!F2043!VSS(103)!!!!
S!GND!U7C1!BF27!@baseboard_fab2_lib.baseboard_fab2(sch_1):page124_i16@chpset_lib.lbg_core_qat_ext_c(chips)!LBG_CORE_QAT_EXT_C_BGA1-IC,TBD!!!F2043!VSS(104)!!!!
S!GND!U7C1!BF24!@baseboard_fab2_lib.baseboard_fab2(sch_1):page124_i16@chpset_lib.lbg_core_qat_ext_c(chips)!LBG_CORE_QAT_EXT_C_BGA1-IC,TBD!!!F2043!VSS(105)!!!!
S!GND!U7C1!BF20!@baseboard_fab2_lib.baseboard_fab2(sch_1):page124_i16@chpset_lib.lbg_core_qat_ext_c(chips)!LBG_CORE_QAT_EXT_C_BGA1-IC,TBD!!!F2043!VSS(106)!!!!
S!GND!U7C1!BG44!@baseboard_fab2_lib.baseboard_fab2(sch_1):page124_i16@chpset_lib.lbg_core_qat_ext_c(chips)!LBG_CORE_QAT_EXT_C_BGA1-IC,TBD!!!F2043!VSS(107)!!!!
S!GND!U7C1!BF54!@baseboard_fab2_lib.baseboard_fab2(sch_1):page124_i16@chpset_lib.lbg_core_qat_ext_c(chips)!LBG_CORE_QAT_EXT_C_BGA1-IC,TBD!!!F2043!VSS(108)!!!!
S!GND!U7C1!BF17!@baseboard_fab2_lib.baseboard_fab2(sch_1):page124_i16@chpset_lib.lbg_core_qat_ext_c(chips)!LBG_CORE_QAT_EXT_C_BGA1-IC,TBD!!!F2043!VSS(109)!!!!
S!GND!U7C1!BF13!@baseboard_fab2_lib.baseboard_fab2(sch_1):page124_i16@chpset_lib.lbg_core_qat_ext_c(chips)!LBG_CORE_QAT_EXT_C_BGA1-IC,TBD!!!F2043!VSS(110)!!!!
S!GND!U7C1!BE66!@baseboard_fab2_lib.baseboard_fab2(sch_1):page124_i16@chpset_lib.lbg_core_qat_ext_c(chips)!LBG_CORE_QAT_EXT_C_BGA1-IC,TBD!!!F2043!VSS(111)!!!!
S!GND!U7C1!BE63!@baseboard_fab2_lib.baseboard_fab2(sch_1):page124_i16@chpset_lib.lbg_core_qat_ext_c(chips)!LBG_CORE_QAT_EXT_C_BGA1-IC,TBD!!!F2043!VSS(112)!!!!
S!GND!U7C1!BE59!@baseboard_fab2_lib.baseboard_fab2(sch_1):page124_i16@chpset_lib.lbg_core_qat_ext_c(chips)!LBG_CORE_QAT_EXT_C_BGA1-IC,TBD!!!F2043!VSS(113)!!!!
S!GND!U7C1!BE56!@baseboard_fab2_lib.baseboard_fab2(sch_1):page124_i16@chpset_lib.lbg_core_qat_ext_c(chips)!LBG_CORE_QAT_EXT_C_BGA1-IC,TBD!!!F2043!VSS(114)!!!!
S!GND!U7C1!BE37!@baseboard_fab2_lib.baseboard_fab2(sch_1):page124_i16@chpset_lib.lbg_core_qat_ext_c(chips)!LBG_CORE_QAT_EXT_C_BGA1-IC,TBD!!!F2043!VSS(115)!!!!
S!GND!U7C1!BE33!@baseboard_fab2_lib.baseboard_fab2(sch_1):page124_i16@chpset_lib.lbg_core_qat_ext_c(chips)!LBG_CORE_QAT_EXT_C_BGA1-IC,TBD!!!F2043!VSS(116)!!!!
S!GND!U7C1!BE29!@baseboard_fab2_lib.baseboard_fab2(sch_1):page124_i16@chpset_lib.lbg_core_qat_ext_c(chips)!LBG_CORE_QAT_EXT_C_BGA1-IC,TBD!!!F2043!VSS(117)!!!!
S!GND!U7C1!BD68!@baseboard_fab2_lib.baseboard_fab2(sch_1):page124_i16@chpset_lib.lbg_core_qat_ext_c(chips)!LBG_CORE_QAT_EXT_C_BGA1-IC,TBD!!!F2043!VSS(118)!!!!
S!GND!U7C1!BD54!@baseboard_fab2_lib.baseboard_fab2(sch_1):page124_i16@chpset_lib.lbg_core_qat_ext_c(chips)!LBG_CORE_QAT_EXT_C_BGA1-IC,TBD!!!F2043!VSS(119)!!!!
S!GND!U7C1!BD50!@baseboard_fab2_lib.baseboard_fab2(sch_1):page124_i16@chpset_lib.lbg_core_qat_ext_c(chips)!LBG_CORE_QAT_EXT_C_BGA1-IC,TBD!!!F2043!VSS(120)!!!!
S!GND!U7C1!BD5!@baseboard_fab2_lib.baseboard_fab2(sch_1):page124_i16@chpset_lib.lbg_core_qat_ext_c(chips)!LBG_CORE_QAT_EXT_C_BGA1-IC,TBD!!!F2043!VSS(121)!!!!
S!GND!U7C1!BD35!@baseboard_fab2_lib.baseboard_fab2(sch_1):page124_i16@chpset_lib.lbg_core_qat_ext_c(chips)!LBG_CORE_QAT_EXT_C_BGA1-IC,TBD!!!F2043!VSS(122)!!!!
S!GND!U7C1!BD31!@baseboard_fab2_lib.baseboard_fab2(sch_1):page124_i16@chpset_lib.lbg_core_qat_ext_c(chips)!LBG_CORE_QAT_EXT_C_BGA1-IC,TBD!!!F2043!VSS(123)!!!!
S!GND!U7C1!BD27!@baseboard_fab2_lib.baseboard_fab2(sch_1):page124_i16@chpset_lib.lbg_core_qat_ext_c(chips)!LBG_CORE_QAT_EXT_C_BGA1-IC,TBD!!!F2043!VSS(124)!!!!
S!GND!U7C1!BD24!@baseboard_fab2_lib.baseboard_fab2(sch_1):page124_i16@chpset_lib.lbg_core_qat_ext_c(chips)!LBG_CORE_QAT_EXT_C_BGA1-IC,TBD!!!F2043!VSS(125)!!!!
S!GND!U7C1!BC71!@baseboard_fab2_lib.baseboard_fab2(sch_1):page124_i16@chpset_lib.lbg_core_qat_ext_c(chips)!LBG_CORE_QAT_EXT_C_BGA1-IC,TBD!!!F2043!VSS(126)!!!!
S!GND!U7C1!BC69!@baseboard_fab2_lib.baseboard_fab2(sch_1):page124_i16@chpset_lib.lbg_core_qat_ext_c(chips)!LBG_CORE_QAT_EXT_C_BGA1-IC,TBD!!!F2043!VSS(127)!!!!
S!GND!U7C1!BB72!@baseboard_fab2_lib.baseboard_fab2(sch_1):page124_i16@chpset_lib.lbg_core_qat_ext_c(chips)!LBG_CORE_QAT_EXT_C_BGA1-IC,TBD!!!F2043!VSS(128)!!!!
S!GND!U7C1!BB70!@baseboard_fab2_lib.baseboard_fab2(sch_1):page124_i16@chpset_lib.lbg_core_qat_ext_c(chips)!LBG_CORE_QAT_EXT_C_BGA1-IC,TBD!!!F2043!VSS(129)!!!!
S!GND!U7C1!BB68!@baseboard_fab2_lib.baseboard_fab2(sch_1):page124_i16@chpset_lib.lbg_core_qat_ext_c(chips)!LBG_CORE_QAT_EXT_C_BGA1-IC,TBD!!!F2043!VSS(130)!!!!
S!GND!U7C1!BB66!@baseboard_fab2_lib.baseboard_fab2(sch_1):page124_i16@chpset_lib.lbg_core_qat_ext_c(chips)!LBG_CORE_QAT_EXT_C_BGA1-IC,TBD!!!F2043!VSS(131)!!!!
S!GND!U7C1!BB59!@baseboard_fab2_lib.baseboard_fab2(sch_1):page124_i16@chpset_lib.lbg_core_qat_ext_c(chips)!LBG_CORE_QAT_EXT_C_BGA1-IC,TBD!!!F2043!VSS(132)!!!!
S!GND!U7C1!BB44!@baseboard_fab2_lib.baseboard_fab2(sch_1):page124_i16@chpset_lib.lbg_core_qat_ext_c(chips)!LBG_CORE_QAT_EXT_C_BGA1-IC,TBD!!!F2043!VSS(133)!!!!
S!GND!U7C1!BB22!@baseboard_fab2_lib.baseboard_fab2(sch_1):page124_i16@chpset_lib.lbg_core_qat_ext_c(chips)!LBG_CORE_QAT_EXT_C_BGA1-IC,TBD!!!F2043!VSS(134)!!!!
S!GND!U7C1!BB18!@baseboard_fab2_lib.baseboard_fab2(sch_1):page124_i16@chpset_lib.lbg_core_qat_ext_c(chips)!LBG_CORE_QAT_EXT_C_BGA1-IC,TBD!!!F2043!VSS(135)!!!!
S!GND!U7C1!BB15!@baseboard_fab2_lib.baseboard_fab2(sch_1):page124_i16@chpset_lib.lbg_core_qat_ext_c(chips)!LBG_CORE_QAT_EXT_C_BGA1-IC,TBD!!!F2043!VSS(136)!!!!
S!GND!U7C1!BB11!@baseboard_fab2_lib.baseboard_fab2(sch_1):page124_i16@chpset_lib.lbg_core_qat_ext_c(chips)!LBG_CORE_QAT_EXT_C_BGA1-IC,TBD!!!F2043!VSS(137)!!!!
S!GND!U7C1!BB7!@baseboard_fab2_lib.baseboard_fab2(sch_1):page124_i16@chpset_lib.lbg_core_qat_ext_c(chips)!LBG_CORE_QAT_EXT_C_BGA1-IC,TBD!!!F2043!VSS(138)!!!!
S!GND!U7C1!BB5!@baseboard_fab2_lib.baseboard_fab2(sch_1):page124_i16@chpset_lib.lbg_core_qat_ext_c(chips)!LBG_CORE_QAT_EXT_C_BGA1-IC,TBD!!!F2043!VSS(139)!!!!
S!GND!U7C1!BA58!@baseboard_fab2_lib.baseboard_fab2(sch_1):page124_i16@chpset_lib.lbg_core_qat_ext_c(chips)!LBG_CORE_QAT_EXT_C_BGA1-IC,TBD!!!F2043!VSS(140)!!!!
S!GND!U7C1!BA54!@baseboard_fab2_lib.baseboard_fab2(sch_1):page124_i16@chpset_lib.lbg_core_qat_ext_c(chips)!LBG_CORE_QAT_EXT_C_BGA1-IC,TBD!!!F2043!VSS(141)!!!!
S!GND!U7C1!BA50!@baseboard_fab2_lib.baseboard_fab2(sch_1):page124_i16@chpset_lib.lbg_core_qat_ext_c(chips)!LBG_CORE_QAT_EXT_C_BGA1-IC,TBD!!!F2043!VSS(142)!!!!
S!GND!U7C1!AY68!@baseboard_fab2_lib.baseboard_fab2(sch_1):page124_i16@chpset_lib.lbg_core_qat_ext_c(chips)!LBG_CORE_QAT_EXT_C_BGA1-IC,TBD!!!F2043!VSS(143)!!!!
S!GND!U7C1!AY63!@baseboard_fab2_lib.baseboard_fab2(sch_1):page124_i16@chpset_lib.lbg_core_qat_ext_c(chips)!LBG_CORE_QAT_EXT_C_BGA1-IC,TBD!!!F2043!VSS(144)!!!!
S!GND!U7C1!AY56!@baseboard_fab2_lib.baseboard_fab2(sch_1):page124_i16@chpset_lib.lbg_core_qat_ext_c(chips)!LBG_CORE_QAT_EXT_C_BGA1-IC,TBD!!!F2043!VSS(145)!!!!
S!GND!U7C1!AY22!@baseboard_fab2_lib.baseboard_fab2(sch_1):page124_i16@chpset_lib.lbg_core_qat_ext_c(chips)!LBG_CORE_QAT_EXT_C_BGA1-IC,TBD!!!F2043!VSS(146)!!!!
S!GND!U7C1!AY5!@baseboard_fab2_lib.baseboard_fab2(sch_1):page124_i16@chpset_lib.lbg_core_qat_ext_c(chips)!LBG_CORE_QAT_EXT_C_BGA1-IC,TBD!!!F2043!VSS(147)!!!!
S!GND!U7C1!AW61!@baseboard_fab2_lib.baseboard_fab2(sch_1):page124_i16@chpset_lib.lbg_core_qat_ext_c(chips)!LBG_CORE_QAT_EXT_C_BGA1-IC,TBD!!!F2043!VSS(148)!!!!
S!GND!U7C1!AW58!@baseboard_fab2_lib.baseboard_fab2(sch_1):page124_i16@chpset_lib.lbg_core_qat_ext_c(chips)!LBG_CORE_QAT_EXT_C_BGA1-IC,TBD!!!F2043!VSS(149)!!!!
S!GND!U7C1!AW50!@baseboard_fab2_lib.baseboard_fab2(sch_1):page124_i16@chpset_lib.lbg_core_qat_ext_c(chips)!LBG_CORE_QAT_EXT_C_BGA1-IC,TBD!!!F2043!VSS(150)!!!!
S!GND!U7C1!AW46!@baseboard_fab2_lib.baseboard_fab2(sch_1):page124_i16@chpset_lib.lbg_core_qat_ext_c(chips)!LBG_CORE_QAT_EXT_C_BGA1-IC,TBD!!!F2043!VSS(151)!!!!
S!GND!U7C1!AW41!@baseboard_fab2_lib.baseboard_fab2(sch_1):page124_i16@chpset_lib.lbg_core_qat_ext_c(chips)!LBG_CORE_QAT_EXT_C_BGA1-IC,TBD!!!F2043!VSS(152)!!!!
S!GND!U7C1!AW39!@baseboard_fab2_lib.baseboard_fab2(sch_1):page124_i16@chpset_lib.lbg_core_qat_ext_c(chips)!LBG_CORE_QAT_EXT_C_BGA1-IC,TBD!!!F2043!VSS(153)!!!!
S!GND!U7C1!AW37!@baseboard_fab2_lib.baseboard_fab2(sch_1):page124_i16@chpset_lib.lbg_core_qat_ext_c(chips)!LBG_CORE_QAT_EXT_C_BGA1-IC,TBD!!!F2043!VSS(154)!!!!
S!GND!U7C1!AW36!@baseboard_fab2_lib.baseboard_fab2(sch_1):page124_i16@chpset_lib.lbg_core_qat_ext_c(chips)!LBG_CORE_QAT_EXT_C_BGA1-IC,TBD!!!F2043!VSS(155)!!!!
S!GND!U7C1!AW34!@baseboard_fab2_lib.baseboard_fab2(sch_1):page124_i16@chpset_lib.lbg_core_qat_ext_c(chips)!LBG_CORE_QAT_EXT_C_BGA1-IC,TBD!!!F2043!VSS(156)!!!!
S!GND!U7C1!AW32!@baseboard_fab2_lib.baseboard_fab2(sch_1):page124_i16@chpset_lib.lbg_core_qat_ext_c(chips)!LBG_CORE_QAT_EXT_C_BGA1-IC,TBD!!!F2043!VSS(157)!!!!
S!GND!U7C1!AW30!@baseboard_fab2_lib.baseboard_fab2(sch_1):page124_i16@chpset_lib.lbg_core_qat_ext_c(chips)!LBG_CORE_QAT_EXT_C_BGA1-IC,TBD!!!F2043!VSS(158)!!!!
S!GND!U7C1!AW26!@baseboard_fab2_lib.baseboard_fab2(sch_1):page124_i16@chpset_lib.lbg_core_qat_ext_c(chips)!LBG_CORE_QAT_EXT_C_BGA1-IC,TBD!!!F2043!VSS(159)!!!!
S!GND!U7C1!AW17!@baseboard_fab2_lib.baseboard_fab2(sch_1):page124_i16@chpset_lib.lbg_core_qat_ext_c(chips)!LBG_CORE_QAT_EXT_C_BGA1-IC,TBD!!!F2043!VSS(160)!!!!
S!GND!U7C1!AW13!@baseboard_fab2_lib.baseboard_fab2(sch_1):page124_i16@chpset_lib.lbg_core_qat_ext_c(chips)!LBG_CORE_QAT_EXT_C_BGA1-IC,TBD!!!F2043!VSS(161)!!!!
S!GND!U7C1!AW9!@baseboard_fab2_lib.baseboard_fab2(sch_1):page124_i16@chpset_lib.lbg_core_qat_ext_c(chips)!LBG_CORE_QAT_EXT_C_BGA1-IC,TBD!!!F2043!VSS(162)!!!!
S!GND!U7C1!AV68!@baseboard_fab2_lib.baseboard_fab2(sch_1):page124_i16@chpset_lib.lbg_core_qat_ext_c(chips)!LBG_CORE_QAT_EXT_C_BGA1-IC,TBD!!!F2043!VSS(163)!!!!
S!GND!U7C1!AV59!@baseboard_fab2_lib.baseboard_fab2(sch_1):page124_i16@chpset_lib.lbg_core_qat_ext_c(chips)!LBG_CORE_QAT_EXT_C_BGA1-IC,TBD!!!F2043!VSS(164)!!!!
S!GND!U7C1!AV22!@baseboard_fab2_lib.baseboard_fab2(sch_1):page124_i16@chpset_lib.lbg_core_qat_ext_c(chips)!LBG_CORE_QAT_EXT_C_BGA1-IC,TBD!!!F2043!VSS(165)!!!!
S!GND!U7C1!AV5!@baseboard_fab2_lib.baseboard_fab2(sch_1):page124_i16@chpset_lib.lbg_core_qat_ext_c(chips)!LBG_CORE_QAT_EXT_C_BGA1-IC,TBD!!!F2043!VSS(166)!!!!
S!GND!U7C1!AU61!@baseboard_fab2_lib.baseboard_fab2(sch_1):page124_i16@chpset_lib.lbg_core_qat_ext_c(chips)!LBG_CORE_QAT_EXT_C_BGA1-IC,TBD!!!F2043!VSS(167)!!!!
S!GND!U7C1!AU54!@baseboard_fab2_lib.baseboard_fab2(sch_1):page124_i16@chpset_lib.lbg_core_qat_ext_c(chips)!LBG_CORE_QAT_EXT_C_BGA1-IC,TBD!!!F2043!VSS(168)!!!!
S!GND!U7C1!AU50!@baseboard_fab2_lib.baseboard_fab2(sch_1):page124_i16@chpset_lib.lbg_core_qat_ext_c(chips)!LBG_CORE_QAT_EXT_C_BGA1-IC,TBD!!!F2043!VSS(169)!!!!
S!GND!U7C1!AU46!@baseboard_fab2_lib.baseboard_fab2(sch_1):page124_i16@chpset_lib.lbg_core_qat_ext_c(chips)!LBG_CORE_QAT_EXT_C_BGA1-IC,TBD!!!F2043!VSS(170)!!!!
S!GND!U7C1!AU41!@baseboard_fab2_lib.baseboard_fab2(sch_1):page124_i16@chpset_lib.lbg_core_qat_ext_c(chips)!LBG_CORE_QAT_EXT_C_BGA1-IC,TBD!!!F2043!VSS(171)!!!!
S!GND!U7C1!AE22!@baseboard_fab2_lib.baseboard_fab2(sch_1):page124_i16@chpset_lib.lbg_core_qat_ext_c(chips)!LBG_CORE_QAT_EXT_C_BGA1-IC,TBD!!!F2043!VSS(172)!!!!
S!GND!U7C1!AU30!@baseboard_fab2_lib.baseboard_fab2(sch_1):page124_i16@chpset_lib.lbg_core_qat_ext_c(chips)!LBG_CORE_QAT_EXT_C_BGA1-IC,TBD!!!F2043!VSS(173)!!!!
S!GND!U7C1!AU26!@baseboard_fab2_lib.baseboard_fab2(sch_1):page124_i16@chpset_lib.lbg_core_qat_ext_c(chips)!LBG_CORE_QAT_EXT_C_BGA1-IC,TBD!!!F2043!VSS(174)!!!!
S!GND!U7C1!AT59!@baseboard_fab2_lib.baseboard_fab2(sch_1):page124_i16@chpset_lib.lbg_core_qat_ext_c(chips)!LBG_CORE_QAT_EXT_C_BGA1-IC,TBD!!!F2043!VSS(175)!!!!
S!GND!U7C1!AT46!@baseboard_fab2_lib.baseboard_fab2(sch_1):page124_i16@chpset_lib.lbg_core_qat_ext_c(chips)!LBG_CORE_QAT_EXT_C_BGA1-IC,TBD!!!F2043!VSS(176)!!!!
S!GND!U7C1!AT41!@baseboard_fab2_lib.baseboard_fab2(sch_1):page124_i16@chpset_lib.lbg_core_qat_ext_c(chips)!LBG_CORE_QAT_EXT_C_BGA1-IC,TBD!!!F2043!VSS(177)!!!!
S!GND!U7C1!AT30!@baseboard_fab2_lib.baseboard_fab2(sch_1):page124_i16@chpset_lib.lbg_core_qat_ext_c(chips)!LBG_CORE_QAT_EXT_C_BGA1-IC,TBD!!!F2043!VSS(178)!!!!
S!GND!U7C1!AT26!@baseboard_fab2_lib.baseboard_fab2(sch_1):page124_i16@chpset_lib.lbg_core_qat_ext_c(chips)!LBG_CORE_QAT_EXT_C_BGA1-IC,TBD!!!F2043!VSS(179)!!!!
S!GND!U7C1!AT22!@baseboard_fab2_lib.baseboard_fab2(sch_1):page124_i16@chpset_lib.lbg_core_qat_ext_c(chips)!LBG_CORE_QAT_EXT_C_BGA1-IC,TBD!!!F2043!VSS(180)!!!!
S!GND!U7C1!AT18!@baseboard_fab2_lib.baseboard_fab2(sch_1):page124_i16@chpset_lib.lbg_core_qat_ext_c(chips)!LBG_CORE_QAT_EXT_C_BGA1-IC,TBD!!!F2043!VSS(181)!!!!
S!GND!U7C1!AT15!@baseboard_fab2_lib.baseboard_fab2(sch_1):page124_i16@chpset_lib.lbg_core_qat_ext_c(chips)!LBG_CORE_QAT_EXT_C_BGA1-IC,TBD!!!F2043!VSS(182)!!!!
S!GND!U7C1!AT11!@baseboard_fab2_lib.baseboard_fab2(sch_1):page124_i16@chpset_lib.lbg_core_qat_ext_c(chips)!LBG_CORE_QAT_EXT_C_BGA1-IC,TBD!!!F2043!VSS(183)!!!!
S!GND!U7C1!AT7!@baseboard_fab2_lib.baseboard_fab2(sch_1):page124_i16@chpset_lib.lbg_core_qat_ext_c(chips)!LBG_CORE_QAT_EXT_C_BGA1-IC,TBD!!!F2043!VSS(184)!!!!
S!GND!U7C1!AR72!@baseboard_fab2_lib.baseboard_fab2(sch_1):page124_i16@chpset_lib.lbg_core_qat_ext_c(chips)!LBG_CORE_QAT_EXT_C_BGA1-IC,TBD!!!F2043!VSS(185)!!!!
S!GND!U7C1!AR70!@baseboard_fab2_lib.baseboard_fab2(sch_1):page124_i16@chpset_lib.lbg_core_qat_ext_c(chips)!LBG_CORE_QAT_EXT_C_BGA1-IC,TBD!!!F2043!VSS(186)!!!!
S!GND!U7C1!AR68!@baseboard_fab2_lib.baseboard_fab2(sch_1):page124_i16@chpset_lib.lbg_core_qat_ext_c(chips)!LBG_CORE_QAT_EXT_C_BGA1-IC,TBD!!!F2043!VSS(187)!!!!
S!GND!U7C1!AR65!@baseboard_fab2_lib.baseboard_fab2(sch_1):page124_i16@chpset_lib.lbg_core_qat_ext_c(chips)!LBG_CORE_QAT_EXT_C_BGA1-IC,TBD!!!F2043!VSS(188)!!!!
S!GND!U7C1!AR58!@baseboard_fab2_lib.baseboard_fab2(sch_1):page124_i16@chpset_lib.lbg_core_qat_ext_c(chips)!LBG_CORE_QAT_EXT_C_BGA1-IC,TBD!!!F2043!VSS(189)!!!!
S!GND!U7C1!AR50!@baseboard_fab2_lib.baseboard_fab2(sch_1):page124_i16@chpset_lib.lbg_core_qat_ext_c(chips)!LBG_CORE_QAT_EXT_C_BGA1-IC,TBD!!!F2043!VSS(190)!!!!
S!GND!U7C1!AR5!@baseboard_fab2_lib.baseboard_fab2(sch_1):page124_i16@chpset_lib.lbg_core_qat_ext_c(chips)!LBG_CORE_QAT_EXT_C_BGA1-IC,TBD!!!F2043!VSS(191)!!!!
S!GND!U7C1!AP66!@baseboard_fab2_lib.baseboard_fab2(sch_1):page124_i16@chpset_lib.lbg_core_qat_ext_c(chips)!LBG_CORE_QAT_EXT_C_BGA1-IC,TBD!!!F2043!VSS(192)!!!!
S!GND!U7C1!AP52!@baseboard_fab2_lib.baseboard_fab2(sch_1):page124_i16@chpset_lib.lbg_core_qat_ext_c(chips)!LBG_CORE_QAT_EXT_C_BGA1-IC,TBD!!!F2043!VSS(193)!!!!
S!GND!U7C1!AP46!@baseboard_fab2_lib.baseboard_fab2(sch_1):page124_i16@chpset_lib.lbg_core_qat_ext_c(chips)!LBG_CORE_QAT_EXT_C_BGA1-IC,TBD!!!F2043!VSS(194)!!!!
S!GND!U7C1!AP41!@baseboard_fab2_lib.baseboard_fab2(sch_1):page124_i16@chpset_lib.lbg_core_qat_ext_c(chips)!LBG_CORE_QAT_EXT_C_BGA1-IC,TBD!!!F2043!VSS(195)!!!!
S!GND!U7C1!AP4!@baseboard_fab2_lib.baseboard_fab2(sch_1):page124_i16@chpset_lib.lbg_core_qat_ext_c(chips)!LBG_CORE_QAT_EXT_C_BGA1-IC,TBD!!!F2043!VSS(196)!!!!
S!GND!U7C1!AP30!@baseboard_fab2_lib.baseboard_fab2(sch_1):page124_i16@chpset_lib.lbg_core_qat_ext_c(chips)!LBG_CORE_QAT_EXT_C_BGA1-IC,TBD!!!F2043!VSS(197)!!!!
S!GND!U7C1!AP26!@baseboard_fab2_lib.baseboard_fab2(sch_1):page124_i16@chpset_lib.lbg_core_qat_ext_c(chips)!LBG_CORE_QAT_EXT_C_BGA1-IC,TBD!!!F2043!VSS(198)!!!!
S!GND!U7C1!AP2!@baseboard_fab2_lib.baseboard_fab2(sch_1):page124_i16@chpset_lib.lbg_core_qat_ext_c(chips)!LBG_CORE_QAT_EXT_C_BGA1-IC,TBD!!!F2043!VSS(199)!!!!
S!GND!U7C1!AN9!@baseboard_fab2_lib.baseboard_fab2(sch_1):page124_i16@chpset_lib.lbg_core_qat_ext_c(chips)!LBG_CORE_QAT_EXT_C_BGA1-IC,TBD!!!F2043!VSS(200)!!!!
S!GND!U7C1!AN58!@baseboard_fab2_lib.baseboard_fab2(sch_1):page124_i16@chpset_lib.lbg_core_qat_ext_c(chips)!LBG_CORE_QAT_EXT_C_BGA1-IC,TBD!!!F2043!VSS(201)!!!!
S!GND!U7C1!AN5!@baseboard_fab2_lib.baseboard_fab2(sch_1):page124_i16@chpset_lib.lbg_core_qat_ext_c(chips)!LBG_CORE_QAT_EXT_C_BGA1-IC,TBD!!!F2043!VSS(202)!!!!
S!GND!U7C1!AN20!@baseboard_fab2_lib.baseboard_fab2(sch_1):page124_i16@chpset_lib.lbg_core_qat_ext_c(chips)!LBG_CORE_QAT_EXT_C_BGA1-IC,TBD!!!F2043!VSS(203)!!!!
S!GND!U7C1!AP22!@baseboard_fab2_lib.baseboard_fab2(sch_1):page124_i16@chpset_lib.lbg_core_qat_ext_c(chips)!LBG_CORE_QAT_EXT_C_BGA1-IC,TBD!!!F2043!VSS(204)!!!!
S!GND!U7C1!AN68!@baseboard_fab2_lib.baseboard_fab2(sch_1):page124_i16@chpset_lib.lbg_core_qat_ext_c(chips)!LBG_CORE_QAT_EXT_C_BGA1-IC,TBD!!!F2043!VSS(205)!!!!
S!GND!U7C1!AN17!@baseboard_fab2_lib.baseboard_fab2(sch_1):page124_i16@chpset_lib.lbg_core_qat_ext_c(chips)!LBG_CORE_QAT_EXT_C_BGA1-IC,TBD!!!F2043!VSS(206)!!!!
S!GND!U7C1!AN13!@baseboard_fab2_lib.baseboard_fab2(sch_1):page124_i16@chpset_lib.lbg_core_qat_ext_c(chips)!LBG_CORE_QAT_EXT_C_BGA1-IC,TBD!!!F2043!VSS(207)!!!!
S!GND!U7C1!AM46!@baseboard_fab2_lib.baseboard_fab2(sch_1):page124_i16@chpset_lib.lbg_core_qat_ext_c(chips)!LBG_CORE_QAT_EXT_C_BGA1-IC,TBD!!!F2043!VSS(208)!!!!
S!GND!U7C1!AM41!@baseboard_fab2_lib.baseboard_fab2(sch_1):page124_i16@chpset_lib.lbg_core_qat_ext_c(chips)!LBG_CORE_QAT_EXT_C_BGA1-IC,TBD!!!F2043!VSS(209)!!!!
S!GND!U7C1!AM30!@baseboard_fab2_lib.baseboard_fab2(sch_1):page124_i16@chpset_lib.lbg_core_qat_ext_c(chips)!LBG_CORE_QAT_EXT_C_BGA1-IC,TBD!!!F2043!VSS(210)!!!!
S!GND!U7C1!AM26!@baseboard_fab2_lib.baseboard_fab2(sch_1):page124_i16@chpset_lib.lbg_core_qat_ext_c(chips)!LBG_CORE_QAT_EXT_C_BGA1-IC,TBD!!!F2043!VSS(211)!!!!
S!GND!U7C1!AL72!@baseboard_fab2_lib.baseboard_fab2(sch_1):page124_i16@chpset_lib.lbg_core_qat_ext_c(chips)!LBG_CORE_QAT_EXT_C_BGA1-IC,TBD!!!F2043!VSS(212)!!!!
S!GND!U7C1!AL70!@baseboard_fab2_lib.baseboard_fab2(sch_1):page124_i16@chpset_lib.lbg_core_qat_ext_c(chips)!LBG_CORE_QAT_EXT_C_BGA1-IC,TBD!!!F2043!VSS(213)!!!!
S!GND!U7C1!AL68!@baseboard_fab2_lib.baseboard_fab2(sch_1):page124_i16@chpset_lib.lbg_core_qat_ext_c(chips)!LBG_CORE_QAT_EXT_C_BGA1-IC,TBD!!!F2043!VSS(214)!!!!
S!GND!U7C1!BJ68!@baseboard_fab2_lib.baseboard_fab2(sch_1):page124_i16@chpset_lib.lbg_core_qat_ext_c(chips)!LBG_CORE_QAT_EXT_C_BGA1-IC,TBD!!!F2043!VSS(75)!!!!
S!GND!U7C1!BJ52!@baseboard_fab2_lib.baseboard_fab2(sch_1):page124_i16@chpset_lib.lbg_core_qat_ext_c(chips)!LBG_CORE_QAT_EXT_C_BGA1-IC,TBD!!!F2043!VSS(76)!!!!
S!GND!U7C1!BJ33!@baseboard_fab2_lib.baseboard_fab2(sch_1):page124_i16@chpset_lib.lbg_core_qat_ext_c(chips)!LBG_CORE_QAT_EXT_C_BGA1-IC,TBD!!!F2043!VSS(77)!!!!
S!GND!U7C1!BJ3!@baseboard_fab2_lib.baseboard_fab2(sch_1):page124_i16@chpset_lib.lbg_core_qat_ext_c(chips)!LBG_CORE_QAT_EXT_C_BGA1-IC,TBD!!!F2043!VSS(78)!!!!
S!GND!U7C1!BJ26!@baseboard_fab2_lib.baseboard_fab2(sch_1):page124_i16@chpset_lib.lbg_core_qat_ext_c(chips)!LBG_CORE_QAT_EXT_C_BGA1-IC,TBD!!!F2043!VSS(79)!!!!
S!GND!U7C1!BJ18!@baseboard_fab2_lib.baseboard_fab2(sch_1):page124_i16@chpset_lib.lbg_core_qat_ext_c(chips)!LBG_CORE_QAT_EXT_C_BGA1-IC,TBD!!!F2043!VSS(80)!!!!
S!GND!U7C1!BJ15!@baseboard_fab2_lib.baseboard_fab2(sch_1):page124_i16@chpset_lib.lbg_core_qat_ext_c(chips)!LBG_CORE_QAT_EXT_C_BGA1-IC,TBD!!!F2043!VSS(81)!!!!
S!GND!U7C1!BJ7!@baseboard_fab2_lib.baseboard_fab2(sch_1):page124_i16@chpset_lib.lbg_core_qat_ext_c(chips)!LBG_CORE_QAT_EXT_C_BGA1-IC,TBD!!!F2043!VSS(82)!!!!
S!GND!U7C1!BJ5!@baseboard_fab2_lib.baseboard_fab2(sch_1):page124_i16@chpset_lib.lbg_core_qat_ext_c(chips)!LBG_CORE_QAT_EXT_C_BGA1-IC,TBD!!!F2043!VSS(83)!!!!
S!GND!U7C1!BJ11!@baseboard_fab2_lib.baseboard_fab2(sch_1):page124_i16@chpset_lib.lbg_core_qat_ext_c(chips)!LBG_CORE_QAT_EXT_C_BGA1-IC,TBD!!!F2043!VSS(84)!!!!
S!GND!U7C1!BJ1!@baseboard_fab2_lib.baseboard_fab2(sch_1):page124_i16@chpset_lib.lbg_core_qat_ext_c(chips)!LBG_CORE_QAT_EXT_C_BGA1-IC,TBD!!!F2043!VSS(85)!!!!
S!GND!U7C1!BH54!@baseboard_fab2_lib.baseboard_fab2(sch_1):page124_i16@chpset_lib.lbg_core_qat_ext_c(chips)!LBG_CORE_QAT_EXT_C_BGA1-IC,TBD!!!F2043!VSS(86)!!!!
S!GND!U7C1!BH46!@baseboard_fab2_lib.baseboard_fab2(sch_1):page124_i16@chpset_lib.lbg_core_qat_ext_c(chips)!LBG_CORE_QAT_EXT_C_BGA1-IC,TBD!!!F2043!VSS(87)!!!!
S!GND!U7C1!BH42!@baseboard_fab2_lib.baseboard_fab2(sch_1):page124_i16@chpset_lib.lbg_core_qat_ext_c(chips)!LBG_CORE_QAT_EXT_C_BGA1-IC,TBD!!!F2043!VSS(88)!!!!
S!GND!U7C1!BH38!@baseboard_fab2_lib.baseboard_fab2(sch_1):page124_i16@chpset_lib.lbg_core_qat_ext_c(chips)!LBG_CORE_QAT_EXT_C_BGA1-IC,TBD!!!F2043!VSS(89)!!!!
S!GND!U7C1!BH27!@baseboard_fab2_lib.baseboard_fab2(sch_1):page124_i16@chpset_lib.lbg_core_qat_ext_c(chips)!LBG_CORE_QAT_EXT_C_BGA1-IC,TBD!!!F2043!VSS(90)!!!!
S!GND!U7C1!BG63!@baseboard_fab2_lib.baseboard_fab2(sch_1):page124_i16@chpset_lib.lbg_core_qat_ext_c(chips)!LBG_CORE_QAT_EXT_C_BGA1-IC,TBD!!!F2043!VSS(91)!!!!
S!GND!U7C1!BG59!@baseboard_fab2_lib.baseboard_fab2(sch_1):page124_i16@chpset_lib.lbg_core_qat_ext_c(chips)!LBG_CORE_QAT_EXT_C_BGA1-IC,TBD!!!F2043!VSS(92)!!!!
S!GND!U7C1!BG48!@baseboard_fab2_lib.baseboard_fab2(sch_1):page124_i16@chpset_lib.lbg_core_qat_ext_c(chips)!LBG_CORE_QAT_EXT_C_BGA1-IC,TBD!!!F2043!VSS(93)!!!!
S!GND!U7C1!BG33!@baseboard_fab2_lib.baseboard_fab2(sch_1):page124_i16@chpset_lib.lbg_core_qat_ext_c(chips)!LBG_CORE_QAT_EXT_C_BGA1-IC,TBD!!!F2043!VSS(94)!!!!
S!GND!U7C1!BF9!@baseboard_fab2_lib.baseboard_fab2(sch_1):page124_i16@chpset_lib.lbg_core_qat_ext_c(chips)!LBG_CORE_QAT_EXT_C_BGA1-IC,TBD!!!F2043!VSS(95)!!!!
S!GND!U7C1!BF68!@baseboard_fab2_lib.baseboard_fab2(sch_1):page124_i16@chpset_lib.lbg_core_qat_ext_c(chips)!LBG_CORE_QAT_EXT_C_BGA1-IC,TBD!!!F2043!VSS(96)!!!!
S!GND!U7C1!BF65!@baseboard_fab2_lib.baseboard_fab2(sch_1):page124_i16@chpset_lib.lbg_core_qat_ext_c(chips)!LBG_CORE_QAT_EXT_C_BGA1-IC,TBD!!!F2043!VSS(97)!!!!
S!GND!U7C1!BF61!@baseboard_fab2_lib.baseboard_fab2(sch_1):page124_i16@chpset_lib.lbg_core_qat_ext_c(chips)!LBG_CORE_QAT_EXT_C_BGA1-IC,TBD!!!F2043!VSS(98)!!!!
S!GND!U7C1!BF58!@baseboard_fab2_lib.baseboard_fab2(sch_1):page124_i16@chpset_lib.lbg_core_qat_ext_c(chips)!LBG_CORE_QAT_EXT_C_BGA1-IC,TBD!!!F2043!VSS(99)!!!!
S!GND!U7C1!CA52!@baseboard_fab2_lib.baseboard_fab2(sch_1):page124_i15@chpset_lib.lbg_core_qat_ext_c(chips)!LBG_CORE_QAT_EXT_C_BGA1-IC,TBD!!!F2042!VSS(0)!!!!
S!GND!U7C1!BW15!@baseboard_fab2_lib.baseboard_fab2(sch_1):page124_i15@chpset_lib.lbg_core_qat_ext_c(chips)!LBG_CORE_QAT_EXT_C_BGA1-IC,TBD!!!F2042!VSS(10)!!!!
S!GND!U7C1!BV40!@baseboard_fab2_lib.baseboard_fab2(sch_1):page124_i15@chpset_lib.lbg_core_qat_ext_c(chips)!LBG_CORE_QAT_EXT_C_BGA1-IC,TBD!!!F2042!VSS(11)!!!!
S!GND!U7C1!BU9!@baseboard_fab2_lib.baseboard_fab2(sch_1):page124_i15@chpset_lib.lbg_core_qat_ext_c(chips)!LBG_CORE_QAT_EXT_C_BGA1-IC,TBD!!!F2042!VSS(12)!!!!
S!GND!U7C1!BU63!@baseboard_fab2_lib.baseboard_fab2(sch_1):page124_i15@chpset_lib.lbg_core_qat_ext_c(chips)!LBG_CORE_QAT_EXT_C_BGA1-IC,TBD!!!F2042!VSS(13)!!!!
S!GND!U7C1!BU61!@baseboard_fab2_lib.baseboard_fab2(sch_1):page124_i15@chpset_lib.lbg_core_qat_ext_c(chips)!LBG_CORE_QAT_EXT_C_BGA1-IC,TBD!!!F2042!VSS(14)!!!!
S!GND!U7C1!BU59!@baseboard_fab2_lib.baseboard_fab2(sch_1):page124_i15@chpset_lib.lbg_core_qat_ext_c(chips)!LBG_CORE_QAT_EXT_C_BGA1-IC,TBD!!!F2042!VSS(15)!!!!
S!GND!U7C1!BU57!@baseboard_fab2_lib.baseboard_fab2(sch_1):page124_i15@chpset_lib.lbg_core_qat_ext_c(chips)!LBG_CORE_QAT_EXT_C_BGA1-IC,TBD!!!F2042!VSS(16)!!!!
S!GND!U7C1!BU54!@baseboard_fab2_lib.baseboard_fab2(sch_1):page124_i15@chpset_lib.lbg_core_qat_ext_c(chips)!LBG_CORE_QAT_EXT_C_BGA1-IC,TBD!!!F2042!VSS(17)!!!!
S!GND!U7C1!BU52!@baseboard_fab2_lib.baseboard_fab2(sch_1):page124_i15@chpset_lib.lbg_core_qat_ext_c(chips)!LBG_CORE_QAT_EXT_C_BGA1-IC,TBD!!!F2042!VSS(18)!!!!
S!GND!U7C1!BU50!@baseboard_fab2_lib.baseboard_fab2(sch_1):page124_i15@chpset_lib.lbg_core_qat_ext_c(chips)!LBG_CORE_QAT_EXT_C_BGA1-IC,TBD!!!F2042!VSS(19)!!!!
S!GND!U7C1!CA50!@baseboard_fab2_lib.baseboard_fab2(sch_1):page124_i15@chpset_lib.lbg_core_qat_ext_c(chips)!LBG_CORE_QAT_EXT_C_BGA1-IC,TBD!!!F2042!VSS(1)!!!!
S!GND!U7C1!BU48!@baseboard_fab2_lib.baseboard_fab2(sch_1):page124_i15@chpset_lib.lbg_core_qat_ext_c(chips)!LBG_CORE_QAT_EXT_C_BGA1-IC,TBD!!!F2042!VSS(20)!!!!
S!GND!U7C1!BU45!@baseboard_fab2_lib.baseboard_fab2(sch_1):page124_i15@chpset_lib.lbg_core_qat_ext_c(chips)!LBG_CORE_QAT_EXT_C_BGA1-IC,TBD!!!F2042!VSS(21)!!!!
S!GND!U7C1!BU43!@baseboard_fab2_lib.baseboard_fab2(sch_1):page124_i15@chpset_lib.lbg_core_qat_ext_c(chips)!LBG_CORE_QAT_EXT_C_BGA1-IC,TBD!!!F2042!VSS(22)!!!!
S!GND!U7C1!BU41!@baseboard_fab2_lib.baseboard_fab2(sch_1):page124_i15@chpset_lib.lbg_core_qat_ext_c(chips)!LBG_CORE_QAT_EXT_C_BGA1-IC,TBD!!!F2042!VSS(23)!!!!
S!GND!U7C1!BU39!@baseboard_fab2_lib.baseboard_fab2(sch_1):page124_i15@chpset_lib.lbg_core_qat_ext_c(chips)!LBG_CORE_QAT_EXT_C_BGA1-IC,TBD!!!F2042!VSS(24)!!!!
S!GND!U7C1!BU37!@baseboard_fab2_lib.baseboard_fab2(sch_1):page124_i15@chpset_lib.lbg_core_qat_ext_c(chips)!LBG_CORE_QAT_EXT_C_BGA1-IC,TBD!!!F2042!VSS(25)!!!!
S!GND!U7C1!BU34!@baseboard_fab2_lib.baseboard_fab2(sch_1):page124_i15@chpset_lib.lbg_core_qat_ext_c(chips)!LBG_CORE_QAT_EXT_C_BGA1-IC,TBD!!!F2042!VSS(26)!!!!
S!GND!U7C1!BU32!@baseboard_fab2_lib.baseboard_fab2(sch_1):page124_i15@chpset_lib.lbg_core_qat_ext_c(chips)!LBG_CORE_QAT_EXT_C_BGA1-IC,TBD!!!F2042!VSS(27)!!!!
S!GND!U7C1!BU30!@baseboard_fab2_lib.baseboard_fab2(sch_1):page124_i15@chpset_lib.lbg_core_qat_ext_c(chips)!LBG_CORE_QAT_EXT_C_BGA1-IC,TBD!!!F2042!VSS(28)!!!!
S!GND!U7C1!BU28!@baseboard_fab2_lib.baseboard_fab2(sch_1):page124_i15@chpset_lib.lbg_core_qat_ext_c(chips)!LBG_CORE_QAT_EXT_C_BGA1-IC,TBD!!!F2042!VSS(29)!!!!
S!GND!U7C1!CA26!@baseboard_fab2_lib.baseboard_fab2(sch_1):page124_i15@chpset_lib.lbg_core_qat_ext_c(chips)!LBG_CORE_QAT_EXT_C_BGA1-IC,TBD!!!F2042!VSS(2)!!!!
S!GND!U7C1!BU26!@baseboard_fab2_lib.baseboard_fab2(sch_1):page124_i15@chpset_lib.lbg_core_qat_ext_c(chips)!LBG_CORE_QAT_EXT_C_BGA1-IC,TBD!!!F2042!VSS(30)!!!!
S!GND!U7C1!BU24!@baseboard_fab2_lib.baseboard_fab2(sch_1):page124_i15@chpset_lib.lbg_core_qat_ext_c(chips)!LBG_CORE_QAT_EXT_C_BGA1-IC,TBD!!!F2042!VSS(31)!!!!
S!GND!U7C1!BU22!@baseboard_fab2_lib.baseboard_fab2(sch_1):page124_i15@chpset_lib.lbg_core_qat_ext_c(chips)!LBG_CORE_QAT_EXT_C_BGA1-IC,TBD!!!F2042!VSS(32)!!!!
S!GND!U7C1!BU20!@baseboard_fab2_lib.baseboard_fab2(sch_1):page124_i15@chpset_lib.lbg_core_qat_ext_c(chips)!LBG_CORE_QAT_EXT_C_BGA1-IC,TBD!!!F2042!VSS(33)!!!!
S!GND!U7C1!BU18!@baseboard_fab2_lib.baseboard_fab2(sch_1):page124_i15@chpset_lib.lbg_core_qat_ext_c(chips)!LBG_CORE_QAT_EXT_C_BGA1-IC,TBD!!!F2042!VSS(34)!!!!
S!GND!U7C1!BU15!@baseboard_fab2_lib.baseboard_fab2(sch_1):page124_i15@chpset_lib.lbg_core_qat_ext_c(chips)!LBG_CORE_QAT_EXT_C_BGA1-IC,TBD!!!F2042!VSS(35)!!!!
S!GND!U7C1!BV49!@baseboard_fab2_lib.baseboard_fab2(sch_1):page124_i15@chpset_lib.lbg_core_qat_ext_c(chips)!LBG_CORE_QAT_EXT_C_BGA1-IC,TBD!!!F2042!VSS(36)!!!!
S!GND!U7C1!BU11!@baseboard_fab2_lib.baseboard_fab2(sch_1):page124_i15@chpset_lib.lbg_core_qat_ext_c(chips)!LBG_CORE_QAT_EXT_C_BGA1-IC,TBD!!!F2042!VSS(37)!!!!
S!GND!U7C1!BU13!@baseboard_fab2_lib.baseboard_fab2(sch_1):page124_i15@chpset_lib.lbg_core_qat_ext_c(chips)!LBG_CORE_QAT_EXT_C_BGA1-IC,TBD!!!F2042!VSS(38)!!!!
S!GND!U7C1!BT66!@baseboard_fab2_lib.baseboard_fab2(sch_1):page124_i15@chpset_lib.lbg_core_qat_ext_c(chips)!LBG_CORE_QAT_EXT_C_BGA1-IC,TBD!!!F2042!VSS(39)!!!!
S!GND!U7C1!CA18!@baseboard_fab2_lib.baseboard_fab2(sch_1):page124_i15@chpset_lib.lbg_core_qat_ext_c(chips)!LBG_CORE_QAT_EXT_C_BGA1-IC,TBD!!!F2042!VSS(3)!!!!
S!GND!U7C1!BR6!@baseboard_fab2_lib.baseboard_fab2(sch_1):page124_i15@chpset_lib.lbg_core_qat_ext_c(chips)!LBG_CORE_QAT_EXT_C_BGA1-IC,TBD!!!F2042!VSS(40)!!!!
S!GND!U7C1!BR58!@baseboard_fab2_lib.baseboard_fab2(sch_1):page124_i15@chpset_lib.lbg_core_qat_ext_c(chips)!LBG_CORE_QAT_EXT_C_BGA1-IC,TBD!!!F2042!VSS(41)!!!!
S!GND!U7C1!BR54!@baseboard_fab2_lib.baseboard_fab2(sch_1):page124_i15@chpset_lib.lbg_core_qat_ext_c(chips)!LBG_CORE_QAT_EXT_C_BGA1-IC,TBD!!!F2042!VSS(42)!!!!
S!GND!U7C1!BT8!@baseboard_fab2_lib.baseboard_fab2(sch_1):page124_i15@chpset_lib.lbg_core_qat_ext_c(chips)!LBG_CORE_QAT_EXT_C_BGA1-IC,TBD!!!F2042!VSS(43)!!!!
S!GND!U7C1!BR50!@baseboard_fab2_lib.baseboard_fab2(sch_1):page124_i15@chpset_lib.lbg_core_qat_ext_c(chips)!LBG_CORE_QAT_EXT_C_BGA1-IC,TBD!!!F2042!VSS(44)!!!!
S!GND!U7C1!BR20!@baseboard_fab2_lib.baseboard_fab2(sch_1):page124_i15@chpset_lib.lbg_core_qat_ext_c(chips)!LBG_CORE_QAT_EXT_C_BGA1-IC,TBD!!!F2042!VSS(45)!!!!
S!GND!U7C1!BN66!@baseboard_fab2_lib.baseboard_fab2(sch_1):page124_i15@chpset_lib.lbg_core_qat_ext_c(chips)!LBG_CORE_QAT_EXT_C_BGA1-IC,TBD!!!F2042!VSS(46)!!!!
S!GND!U7C1!BN52!@baseboard_fab2_lib.baseboard_fab2(sch_1):page124_i15@chpset_lib.lbg_core_qat_ext_c(chips)!LBG_CORE_QAT_EXT_C_BGA1-IC,TBD!!!F2042!VSS(47)!!!!
S!GND!U7C1!BN5!@baseboard_fab2_lib.baseboard_fab2(sch_1):page124_i15@chpset_lib.lbg_core_qat_ext_c(chips)!LBG_CORE_QAT_EXT_C_BGA1-IC,TBD!!!F2042!VSS(48)!!!!
S!GND!U7C1!BN59!@baseboard_fab2_lib.baseboard_fab2(sch_1):page124_i15@chpset_lib.lbg_core_qat_ext_c(chips)!LBG_CORE_QAT_EXT_C_BGA1-IC,TBD!!!F2042!VSS(49)!!!!
S!GND!U7C1!CA15!@baseboard_fab2_lib.baseboard_fab2(sch_1):page124_i15@chpset_lib.lbg_core_qat_ext_c(chips)!LBG_CORE_QAT_EXT_C_BGA1-IC,TBD!!!F2042!VSS(4)!!!!
S!GND!U7C1!BN22!@baseboard_fab2_lib.baseboard_fab2(sch_1):page124_i15@chpset_lib.lbg_core_qat_ext_c(chips)!LBG_CORE_QAT_EXT_C_BGA1-IC,TBD!!!F2042!VSS(50)!!!!
S!GND!U7C1!BM9!@baseboard_fab2_lib.baseboard_fab2(sch_1):page124_i15@chpset_lib.lbg_core_qat_ext_c(chips)!LBG_CORE_QAT_EXT_C_BGA1-IC,TBD!!!F2042!VSS(51)!!!!
S!GND!U7C1!BM71!@baseboard_fab2_lib.baseboard_fab2(sch_1):page124_i15@chpset_lib.lbg_core_qat_ext_c(chips)!LBG_CORE_QAT_EXT_C_BGA1-IC,TBD!!!F2042!VSS(52)!!!!
S!GND!U7C1!BM69!@baseboard_fab2_lib.baseboard_fab2(sch_1):page124_i15@chpset_lib.lbg_core_qat_ext_c(chips)!LBG_CORE_QAT_EXT_C_BGA1-IC,TBD!!!F2042!VSS(53)!!!!
S!GND!U7C1!BM58!@baseboard_fab2_lib.baseboard_fab2(sch_1):page124_i15@chpset_lib.lbg_core_qat_ext_c(chips)!LBG_CORE_QAT_EXT_C_BGA1-IC,TBD!!!F2042!VSS(54)!!!!
S!GND!U7C1!BM50!@baseboard_fab2_lib.baseboard_fab2(sch_1):page124_i15@chpset_lib.lbg_core_qat_ext_c(chips)!LBG_CORE_QAT_EXT_C_BGA1-IC,TBD!!!F2042!VSS(55)!!!!
S!GND!U7C1!BM46!@baseboard_fab2_lib.baseboard_fab2(sch_1):page124_i15@chpset_lib.lbg_core_qat_ext_c(chips)!LBG_CORE_QAT_EXT_C_BGA1-IC,TBD!!!F2042!VSS(56)!!!!
S!GND!U7C1!BN37!@baseboard_fab2_lib.baseboard_fab2(sch_1):page124_i15@chpset_lib.lbg_core_qat_ext_c(chips)!LBG_CORE_QAT_EXT_C_BGA1-IC,TBD!!!F2042!VSS(57)!!!!
S!GND!U7C1!BM17!@baseboard_fab2_lib.baseboard_fab2(sch_1):page124_i15@chpset_lib.lbg_core_qat_ext_c(chips)!LBG_CORE_QAT_EXT_C_BGA1-IC,TBD!!!F2042!VSS(58)!!!!
S!GND!U7C1!BM13!@baseboard_fab2_lib.baseboard_fab2(sch_1):page124_i15@chpset_lib.lbg_core_qat_ext_c(chips)!LBG_CORE_QAT_EXT_C_BGA1-IC,TBD!!!F2042!VSS(59)!!!!
S!GND!U7C1!BY49!@baseboard_fab2_lib.baseboard_fab2(sch_1):page124_i15@chpset_lib.lbg_core_qat_ext_c(chips)!LBG_CORE_QAT_EXT_C_BGA1-IC,TBD!!!F2042!VSS(5)!!!!
S!GND!U7C1!BL72!@baseboard_fab2_lib.baseboard_fab2(sch_1):page124_i15@chpset_lib.lbg_core_qat_ext_c(chips)!LBG_CORE_QAT_EXT_C_BGA1-IC,TBD!!!F2042!VSS(60)!!!!
S!GND!U7C1!BL70!@baseboard_fab2_lib.baseboard_fab2(sch_1):page124_i15@chpset_lib.lbg_core_qat_ext_c(chips)!LBG_CORE_QAT_EXT_C_BGA1-IC,TBD!!!F2042!VSS(61)!!!!
S!GND!U7C1!BL63!@baseboard_fab2_lib.baseboard_fab2(sch_1):page124_i15@chpset_lib.lbg_core_qat_ext_c(chips)!LBG_CORE_QAT_EXT_C_BGA1-IC,TBD!!!F2042!VSS(62)!!!!
S!GND!U7C1!BL5!@baseboard_fab2_lib.baseboard_fab2(sch_1):page124_i15@chpset_lib.lbg_core_qat_ext_c(chips)!LBG_CORE_QAT_EXT_C_BGA1-IC,TBD!!!F2042!VSS(63)!!!!
S!GND!U7C1!BL37!@baseboard_fab2_lib.baseboard_fab2(sch_1):page124_i15@chpset_lib.lbg_core_qat_ext_c(chips)!LBG_CORE_QAT_EXT_C_BGA1-IC,TBD!!!F2042!VSS(64)!!!!
S!GND!U7C1!BL68!@baseboard_fab2_lib.baseboard_fab2(sch_1):page124_i15@chpset_lib.lbg_core_qat_ext_c(chips)!LBG_CORE_QAT_EXT_C_BGA1-IC,TBD!!!F2042!VSS(65)!!!!
S!GND!U7C1!BL40!@baseboard_fab2_lib.baseboard_fab2(sch_1):page124_i15@chpset_lib.lbg_core_qat_ext_c(chips)!LBG_CORE_QAT_EXT_C_BGA1-IC,TBD!!!F2042!VSS(66)!!!!
S!GND!U7C1!BL22!@baseboard_fab2_lib.baseboard_fab2(sch_1):page124_i15@chpset_lib.lbg_core_qat_ext_c(chips)!LBG_CORE_QAT_EXT_C_BGA1-IC,TBD!!!F2042!VSS(67)!!!!
S!GND!U7C1!BK50!@baseboard_fab2_lib.baseboard_fab2(sch_1):page124_i15@chpset_lib.lbg_core_qat_ext_c(chips)!LBG_CORE_QAT_EXT_C_BGA1-IC,TBD!!!F2042!VSS(68)!!!!
S!GND!U7C1!BK42!@baseboard_fab2_lib.baseboard_fab2(sch_1):page124_i15@chpset_lib.lbg_core_qat_ext_c(chips)!LBG_CORE_QAT_EXT_C_BGA1-IC,TBD!!!F2042!VSS(69)!!!!
S!GND!U7C1!BY40!@baseboard_fab2_lib.baseboard_fab2(sch_1):page124_i15@chpset_lib.lbg_core_qat_ext_c(chips)!LBG_CORE_QAT_EXT_C_BGA1-IC,TBD!!!F2042!VSS(6)!!!!
S!GND!U7C1!BK38!@baseboard_fab2_lib.baseboard_fab2(sch_1):page124_i15@chpset_lib.lbg_core_qat_ext_c(chips)!LBG_CORE_QAT_EXT_C_BGA1-IC,TBD!!!F2042!VSS(70)!!!!
S!GND!U7C1!BK35!@baseboard_fab2_lib.baseboard_fab2(sch_1):page124_i15@chpset_lib.lbg_core_qat_ext_c(chips)!LBG_CORE_QAT_EXT_C_BGA1-IC,TBD!!!F2042!VSS(71)!!!!
S!GND!U7C1!BK31!@baseboard_fab2_lib.baseboard_fab2(sch_1):page124_i15@chpset_lib.lbg_core_qat_ext_c(chips)!LBG_CORE_QAT_EXT_C_BGA1-IC,TBD!!!F2042!VSS(72)!!!!
S!GND!U7C1!BK27!@baseboard_fab2_lib.baseboard_fab2(sch_1):page124_i15@chpset_lib.lbg_core_qat_ext_c(chips)!LBG_CORE_QAT_EXT_C_BGA1-IC,TBD!!!F2042!VSS(73)!!!!
S!GND!U7C1!BK24!@baseboard_fab2_lib.baseboard_fab2(sch_1):page124_i15@chpset_lib.lbg_core_qat_ext_c(chips)!LBG_CORE_QAT_EXT_C_BGA1-IC,TBD!!!F2042!VSS(74)!!!!
S!GND!U7C1!BW52!@baseboard_fab2_lib.baseboard_fab2(sch_1):page124_i15@chpset_lib.lbg_core_qat_ext_c(chips)!LBG_CORE_QAT_EXT_C_BGA1-IC,TBD!!!F2042!VSS(7)!!!!
S!GND!U7C1!BW26!@baseboard_fab2_lib.baseboard_fab2(sch_1):page124_i15@chpset_lib.lbg_core_qat_ext_c(chips)!LBG_CORE_QAT_EXT_C_BGA1-IC,TBD!!!F2042!VSS(8)!!!!
S!GND!U7C1!BW18!@baseboard_fab2_lib.baseboard_fab2(sch_1):page124_i15@chpset_lib.lbg_core_qat_ext_c(chips)!LBG_CORE_QAT_EXT_C_BGA1-IC,TBD!!!F2042!VSS(9)!!!!
S!TP_JUMPER_BLOCK_1_1!J8G2!1!@baseboard_fab2_lib.baseboard_fab2(sch_1):page134_i5@mstr_conn.conn12_d59987001(chips)!CONN12_D59987001_THLF-CONN,D59A!!!F2258!IO1!!!!
S!FM_DIS_ADR_DLY!J8G2!10!@baseboard_fab2_lib.baseboard_fab2(sch_1):page134_i5@mstr_conn.conn12_d59987001(chips)!CONN12_D59987001_THLF-CONN,D59A!!!F2258!IO10!!!!
S!GND!J8G2!11!@baseboard_fab2_lib.baseboard_fab2(sch_1):page134_i5@mstr_conn.conn12_d59987001(chips)!CONN12_D59987001_THLF-CONN,D59A!!!F2258!IO11!!!!
S!GND!J8G2!12!@baseboard_fab2_lib.baseboard_fab2(sch_1):page134_i5@mstr_conn.conn12_d59987001(chips)!CONN12_D59987001_THLF-CONN,D59A!!!F2258!IO12!!!!
S!TP_JUMPER_BLOCK_1_2!J8G2!2!@baseboard_fab2_lib.baseboard_fab2(sch_1):page134_i5@mstr_conn.conn12_d59987001(chips)!CONN12_D59987001_THLF-CONN,D59A!!!F2258!IO2!!!!
S!RST_BMC_SRST_N!J8G2!3!@baseboard_fab2_lib.baseboard_fab2(sch_1):page134_i5@mstr_conn.conn12_d59987001(chips)!CONN12_D59987001_THLF-CONN,D59A!!!F2258!IO3!!!!
S!FM_IE_DISABLE_N!J8G2!4!@baseboard_fab2_lib.baseboard_fab2(sch_1):page134_i5@mstr_conn.conn12_d59987001(chips)!CONN12_D59987001_THLF-CONN,D59A!!!F2258!IO4!!!!
S!GND!J8G2!5!@baseboard_fab2_lib.baseboard_fab2(sch_1):page134_i5@mstr_conn.conn12_d59987001(chips)!CONN12_D59987001_THLF-CONN,D59A!!!F2258!IO5!!!!
S!GND!J8G2!6!@baseboard_fab2_lib.baseboard_fab2(sch_1):page134_i5@mstr_conn.conn12_d59987001(chips)!CONN12_D59987001_THLF-CONN,D59A!!!F2258!IO6!!!!
S!TP_JUMPER_BLOCK_1_7!J8G2!7!@baseboard_fab2_lib.baseboard_fab2(sch_1):page134_i5@mstr_conn.conn12_d59987001(chips)!CONN12_D59987001_THLF-CONN,D59A!!!F2258!IO7!!!!
S!TP_JUMPER_BLOCK_1_8!J8G2!8!@baseboard_fab2_lib.baseboard_fab2(sch_1):page134_i5@mstr_conn.conn12_d59987001(chips)!CONN12_D59987001_THLF-CONN,D59A!!!F2258!IO8!!!!
S!FM_CPLD_UART_CH_LOCK_N!J8G2!9!@baseboard_fab2_lib.baseboard_fab2(sch_1):page134_i5@mstr_conn.conn12_d59987001(chips)!CONN12_D59987001_THLF-CONN,D59A!!!F2258!IO9!!!!
S!TP_ME_RCVR_BOOT!J7G3!1!@baseboard_fab2_lib.baseboard_fab2(sch_1):page136_i167@mstr_conn.conn12_d59987001(chips)!CONN12_D59987001_THLF-CONN,D59A!!!F2257!IO1!!!!
S!FM_BIOS_TOP_SWAP!J7G3!10!@baseboard_fab2_lib.baseboard_fab2(sch_1):page136_i167@mstr_conn.conn12_d59987001(chips)!CONN12_D59987001_THLF-CONN,D59A!!!F2257!IO10!!!!
S!PD_PASSWORD_CLEAR!J7G3!11!@baseboard_fab2_lib.baseboard_fab2(sch_1):page136_i167@mstr_conn.conn12_d59987001(chips)!CONN12_D59987001_THLF-CONN,D59A!!!F2257!IO11!!!!
S!PU_BIOS_RECOVER_BOOT!J7G3!12!@baseboard_fab2_lib.baseboard_fab2(sch_1):page136_i167@mstr_conn.conn12_d59987001(chips)!CONN12_D59987001_THLF-CONN,D59A!!!F2257!IO12!!!!
S!TP_BIOS_USB_RECOVERY!J7G3!2!@baseboard_fab2_lib.baseboard_fab2(sch_1):page136_i167@mstr_conn.conn12_d59987001(chips)!CONN12_D59987001_THLF-CONN,D59A!!!F2257!IO2!!!!
S!FM_ME_RECOVER_N!J7G3!3!@baseboard_fab2_lib.baseboard_fab2(sch_1):page136_i167@mstr_conn.conn12_d59987001(chips)!CONN12_D59987001_THLF-CONN,D59A!!!F2257!IO3!!!!
S!FM_BIOS_USB_RECOVERY!J7G3!4!@baseboard_fab2_lib.baseboard_fab2(sch_1):page136_i167@mstr_conn.conn12_d59987001(chips)!CONN12_D59987001_THLF-CONN,D59A!!!F2257!IO4!!!!
S!PD_ME_RCVR_N!J7G3!5!@baseboard_fab2_lib.baseboard_fab2(sch_1):page136_i167@mstr_conn.conn12_d59987001(chips)!CONN12_D59987001_THLF-CONN,D59A!!!F2257!IO5!!!!
S!PU_BIOS_USB_RECOVERY!J7G3!6!@baseboard_fab2_lib.baseboard_fab2(sch_1):page136_i167@mstr_conn.conn12_d59987001(chips)!CONN12_D59987001_THLF-CONN,D59A!!!F2257!IO6!!!!
S!TP_PASSWORD_CLEAR!J7G3!7!@baseboard_fab2_lib.baseboard_fab2(sch_1):page136_i167@mstr_conn.conn12_d59987001(chips)!CONN12_D59987001_THLF-CONN,D59A!!!F2257!IO7!!!!
S!TP_BIOS_RECOVER_BOOT!J7G3!8!@baseboard_fab2_lib.baseboard_fab2(sch_1):page136_i167@mstr_conn.conn12_d59987001(chips)!CONN12_D59987001_THLF-CONN,D59A!!!F2257!IO8!!!!
S!FM_PASSWORD_CLEAR_N!J7G3!9!@baseboard_fab2_lib.baseboard_fab2(sch_1):page136_i167@mstr_conn.conn12_d59987001(chips)!CONN12_D59987001_THLF-CONN,D59A!!!F2257!IO9!!!!
S!TP_BMC_DISABLE!J9G1!1!@baseboard_fab2_lib.baseboard_fab2(sch_1):page137_i100@mstr_conn.conn12_d59987001(chips)!CONN12_D59987001_THLF-CONN,D59A!!!F2256!IO1!!!!
S!TP_JUMPER_BLOCK_2_10!J9G1!10!@baseboard_fab2_lib.baseboard_fab2(sch_1):page137_i100@mstr_conn.conn12_d59987001(chips)!CONN12_D59987001_THLF-CONN,D59A!!!F2256!IO10!!!!
S!PD_IE_DEBUG_MODE!J9G1!11!@baseboard_fab2_lib.baseboard_fab2(sch_1):page137_i100@mstr_conn.conn12_d59987001(chips)!CONN12_D59987001_THLF-CONN,D59A!!!F2256!IO11!!!!
S!TP_JUMPER_BLOCK_2_12!J9G1!12!@baseboard_fab2_lib.baseboard_fab2(sch_1):page137_i100@mstr_conn.conn12_d59987001(chips)!CONN12_D59987001_THLF-CONN,D59A!!!F2256!IO12!!!!
S!TP_RST_RTCRST_N!J9G1!2!@baseboard_fab2_lib.baseboard_fab2(sch_1):page137_i100@mstr_conn.conn12_d59987001(chips)!CONN12_D59987001_THLF-CONN,D59A!!!F2256!IO2!!!!
S!FM_ROMA<0>!J9G1!3!@baseboard_fab2_lib.baseboard_fab2(sch_1):page137_i100@mstr_conn.conn12_d59987001(chips)!CONN12_D59987001_THLF-CONN,D59A!!!F2256!IO3!!!!
S!RST_RTCRST_N!J9G1!4!@baseboard_fab2_lib.baseboard_fab2(sch_1):page137_i100@mstr_conn.conn12_d59987001(chips)!CONN12_D59987001_THLF-CONN,D59A!!!F2256!IO4!!!!
S!FM_BMC_DISABLE!J9G1!5!@baseboard_fab2_lib.baseboard_fab2(sch_1):page137_i100@mstr_conn.conn12_d59987001(chips)!CONN12_D59987001_THLF-CONN,D59A!!!F2256!IO5!!!!
S!PD_RST_RTCRST_N!J9G1!6!@baseboard_fab2_lib.baseboard_fab2(sch_1):page137_i100@mstr_conn.conn12_d59987001(chips)!CONN12_D59987001_THLF-CONN,D59A!!!F2256!IO6!!!!
S!TP_IE_DEBUG_MODE!J9G1!7!@baseboard_fab2_lib.baseboard_fab2(sch_1):page137_i100@mstr_conn.conn12_d59987001(chips)!CONN12_D59987001_THLF-CONN,D59A!!!F2256!IO7!!!!
S!TP_JUMPER_BLOCK_2_8!J9G1!8!@baseboard_fab2_lib.baseboard_fab2(sch_1):page137_i100@mstr_conn.conn12_d59987001(chips)!CONN12_D59987001_THLF-CONN,D59A!!!F2256!IO8!!!!
S!FM_UART_PRES_N!J9G1!9!@baseboard_fab2_lib.baseboard_fab2(sch_1):page137_i100@mstr_conn.conn12_d59987001(chips)!CONN12_D59987001_THLF-CONN,D59A!!!F2256!IO9!!!!
S!FM_RED_LED_CATHODE!DS9F1!2!@baseboard_fab2_lib.baseboard_fab2(sch_1):page177_i71@mstr_discrete.led(chips)!LED_A1-RED,IC,D14725-005!!!F2035!C!!!!
S!FM_RED_LED_ANODE!DS9F1!1!@baseboard_fab2_lib.baseboard_fab2(sch_1):page177_i71@mstr_discrete.led(chips)!LED_A1-RED,IC,D14725-005!!!F2035!A!!!!
S!A_HSC_LOW_EN!R1D11!1!@baseboard_fab2_lib.baseboard_fab2(sch_1):page199_i88@mstr_discrete.res(chips)!RES_0402-100.0K,1%,1/16W,CHIP,A!!!F1157!A!!!!
S!AGND_HSC!R1D11!2!@baseboard_fab2_lib.baseboard_fab2(sch_1):page199_i88@mstr_discrete.res(chips)!RES_0402-100.0K,1%,1/16W,CHIP,A!!!F1157!B!!!!
S!P12V_PSU!R1D15!1!@baseboard_fab2_lib.baseboard_fab2(sch_1):page199_i92@mstr_discrete.res(chips)!RES_0402-100.0K,1%,1/16W,CHIP,A!!!F1156!A!!!!
S!A_HSC_OCP_SEL!R1D15!2!@baseboard_fab2_lib.baseboard_fab2(sch_1):page199_i92@mstr_discrete.res(chips)!RES_0402-100.0K,1%,1/16W,CHIP,A!!!F1156!B!!!!
S!A_HSC_HIGH_EN!R1D18!1!@baseboard_fab2_lib.baseboard_fab2(sch_1):page199_i87@mstr_discrete.res(chips)!RES_0402-100.0K,1%,1/16W,CHIP,A!!!F1155!A!!!!
S!AGND_HSC!R1D18!2!@baseboard_fab2_lib.baseboard_fab2(sch_1):page199_i87@mstr_discrete.res(chips)!RES_0402-100.0K,1%,1/16W,CHIP,A!!!F1155!B!!!!
S!A_HSC_VCAP!R1D32!1!@baseboard_fab2_lib.baseboard_fab2(sch_1):page199_i17@mstr_discrete.res(chips)!RES_0402-100.0K,1%,1/16W,CHIP,A!!!F1154!A!!!!
S!A_HSC_ISTART!R1D32!2!@baseboard_fab2_lib.baseboard_fab2(sch_1):page199_i17@mstr_discrete.res(chips)!RES_0402-100.0K,1%,1/16W,CHIP,A!!!F1154!B!!!!
S!A_HSC_VCAP!R1D37!1!@baseboard_fab2_lib.baseboard_fab2(sch_1):page199_i15@mstr_discrete.res(chips)!RES_0402-100.0K,1%,1/16W,CHIP,A!!!F1153!A!!!!
S!A_HSC_ISET!R1D37!2!@baseboard_fab2_lib.baseboard_fab2(sch_1):page199_i15@mstr_discrete.res(chips)!RES_0402-100.0K,1%,1/16W,CHIP,A!!!F1153!B!!!!
S!A_HSC_VCAP!R1D39!1!@baseboard_fab2_lib.baseboard_fab2(sch_1):page199_i16@mstr_discrete.res(chips)!RES_0402-100.0K,1%,1/16W,CHIP,A!!!F1152!A!!!!
S!A_HSC_PSET!R1D39!2!@baseboard_fab2_lib.baseboard_fab2(sch_1):page199_i16@mstr_discrete.res(chips)!RES_0402-100.0K,1%,1/16W,CHIP,A!!!F1152!B!!!!
S!P12V_STBY!R1L9!1!@baseboard_fab2_lib.baseboard_fab2(sch_1):page155_i130@mstr_discrete.res(chips)!RES_0402-100.0K,1%,1/16W,CHIP,A!!!F1151!A!!!!
S!FM_CPLD_DBG_PWR_EN!R1L9!2!@baseboard_fab2_lib.baseboard_fab2(sch_1):page155_i130@mstr_discrete.res(chips)!RES_0402-100.0K,1%,1/16W,CHIP,A!!!F1151!B!!!!
S!FAN_TACH0!R1U1!1!@baseboard_fab2_lib.baseboard_fab2(sch_1):page147_i144@mstr_discrete.res(chips)!RES_0402-100.0K,1%,1/16W,CHIP,A!!!F1150!A!!!!
S!GND!R1U1!2!@baseboard_fab2_lib.baseboard_fab2(sch_1):page147_i144@mstr_discrete.res(chips)!RES_0402-100.0K,1%,1/16W,CHIP,A!!!F1150!B!!!!
S!FAN_TACH1!R1U2!1!@baseboard_fab2_lib.baseboard_fab2(sch_1):page147_i145@mstr_discrete.res(chips)!RES_0402-100.0K,1%,1/16W,CHIP,A!!!F1149!A!!!!
S!GND!R1U2!2!@baseboard_fab2_lib.baseboard_fab2(sch_1):page147_i145@mstr_discrete.res(chips)!RES_0402-100.0K,1%,1/16W,CHIP,A!!!F1149!B!!!!
S!FAN_TACH2!R1U4!1!@baseboard_fab2_lib.baseboard_fab2(sch_1):page147_i149@mstr_discrete.res(chips)!RES_0402-100.0K,1%,1/16W,CHIP,A!!!F1148!A!!!!
S!GND!R1U4!2!@baseboard_fab2_lib.baseboard_fab2(sch_1):page147_i149@mstr_discrete.res(chips)!RES_0402-100.0K,1%,1/16W,CHIP,A!!!F1148!B!!!!
S!FAN_TACH3!R1U5!1!@baseboard_fab2_lib.baseboard_fab2(sch_1):page147_i148@mstr_discrete.res(chips)!RES_0402-100.0K,1%,1/16W,CHIP,A!!!F1147!A!!!!
S!GND!R1U5!2!@baseboard_fab2_lib.baseboard_fab2(sch_1):page147_i148@mstr_discrete.res(chips)!RES_0402-100.0K,1%,1/16W,CHIP,A!!!F1147!B!!!!
S!CLK_24M_BMC_LPC!R2T15!1!@baseboard_fab2_lib.baseboard_fab2(sch_1):page144_i532@mstr_discrete.res(chips)!RES_0402-100.0K,1%,1/16W,CHIP,A!!!F1146!A!!!!
S!GND!R2T15!2!@baseboard_fab2_lib.baseboard_fab2(sch_1):page144_i532@mstr_discrete.res(chips)!RES_0402-100.0K,1%,1/16W,CHIP,A!!!F1146!B!!!!
S!P2E_SSB_BMC_RX_C_DP!R3M8!1!@baseboard_fab2_lib.baseboard_fab2(sch_1):page116_i235@mstr_discrete.res(chips)!RES_0402-100.0K,1%,1/16W,CHIP,A!!!F1145!A!!!!
S!GND!R3M8!2!@baseboard_fab2_lib.baseboard_fab2(sch_1):page116_i235@mstr_discrete.res(chips)!RES_0402-100.0K,1%,1/16W,CHIP,A!!!F1145!B!!!!
S!P2E_SSB_BMC_RX_C_DN!R3M9!1!@baseboard_fab2_lib.baseboard_fab2(sch_1):page116_i234@mstr_discrete.res(chips)!RES_0402-100.0K,1%,1/16W,CHIP,A!!!F1144!A!!!!
S!GND!R3M9!2!@baseboard_fab2_lib.baseboard_fab2(sch_1):page116_i234@mstr_discrete.res(chips)!RES_0402-100.0K,1%,1/16W,CHIP,A!!!F1144!B!!!!
S!FM_CTNR_PS_ON!R8B4!1!@baseboard_fab2_lib.baseboard_fab2(sch_1):page198_i83@mstr_discrete.res(chips)!RES_0402-100.0K,1%,1/16W,CHIP,A!!!F1143!A!!!!
S!GND!R8B4!2!@baseboard_fab2_lib.baseboard_fab2(sch_1):page198_i83@mstr_discrete.res(chips)!RES_0402-100.0K,1%,1/16W,CHIP,A!!!F1143!B!!!!
S!RST_PLTRST_BUF_N!R9F4!1!@baseboard_fab2_lib.baseboard_fab2(sch_1):page145_i208@mstr_discrete.res(chips)!RES_0402-100.0K,1%,1/16W,CHIP,A!!!F1142!A!!!!
S!GND!R9F4!2!@baseboard_fab2_lib.baseboard_fab2(sch_1):page145_i208@mstr_discrete.res(chips)!RES_0402-100.0K,1%,1/16W,CHIP,A!!!F1142!B!!!!
S!P2E_SSB_BMC_TX_C_DP!R9F42!1!@baseboard_fab2_lib.baseboard_fab2(sch_1):page145_i214@mstr_discrete.res(chips)!RES_0402-100.0K,1%,1/16W,CHIP,A!!!F1141!A!!!!
S!GND!R9F42!2!@baseboard_fab2_lib.baseboard_fab2(sch_1):page145_i214@mstr_discrete.res(chips)!RES_0402-100.0K,1%,1/16W,CHIP,A!!!F1141!B!!!!
S!P2E_SSB_BMC_TX_C_DN!R9F43!1!@baseboard_fab2_lib.baseboard_fab2(sch_1):page145_i216@mstr_discrete.res(chips)!RES_0402-100.0K,1%,1/16W,CHIP,A!!!F1140!A!!!!
S!GND!R9F43!2!@baseboard_fab2_lib.baseboard_fab2(sch_1):page145_i216@mstr_discrete.res(chips)!RES_0402-100.0K,1%,1/16W,CHIP,A!!!F1140!B!!!!
S!CLK_100M_BMC_PE_R_DN!R9F44!1!@baseboard_fab2_lib.baseboard_fab2(sch_1):page145_i211@mstr_discrete.res(chips)!RES_0402-100.0K,1%,1/16W,CHIP,A!!!F1139!A!!!!
S!GND!R9F44!2!@baseboard_fab2_lib.baseboard_fab2(sch_1):page145_i211@mstr_discrete.res(chips)!RES_0402-100.0K,1%,1/16W,CHIP,A!!!F1139!B!!!!
S!CLK_100M_BMC_PE_R_DP!R9F45!1!@baseboard_fab2_lib.baseboard_fab2(sch_1):page145_i210@mstr_discrete.res(chips)!RES_0402-100.0K,1%,1/16W,CHIP,A!!!F1138!A!!!!
S!GND!R9F45!2!@baseboard_fab2_lib.baseboard_fab2(sch_1):page145_i210@mstr_discrete.res(chips)!RES_0402-100.0K,1%,1/16W,CHIP,A!!!F1138!B!!!!
S!FM_PE_BMC_WAKE_N!R9F46!1!@baseboard_fab2_lib.baseboard_fab2(sch_1):page145_i218@mstr_discrete.res(chips)!RES_0402-100.0K,1%,1/16W,CHIP,A!!!F1137!A!!!!
S!GND!R9F46!2!@baseboard_fab2_lib.baseboard_fab2(sch_1):page145_i218@mstr_discrete.res(chips)!RES_0402-100.0K,1%,1/16W,CHIP,A!!!F1137!B!!!!
S!A_P3V_BAT_SCALED!R9G26!1!@baseboard_fab2_lib.baseboard_fab2(sch_1):page169_i106@mstr_discrete.res(chips)!RES_0402-100.0K,1%,1/16W,CHIP,A!!!F1136!A!!!!
S!GND!R9G26!2!@baseboard_fab2_lib.baseboard_fab2(sch_1):page169_i106@mstr_discrete.res(chips)!RES_0402-100.0K,1%,1/16W,CHIP,A!!!F1136!B!!!!
S!P12V_STBY!R9P23!1!@baseboard_fab2_lib.baseboard_fab2(sch_1):page199_i54@mstr_discrete.res(chips)!RES_0402-100.0K,1%,1/16W,CHIP,A!!!F1135!A!!!!
S!A_HSC_PWGIN!R9P23!2!@baseboard_fab2_lib.baseboard_fab2(sch_1):page199_i54@mstr_discrete.res(chips)!RES_0402-100.0K,1%,1/16W,CHIP,A!!!F1135!B!!!!
S!P12V_PSU!R9P28!1!@baseboard_fab2_lib.baseboard_fab2(sch_1):page199_i6@mstr_discrete.res(chips)!RES_0402-100.0K,1%,1/16W,CHIP,A!!!F1134!A!!!!
S!A_HSC_OV!R9P28!2!@baseboard_fab2_lib.baseboard_fab2(sch_1):page199_i6@mstr_discrete.res(chips)!RES_0402-100.0K,1%,1/16W,CHIP,A!!!F1134!B!!!!
S!P12V_PSU!R9P29!1!@baseboard_fab2_lib.baseboard_fab2(sch_1):page199_i12@mstr_discrete.res(chips)!RES_0402-100.0K,1%,1/16W,CHIP,A!!!F1133!A!!!!
S!A_HSC_UV!R9P29!2!@baseboard_fab2_lib.baseboard_fab2(sch_1):page199_i12@mstr_discrete.res(chips)!RES_0402-100.0K,1%,1/16W,CHIP,A!!!F1133!B!!!!
S!P12V!R8D38!1!@baseboard_fab2_lib.baseboard_fab2(sch_1):page196_i112@mstr_discrete.res(chips)!RES_0402-100.0K,1%,1/16W,CHIP,A!!!F1132!A!!!!
S!A_PG_P12V_MAIN!R8D38!2!@baseboard_fab2_lib.baseboard_fab2(sch_1):page196_i112@mstr_discrete.res(chips)!RES_0402-100.0K,1%,1/16W,CHIP,A!!!F1132!B!!!!
S!P12V_STBY!R9P33!1!@baseboard_fab2_lib.baseboard_fab2(sch_1):page200_i222@mstr_discrete.res(chips)!RES_0402-100.0K,1%,1/16W,CHIP,A!!!F1131!A!!!!
S!A_HSC_INAP!R9P33!2!@baseboard_fab2_lib.baseboard_fab2(sch_1):page200_i222@mstr_discrete.res(chips)!RES_0402-100.0K,1%,1/16W,CHIP,A!!!F1131!B!!!!
S!GND!CR1F5!2!@baseboard_fab2_lib.baseboard_fab2(sch_1):page200_i220@mstr_discrete.diode(chips)!DIODE_SM-MBRS340T3G,EMPTY,C819A!!!F2218!A!!!!
S!P12V_STBY!CR1F5!1!@baseboard_fab2_lib.baseboard_fab2(sch_1):page200_i220@mstr_discrete.diode(chips)!DIODE_SM-MBRS340T3G,EMPTY,C819A!!!F2218!C!!!!
S!VR_PVCCIO_CPU0_AIREF1!EU3P1!21!@baseboard_fab2_lib.baseboard_fab2(sch_1):page211_i93@mstr_controller.pxe1110b(chips)!PXE1110B_QFN-IC,H89187-001!!!F1976!AIREF1!!!!
S!ISENSE_PVCCIO_CPU0_PH1_IMON!EU3P1!22!@baseboard_fab2_lib.baseboard_fab2(sch_1):page211_i93@mstr_controller.pxe1110b(chips)!PXE1110B_QFN-IC,H89187-001!!!F1976!AISEN1!!!!
S!VR_PVCCIO_CPU0_PWM1!EU3P1!5!@baseboard_fab2_lib.baseboard_fab2(sch_1):page211_i93@mstr_controller.pxe1110b(chips)!PXE1110B_QFN-IC,H89187-001!!!F1976!APWM1!!!!
S!A_TSENSE_PVCCIO_CPU0!EU3P1!35!@baseboard_fab2_lib.baseboard_fab2(sch_1):page211_i93@mstr_controller.pxe1110b(chips)!PXE1110B_QFN-IC,H89187-001!!!F1976!ATSEN!!!!
S!VSENSE_PVCCIO_CPU0_AVSN!EU3P1!20!@baseboard_fab2_lib.baseboard_fab2(sch_1):page211_i93@mstr_controller.pxe1110b(chips)!PXE1110B_QFN-IC,H89187-001!!!F1976!AVREF!!!!
S!VR_PVCCIO_CPU0_AVSP!EU3P1!19!@baseboard_fab2_lib.baseboard_fab2(sch_1):page211_i93@mstr_controller.pxe1110b(chips)!PXE1110B_QFN-IC,H89187-001!!!F1976!AVSEN!!!!
S!TP_PVCCIO_CPU0_BIREF1!EU3P1!25!@baseboard_fab2_lib.baseboard_fab2(sch_1):page211_i93@mstr_controller.pxe1110b(chips)!PXE1110B_QFN-IC,H89187-001!!!F1976!BIREF1!!!!
S!GND!EU3P1!26!@baseboard_fab2_lib.baseboard_fab2(sch_1):page211_i93@mstr_controller.pxe1110b(chips)!PXE1110B_QFN-IC,H89187-001!!!F1976!BISEN1!!!!
S!TP_PVCCIO_CPU0_BPWM1!EU3P1!3!@baseboard_fab2_lib.baseboard_fab2(sch_1):page211_i93@mstr_controller.pxe1110b(chips)!PXE1110B_QFN-IC,H89187-001!!!F1976!BPWM1!!!!
S!TP_PVCCIO_CPU0_BTSEN!EU3P1!34!@baseboard_fab2_lib.baseboard_fab2(sch_1):page211_i93@mstr_controller.pxe1110b(chips)!PXE1110B_QFN-IC,H89187-001!!!F1976!BTSEN!!!!
S!TP_PVCCIO_CPU0_BVREF!EU3P1!30!@baseboard_fab2_lib.baseboard_fab2(sch_1):page211_i93@mstr_controller.pxe1110b(chips)!PXE1110B_QFN-IC,H89187-001!!!F1976!BVREF!!!!
S!TP_PVCCIO_CPU0_BVSEN!EU3P1!29!@baseboard_fab2_lib.baseboard_fab2(sch_1):page211_i93@mstr_controller.pxe1110b(chips)!PXE1110B_QFN-IC,H89187-001!!!F1976!BVSEN!!!!
S!NC_PVCCIO_CPU0_DNC0!EU3P1!1!@baseboard_fab2_lib.baseboard_fab2(sch_1):page211_i93@mstr_controller.pxe1110b(chips)!PXE1110B_QFN-IC,H89187-001!!!F1976!DNC(0)!!!!
S!NC_PVCCIO_CPU0_DNC1!EU3P1!2!@baseboard_fab2_lib.baseboard_fab2(sch_1):page211_i93@mstr_controller.pxe1110b(chips)!PXE1110B_QFN-IC,H89187-001!!!F1976!DNC(1)!!!!
S!NC_PVCCIO_CPU0_DNC2!EU3P1!4!@baseboard_fab2_lib.baseboard_fab2(sch_1):page211_i93@mstr_controller.pxe1110b(chips)!PXE1110B_QFN-IC,H89187-001!!!F1976!DNC(2)!!!!
S!NC_PVCCIO_CPU0_DNC3!EU3P1!24!@baseboard_fab2_lib.baseboard_fab2(sch_1):page211_i93@mstr_controller.pxe1110b(chips)!PXE1110B_QFN-IC,H89187-001!!!F1976!DNC(3)!!!!
S!NC_PVCCIO_CPU0_DNC4!EU3P1!28!@baseboard_fab2_lib.baseboard_fab2(sch_1):page211_i93@mstr_controller.pxe1110b(chips)!PXE1110B_QFN-IC,H89187-001!!!F1976!DNC(4)!!!!
S!PU_VR_PVCCIO_CPU0_FAULT1!EU3P1!32!@baseboard_fab2_lib.baseboard_fab2(sch_1):page211_i93@mstr_controller.pxe1110b(chips)!PXE1110B_QFN-IC,H89187-001!!!F1976!MP4!!!!
S!TP_VR_PVCCIO_CPU0_MP2!EU3P1!18!@baseboard_fab2_lib.baseboard_fab2(sch_1):page211_i93@mstr_controller.pxe1110b(chips)!PXE1110B_QFN-IC,H89187-001!!!F1976!MP2!!!!
S!GND!EU3P1!27!@baseboard_fab2_lib.baseboard_fab2(sch_1):page211_i93@mstr_controller.pxe1110b(chips)!PXE1110B_QFN-IC,H89187-001!!!F1976!GND(0)!!!!
S!GND!EU3P1!23!@baseboard_fab2_lib.baseboard_fab2(sch_1):page211_i93@mstr_controller.pxe1110b(chips)!PXE1110B_QFN-IC,H89187-001!!!F1976!GND(1)!!!!
S!TP_VR_PVCCIO_CPU0_MP3!EU3P1!31!@baseboard_fab2_lib.baseboard_fab2(sch_1):page211_i93@mstr_controller.pxe1110b(chips)!PXE1110B_QFN-IC,H89187-001!!!F1976!MP3!!!!
S!TP_VR_PVCCIO_CPU0_MP0!EU3P1!13!@baseboard_fab2_lib.baseboard_fab2(sch_1):page211_i93@mstr_controller.pxe1110b(chips)!PXE1110B_QFN-IC,H89187-001!!!F1976!MP0!!!!
S!TP_VR_PVCCIO_CPU0_MP1!EU3P1!14!@baseboard_fab2_lib.baseboard_fab2(sch_1):page211_i93@mstr_controller.pxe1110b(chips)!PXE1110B_QFN-IC,H89187-001!!!F1976!MP1!!!!
S!TP_VR_PVCCIO_CPU0_AIINSEN!EU3P1!38!@baseboard_fab2_lib.baseboard_fab2(sch_1):page211_i93@mstr_controller.pxe1110b(chips)!PXE1110B_QFN-IC,H89187-001!!!F1976!IINSEN!!!!
S!TP_PVCCIO_CPU0_PINALRT_N!EU3P1!12!@baseboard_fab2_lib.baseboard_fab2(sch_1):page211_i93@mstr_controller.pxe1110b(chips)!PXE1110B_QFN-IC,H89187-001!!!F1976!PINALRT_N!!!!
S!TP_PVCCIO_CPU0_RESET_N!EU3P1!8!@baseboard_fab2_lib.baseboard_fab2(sch_1):page211_i93@mstr_controller.pxe1110b(chips)!PXE1110B_QFN-IC,H89187-001!!!F1976!RESET_N!!!!
S!SMB_VR_SCL_PVCCIO_CPU0!EU3P1!7!@baseboard_fab2_lib.baseboard_fab2(sch_1):page211_i93@mstr_controller.pxe1110b(chips)!PXE1110B_QFN-IC,H89187-001!!!F1976!SCL!!!!
S!SMB_VR_SDA_PVCCIO_CPU0!EU3P1!6!@baseboard_fab2_lib.baseboard_fab2(sch_1):page211_i93@mstr_controller.pxe1110b(chips)!PXE1110B_QFN-IC,H89187-001!!!F1976!SDA!!!!
S!GND!EU3P1!41!@baseboard_fab2_lib.baseboard_fab2(sch_1):page211_i93@mstr_controller.pxe1110b(chips)!PXE1110B_QFN-IC,H89187-001!!!F1976!THPAD!!!!
S!SVID_ALERT_PVCCIO_CPU0!EU3P1!17!@baseboard_fab2_lib.baseboard_fab2(sch_1):page211_i93@mstr_controller.pxe1110b(chips)!PXE1110B_QFN-IC,H89187-001!!!F1976!VALRT_N!!!!
S!SVID_CLK_PVCCIO_CPU0!EU3P1!15!@baseboard_fab2_lib.baseboard_fab2(sch_1):page211_i93@mstr_controller.pxe1110b(chips)!PXE1110B_QFN-IC,H89187-001!!!F1976!VCLK!!!!
S!VR_PVCCIO_CPU0_VD12!EU3P1!40!@baseboard_fab2_lib.baseboard_fab2(sch_1):page211_i93@mstr_controller.pxe1110b(chips)!PXE1110B_QFN-IC,H89187-001!!!F1976!VD12!!!!
S!VR_PVCCIO_CPU0_VDD!EU3P1!39!@baseboard_fab2_lib.baseboard_fab2(sch_1):page211_i93@mstr_controller.pxe1110b(chips)!PXE1110B_QFN-IC,H89187-001!!!F1976!VDD!!!!
S!SVID_VDIO_PVCCIO_CPU0!EU3P1!16!@baseboard_fab2_lib.baseboard_fab2(sch_1):page211_i93@mstr_controller.pxe1110b(chips)!PXE1110B_QFN-IC,H89187-001!!!F1976!VDIO!!!!
S!VR_PVCCIO_CPU0_VINSEN!EU3P1!37!@baseboard_fab2_lib.baseboard_fab2(sch_1):page211_i93@mstr_controller.pxe1110b(chips)!PXE1110B_QFN-IC,H89187-001!!!F1976!VINSEN!!!!
S!VR_PVCCIO_CPU0_EN!EU3P1!10!@baseboard_fab2_lib.baseboard_fab2(sch_1):page211_i93@mstr_controller.pxe1110b(chips)!PXE1110B_QFN-IC,H89187-001!!!F1976!AVREN!!!!
S!IRQ_PVCCIO_CPU0_VRHOT_N!EU3P1!11!@baseboard_fab2_lib.baseboard_fab2(sch_1):page211_i93@mstr_controller.pxe1110b(chips)!PXE1110B_QFN-IC,H89187-001!!!F1976!VRHOT_N!!!!
S!PWRGD_PVCCIO_CPU0_R!EU3P1!9!@baseboard_fab2_lib.baseboard_fab2(sch_1):page211_i93@mstr_controller.pxe1110b(chips)!PXE1110B_QFN-IC,H89187-001!!!F1976!AVRRDY!!!!
S!VR_PVCCIO_CPU0_XADDR1!EU3P1!36!@baseboard_fab2_lib.baseboard_fab2(sch_1):page211_i93@mstr_controller.pxe1110b(chips)!PXE1110B_QFN-IC,H89187-001!!!F1976!XADDR1!!!!
S!VR_PVCCIO_CPU0_XADDR2!EU3P1!33!@baseboard_fab2_lib.baseboard_fab2(sch_1):page211_i93@mstr_controller.pxe1110b(chips)!PXE1110B_QFN-IC,H89187-001!!!F1976!XADDR2!!!!
S!VR_PVCCIO_CPU1_AIREF1!EU4D5!21!@baseboard_fab2_lib.baseboard_fab2(sch_1):page213_i96@mstr_controller.pxe1110b(chips)!PXE1110B_QFN-IC,H89187-001!!!F1975!AIREF1!!!!
S!ISENSE_PVCCIO_CPU1_PH1_IMON!EU4D5!22!@baseboard_fab2_lib.baseboard_fab2(sch_1):page213_i96@mstr_controller.pxe1110b(chips)!PXE1110B_QFN-IC,H89187-001!!!F1975!AISEN1!!!!
S!VR_PVCCIO_CPU1_PWM1!EU4D5!5!@baseboard_fab2_lib.baseboard_fab2(sch_1):page213_i96@mstr_controller.pxe1110b(chips)!PXE1110B_QFN-IC,H89187-001!!!F1975!APWM1!!!!
S!A_TSENSE_PVCCIO_CPU1!EU4D5!35!@baseboard_fab2_lib.baseboard_fab2(sch_1):page213_i96@mstr_controller.pxe1110b(chips)!PXE1110B_QFN-IC,H89187-001!!!F1975!ATSEN!!!!
S!VSENSE_PVCCIO_CPU1_AVSN!EU4D5!20!@baseboard_fab2_lib.baseboard_fab2(sch_1):page213_i96@mstr_controller.pxe1110b(chips)!PXE1110B_QFN-IC,H89187-001!!!F1975!AVREF!!!!
S!VR_PVCCIO_CPU1_AVSP!EU4D5!19!@baseboard_fab2_lib.baseboard_fab2(sch_1):page213_i96@mstr_controller.pxe1110b(chips)!PXE1110B_QFN-IC,H89187-001!!!F1975!AVSEN!!!!
S!TP_PVCCIO_CPU1_BIREF1!EU4D5!25!@baseboard_fab2_lib.baseboard_fab2(sch_1):page213_i96@mstr_controller.pxe1110b(chips)!PXE1110B_QFN-IC,H89187-001!!!F1975!BIREF1!!!!
S!GND!EU4D5!26!@baseboard_fab2_lib.baseboard_fab2(sch_1):page213_i96@mstr_controller.pxe1110b(chips)!PXE1110B_QFN-IC,H89187-001!!!F1975!BISEN1!!!!
S!TP_PVCCIO_CPU1_BPWM1!EU4D5!3!@baseboard_fab2_lib.baseboard_fab2(sch_1):page213_i96@mstr_controller.pxe1110b(chips)!PXE1110B_QFN-IC,H89187-001!!!F1975!BPWM1!!!!
S!TP_PVCCIO_CPU1_BTSEN!EU4D5!34!@baseboard_fab2_lib.baseboard_fab2(sch_1):page213_i96@mstr_controller.pxe1110b(chips)!PXE1110B_QFN-IC,H89187-001!!!F1975!BTSEN!!!!
S!TP_PVCCIO_CPU1_BVREF!EU4D5!30!@baseboard_fab2_lib.baseboard_fab2(sch_1):page213_i96@mstr_controller.pxe1110b(chips)!PXE1110B_QFN-IC,H89187-001!!!F1975!BVREF!!!!
S!TP_PVCCIO_CPU1_BVSEN!EU4D5!29!@baseboard_fab2_lib.baseboard_fab2(sch_1):page213_i96@mstr_controller.pxe1110b(chips)!PXE1110B_QFN-IC,H89187-001!!!F1975!BVSEN!!!!
S!NC_PVCCIO_CPU1_DNC0!EU4D5!1!@baseboard_fab2_lib.baseboard_fab2(sch_1):page213_i96@mstr_controller.pxe1110b(chips)!PXE1110B_QFN-IC,H89187-001!!!F1975!DNC(0)!!!!
S!NC_PVCCIO_CPU1_DNC1!EU4D5!2!@baseboard_fab2_lib.baseboard_fab2(sch_1):page213_i96@mstr_controller.pxe1110b(chips)!PXE1110B_QFN-IC,H89187-001!!!F1975!DNC(1)!!!!
S!NC_PVCCIO_CPU1_DNC2!EU4D5!4!@baseboard_fab2_lib.baseboard_fab2(sch_1):page213_i96@mstr_controller.pxe1110b(chips)!PXE1110B_QFN-IC,H89187-001!!!F1975!DNC(2)!!!!
S!NC_PVCCIO_CPU1_DNC3!EU4D5!24!@baseboard_fab2_lib.baseboard_fab2(sch_1):page213_i96@mstr_controller.pxe1110b(chips)!PXE1110B_QFN-IC,H89187-001!!!F1975!DNC(3)!!!!
S!NC_PVCCIO_CPU1_DNC4!EU4D5!28!@baseboard_fab2_lib.baseboard_fab2(sch_1):page213_i96@mstr_controller.pxe1110b(chips)!PXE1110B_QFN-IC,H89187-001!!!F1975!DNC(4)!!!!
S!PU_VR_PVCCIO_CPU1_FAULT1!EU4D5!32!@baseboard_fab2_lib.baseboard_fab2(sch_1):page213_i96@mstr_controller.pxe1110b(chips)!PXE1110B_QFN-IC,H89187-001!!!F1975!MP4!!!!
S!TP_VR_PVCCIO_CPU1_MP2!EU4D5!18!@baseboard_fab2_lib.baseboard_fab2(sch_1):page213_i96@mstr_controller.pxe1110b(chips)!PXE1110B_QFN-IC,H89187-001!!!F1975!MP2!!!!
S!GND!EU4D5!27!@baseboard_fab2_lib.baseboard_fab2(sch_1):page213_i96@mstr_controller.pxe1110b(chips)!PXE1110B_QFN-IC,H89187-001!!!F1975!GND(0)!!!!
S!GND!EU4D5!23!@baseboard_fab2_lib.baseboard_fab2(sch_1):page213_i96@mstr_controller.pxe1110b(chips)!PXE1110B_QFN-IC,H89187-001!!!F1975!GND(1)!!!!
S!TP_VR_PVCCIO_CPU1_MP3!EU4D5!31!@baseboard_fab2_lib.baseboard_fab2(sch_1):page213_i96@mstr_controller.pxe1110b(chips)!PXE1110B_QFN-IC,H89187-001!!!F1975!MP3!!!!
S!TP_VR_PVCCIO_CPU1_MP0!EU4D5!13!@baseboard_fab2_lib.baseboard_fab2(sch_1):page213_i96@mstr_controller.pxe1110b(chips)!PXE1110B_QFN-IC,H89187-001!!!F1975!MP0!!!!
S!TP_VR_PVCCIO_CPU1_MP1!EU4D5!14!@baseboard_fab2_lib.baseboard_fab2(sch_1):page213_i96@mstr_controller.pxe1110b(chips)!PXE1110B_QFN-IC,H89187-001!!!F1975!MP1!!!!
S!TP_VR_PVCCIO_CPU1_AIINSEN!EU4D5!38!@baseboard_fab2_lib.baseboard_fab2(sch_1):page213_i96@mstr_controller.pxe1110b(chips)!PXE1110B_QFN-IC,H89187-001!!!F1975!IINSEN!!!!
S!TP_PVCCIO_CPU1_PINALRT_N!EU4D5!12!@baseboard_fab2_lib.baseboard_fab2(sch_1):page213_i96@mstr_controller.pxe1110b(chips)!PXE1110B_QFN-IC,H89187-001!!!F1975!PINALRT_N!!!!
S!TP_PVCCIO_CPU1_RESET_N!EU4D5!8!@baseboard_fab2_lib.baseboard_fab2(sch_1):page213_i96@mstr_controller.pxe1110b(chips)!PXE1110B_QFN-IC,H89187-001!!!F1975!RESET_N!!!!
S!SMB_VR_SCL_PVCCIO_CPU1!EU4D5!7!@baseboard_fab2_lib.baseboard_fab2(sch_1):page213_i96@mstr_controller.pxe1110b(chips)!PXE1110B_QFN-IC,H89187-001!!!F1975!SCL!!!!
S!SMB_VR_SDA_PVCCIO_CPU1!EU4D5!6!@baseboard_fab2_lib.baseboard_fab2(sch_1):page213_i96@mstr_controller.pxe1110b(chips)!PXE1110B_QFN-IC,H89187-001!!!F1975!SDA!!!!
S!GND!EU4D5!41!@baseboard_fab2_lib.baseboard_fab2(sch_1):page213_i96@mstr_controller.pxe1110b(chips)!PXE1110B_QFN-IC,H89187-001!!!F1975!THPAD!!!!
S!SVID_ALERT_PVCCIO_CPU1!EU4D5!17!@baseboard_fab2_lib.baseboard_fab2(sch_1):page213_i96@mstr_controller.pxe1110b(chips)!PXE1110B_QFN-IC,H89187-001!!!F1975!VALRT_N!!!!
S!SVID_CLK_PVCCIO_CPU1!EU4D5!15!@baseboard_fab2_lib.baseboard_fab2(sch_1):page213_i96@mstr_controller.pxe1110b(chips)!PXE1110B_QFN-IC,H89187-001!!!F1975!VCLK!!!!
S!VR_PVCCIO_CPU1_VD12!EU4D5!40!@baseboard_fab2_lib.baseboard_fab2(sch_1):page213_i96@mstr_controller.pxe1110b(chips)!PXE1110B_QFN-IC,H89187-001!!!F1975!VD12!!!!
S!VR_PVCCIO_CPU1_VDD!EU4D5!39!@baseboard_fab2_lib.baseboard_fab2(sch_1):page213_i96@mstr_controller.pxe1110b(chips)!PXE1110B_QFN-IC,H89187-001!!!F1975!VDD!!!!
S!SVID_VDIO_PVCCIO_CPU1!EU4D5!16!@baseboard_fab2_lib.baseboard_fab2(sch_1):page213_i96@mstr_controller.pxe1110b(chips)!PXE1110B_QFN-IC,H89187-001!!!F1975!VDIO!!!!
S!VR_PVCCIO_CPU1_VINSEN!EU4D5!37!@baseboard_fab2_lib.baseboard_fab2(sch_1):page213_i96@mstr_controller.pxe1110b(chips)!PXE1110B_QFN-IC,H89187-001!!!F1975!VINSEN!!!!
S!VR_PVCCIO_CPU1_EN!EU4D5!10!@baseboard_fab2_lib.baseboard_fab2(sch_1):page213_i96@mstr_controller.pxe1110b(chips)!PXE1110B_QFN-IC,H89187-001!!!F1975!AVREN!!!!
S!IRQ_PVCCIO_CPU1_VRHOT_N!EU4D5!11!@baseboard_fab2_lib.baseboard_fab2(sch_1):page213_i96@mstr_controller.pxe1110b(chips)!PXE1110B_QFN-IC,H89187-001!!!F1975!VRHOT_N!!!!
S!PWRGD_PVCCIO_CPU1_R!EU4D5!9!@baseboard_fab2_lib.baseboard_fab2(sch_1):page213_i96@mstr_controller.pxe1110b(chips)!PXE1110B_QFN-IC,H89187-001!!!F1975!AVRRDY!!!!
S!VR_PVCCIO_CPU1_XADDR1!EU4D5!36!@baseboard_fab2_lib.baseboard_fab2(sch_1):page213_i96@mstr_controller.pxe1110b(chips)!PXE1110B_QFN-IC,H89187-001!!!F1975!XADDR1!!!!
S!VR_PVCCIO_CPU1_XADDR2!EU4D5!33!@baseboard_fab2_lib.baseboard_fab2(sch_1):page213_i96@mstr_controller.pxe1110b(chips)!PXE1110B_QFN-IC,H89187-001!!!F1975!XADDR2!!!!
S!VR_PVNN_PCH_AIREF1!EU8A1!21!@baseboard_fab2_lib.baseboard_fab2(sch_1):page235_i229@mstr_controller.pxe1110b(chips)!PXE1110B_QFN-IC,H89187-001!!!F1974!AIREF1!!!!
S!ISENSE_PVNN_PCH_PH1_IMON!EU8A1!22!@baseboard_fab2_lib.baseboard_fab2(sch_1):page235_i229@mstr_controller.pxe1110b(chips)!PXE1110B_QFN-IC,H89187-001!!!F1974!AISEN1!!!!
S!VR_PVNN_PCH_PWM1!EU8A1!5!@baseboard_fab2_lib.baseboard_fab2(sch_1):page235_i229@mstr_controller.pxe1110b(chips)!PXE1110B_QFN-IC,H89187-001!!!F1974!APWM1!!!!
S!A_TSENSE_PVNN_PCH_TMON!EU8A1!35!@baseboard_fab2_lib.baseboard_fab2(sch_1):page235_i229@mstr_controller.pxe1110b(chips)!PXE1110B_QFN-IC,H89187-001!!!F1974!ATSEN!!!!
S!VSENSE_PVNN_PCH_STBY_AVSN!EU8A1!20!@baseboard_fab2_lib.baseboard_fab2(sch_1):page235_i229@mstr_controller.pxe1110b(chips)!PXE1110B_QFN-IC,H89187-001!!!F1974!AVREF!!!!
S!VR_PVNN_PCH_AVSP!EU8A1!19!@baseboard_fab2_lib.baseboard_fab2(sch_1):page235_i229@mstr_controller.pxe1110b(chips)!PXE1110B_QFN-IC,H89187-001!!!F1974!AVSEN!!!!
S!VR_P1V05_PCH_BIREF1!EU8A1!25!@baseboard_fab2_lib.baseboard_fab2(sch_1):page235_i229@mstr_controller.pxe1110b(chips)!PXE1110B_QFN-IC,H89187-001!!!F1974!BIREF1!!!!
S!ISENSE_P1V05_PCH_STBY_PH1_IMON!EU8A1!26!@baseboard_fab2_lib.baseboard_fab2(sch_1):page235_i229@mstr_controller.pxe1110b(chips)!PXE1110B_QFN-IC,H89187-001!!!F1974!BISEN1!!!!
S!VR_P1V05_PCH_STBY_PWM1!EU8A1!3!@baseboard_fab2_lib.baseboard_fab2(sch_1):page235_i229@mstr_controller.pxe1110b(chips)!PXE1110B_QFN-IC,H89187-001!!!F1974!BPWM1!!!!
S!A_TSENSE_P1V05_PCH_STBY_TMON!EU8A1!34!@baseboard_fab2_lib.baseboard_fab2(sch_1):page235_i229@mstr_controller.pxe1110b(chips)!PXE1110B_QFN-IC,H89187-001!!!F1974!BTSEN!!!!
S!VSENSE_P1V05_PCH_STBY_AVSN!EU8A1!30!@baseboard_fab2_lib.baseboard_fab2(sch_1):page235_i229@mstr_controller.pxe1110b(chips)!PXE1110B_QFN-IC,H89187-001!!!F1974!BVREF!!!!
S!VR_P1V05_PCH_STBY_AVSP!EU8A1!29!@baseboard_fab2_lib.baseboard_fab2(sch_1):page235_i229@mstr_controller.pxe1110b(chips)!PXE1110B_QFN-IC,H89187-001!!!F1974!BVSEN!!!!
S!NC_PVNN_PCH_DNC0!EU8A1!1!@baseboard_fab2_lib.baseboard_fab2(sch_1):page235_i229@mstr_controller.pxe1110b(chips)!PXE1110B_QFN-IC,H89187-001!!!F1974!DNC(0)!!!!
S!NC_PVNN_PCH_DNC1!EU8A1!2!@baseboard_fab2_lib.baseboard_fab2(sch_1):page235_i229@mstr_controller.pxe1110b(chips)!PXE1110B_QFN-IC,H89187-001!!!F1974!DNC(1)!!!!
S!NC_PVNN_PCH_DNC2!EU8A1!4!@baseboard_fab2_lib.baseboard_fab2(sch_1):page235_i229@mstr_controller.pxe1110b(chips)!PXE1110B_QFN-IC,H89187-001!!!F1974!DNC(2)!!!!
S!NC_PVNN_PCH_DNC3!EU8A1!24!@baseboard_fab2_lib.baseboard_fab2(sch_1):page235_i229@mstr_controller.pxe1110b(chips)!PXE1110B_QFN-IC,H89187-001!!!F1974!DNC(3)!!!!
S!NC_PVNN_PCH_DNC4!EU8A1!28!@baseboard_fab2_lib.baseboard_fab2(sch_1):page235_i229@mstr_controller.pxe1110b(chips)!PXE1110B_QFN-IC,H89187-001!!!F1974!DNC(4)!!!!
S!PU_VR_PVNN_PCH_FAULT1!EU8A1!32!@baseboard_fab2_lib.baseboard_fab2(sch_1):page235_i229@mstr_controller.pxe1110b(chips)!PXE1110B_QFN-IC,H89187-001!!!F1974!MP4!!!!
S!TP_PVNN_PCH_MP2!EU8A1!18!@baseboard_fab2_lib.baseboard_fab2(sch_1):page235_i229@mstr_controller.pxe1110b(chips)!PXE1110B_QFN-IC,H89187-001!!!F1974!MP2!!!!
S!GND!EU8A1!27!@baseboard_fab2_lib.baseboard_fab2(sch_1):page235_i229@mstr_controller.pxe1110b(chips)!PXE1110B_QFN-IC,H89187-001!!!F1974!GND(0)!!!!
S!GND!EU8A1!23!@baseboard_fab2_lib.baseboard_fab2(sch_1):page235_i229@mstr_controller.pxe1110b(chips)!PXE1110B_QFN-IC,H89187-001!!!F1974!GND(1)!!!!
S!TP_PVNN_PCH_MP3!EU8A1!31!@baseboard_fab2_lib.baseboard_fab2(sch_1):page235_i229@mstr_controller.pxe1110b(chips)!PXE1110B_QFN-IC,H89187-001!!!F1974!MP3!!!!
S!VID_PCH_CORE_PVNN_AUX_VID_0!EU8A1!13!@baseboard_fab2_lib.baseboard_fab2(sch_1):page235_i229@mstr_controller.pxe1110b(chips)!PXE1110B_QFN-IC,H89187-001!!!F1974!MP0!!!!
S!VID_PCH_CORE_PVNN_AUX_VID_1!EU8A1!14!@baseboard_fab2_lib.baseboard_fab2(sch_1):page235_i229@mstr_controller.pxe1110b(chips)!PXE1110B_QFN-IC,H89187-001!!!F1974!MP1!!!!
S!TP_VR_PVNN_PCH_AIINSEN!EU8A1!38!@baseboard_fab2_lib.baseboard_fab2(sch_1):page235_i229@mstr_controller.pxe1110b(chips)!PXE1110B_QFN-IC,H89187-001!!!F1974!IINSEN!!!!
S!TP_PVNN_PCH_PINALRT_N!EU8A1!12!@baseboard_fab2_lib.baseboard_fab2(sch_1):page235_i229@mstr_controller.pxe1110b(chips)!PXE1110B_QFN-IC,H89187-001!!!F1974!PINALRT_N!!!!
S!TP_PVNN_PCH_RESET_N!EU8A1!8!@baseboard_fab2_lib.baseboard_fab2(sch_1):page235_i229@mstr_controller.pxe1110b(chips)!PXE1110B_QFN-IC,H89187-001!!!F1974!RESET_N!!!!
S!SMB_VR_SCL_PVNN_PCH!EU8A1!7!@baseboard_fab2_lib.baseboard_fab2(sch_1):page235_i229@mstr_controller.pxe1110b(chips)!PXE1110B_QFN-IC,H89187-001!!!F1974!SCL!!!!
S!SMB_VR_SDA_PVNN_PCH!EU8A1!6!@baseboard_fab2_lib.baseboard_fab2(sch_1):page235_i229@mstr_controller.pxe1110b(chips)!PXE1110B_QFN-IC,H89187-001!!!F1974!SDA!!!!
S!GND!EU8A1!41!@baseboard_fab2_lib.baseboard_fab2(sch_1):page235_i229@mstr_controller.pxe1110b(chips)!PXE1110B_QFN-IC,H89187-001!!!F1974!THPAD!!!!
S!TP_PVNN_PCH_SVID_ALERT!EU8A1!17!@baseboard_fab2_lib.baseboard_fab2(sch_1):page235_i229@mstr_controller.pxe1110b(chips)!PXE1110B_QFN-IC,H89187-001!!!F1974!VALRT_N!!!!
S!TP_PVNN_PCH_VCLK!EU8A1!15!@baseboard_fab2_lib.baseboard_fab2(sch_1):page235_i229@mstr_controller.pxe1110b(chips)!PXE1110B_QFN-IC,H89187-001!!!F1974!VCLK!!!!
S!VR_PVNN_P1V05_PCH_VD12!EU8A1!40!@baseboard_fab2_lib.baseboard_fab2(sch_1):page235_i229@mstr_controller.pxe1110b(chips)!PXE1110B_QFN-IC,H89187-001!!!F1974!VD12!!!!
S!VR_PVNN_PCH_VDD!EU8A1!39!@baseboard_fab2_lib.baseboard_fab2(sch_1):page235_i229@mstr_controller.pxe1110b(chips)!PXE1110B_QFN-IC,H89187-001!!!F1974!VDD!!!!
S!TP_PVNN_PCH_VDIO!EU8A1!16!@baseboard_fab2_lib.baseboard_fab2(sch_1):page235_i229@mstr_controller.pxe1110b(chips)!PXE1110B_QFN-IC,H89187-001!!!F1974!VDIO!!!!
S!VR_PVNN_PCH_VINSEN!EU8A1!37!@baseboard_fab2_lib.baseboard_fab2(sch_1):page235_i229@mstr_controller.pxe1110b(chips)!PXE1110B_QFN-IC,H89187-001!!!F1974!VINSEN!!!!
S!VR_PVNN_PCH_VREN!EU8A1!10!@baseboard_fab2_lib.baseboard_fab2(sch_1):page235_i229@mstr_controller.pxe1110b(chips)!PXE1110B_QFN-IC,H89187-001!!!F1974!AVREN!!!!
S!IRQ_PVNN_PCH_VRHOT_N!EU8A1!11!@baseboard_fab2_lib.baseboard_fab2(sch_1):page235_i229@mstr_controller.pxe1110b(chips)!PXE1110B_QFN-IC,H89187-001!!!F1974!VRHOT_N!!!!
S!PWRGD_PVNN_PCH_R!EU8A1!9!@baseboard_fab2_lib.baseboard_fab2(sch_1):page235_i229@mstr_controller.pxe1110b(chips)!PXE1110B_QFN-IC,H89187-001!!!F1974!AVRRDY!!!!
S!VR_PVNN_PCH_XADDR1!EU8A1!36!@baseboard_fab2_lib.baseboard_fab2(sch_1):page235_i229@mstr_controller.pxe1110b(chips)!PXE1110B_QFN-IC,H89187-001!!!F1974!XADDR1!!!!
S!VR_PVNN_PCH_XADDR2!EU8A1!33!@baseboard_fab2_lib.baseboard_fab2(sch_1):page235_i229@mstr_controller.pxe1110b(chips)!PXE1110B_QFN-IC,H89187-001!!!F1974!XADDR2!!!!
S!VR_PVDDQ_KLM_AIREF1!EU1B1!21!@baseboard_fab2_lib.baseboard_fab2(sch_1):page226_i90@mstr_controller.pxm1310b(chips)!PXM1310B_QFN-IC,H89186-001!!!F1971!AIREF1!!!!
S!VR_PVDDQ_KLM_AIREF2!EU1B1!23!@baseboard_fab2_lib.baseboard_fab2(sch_1):page226_i90@mstr_controller.pxm1310b(chips)!PXM1310B_QFN-IC,H89186-001!!!F1971!AIREF2!!!!
S!TP_PVDDQ_KLM_PH3_IMON_REF!EU1B1!25!@baseboard_fab2_lib.baseboard_fab2(sch_1):page226_i90@mstr_controller.pxm1310b(chips)!PXM1310B_QFN-IC,H89186-001!!!F1971!AIREF3!!!!
S!ISENSE_PVDDQ_KLM_PH1_IMON!EU1B1!22!@baseboard_fab2_lib.baseboard_fab2(sch_1):page226_i90@mstr_controller.pxm1310b(chips)!PXM1310B_QFN-IC,H89186-001!!!F1971!AISEN1!!!!
S!ISENSE_PVDDQ_KLM_PH2_IMON!EU1B1!24!@baseboard_fab2_lib.baseboard_fab2(sch_1):page226_i90@mstr_controller.pxm1310b(chips)!PXM1310B_QFN-IC,H89186-001!!!F1971!AISEN2!!!!
S!TP_PVDDQ_KLM_PH3_IMON!EU1B1!26!@baseboard_fab2_lib.baseboard_fab2(sch_1):page226_i90@mstr_controller.pxm1310b(chips)!PXM1310B_QFN-IC,H89186-001!!!F1971!AISEN3!!!!
S!VR_PVDDQ_KLM_PWM1!EU1B1!5!@baseboard_fab2_lib.baseboard_fab2(sch_1):page226_i90@mstr_controller.pxm1310b(chips)!PXM1310B_QFN-IC,H89186-001!!!F1971!APWM1!!!!
S!VR_PVDDQ_KLM_PWM2!EU1B1!4!@baseboard_fab2_lib.baseboard_fab2(sch_1):page226_i90@mstr_controller.pxm1310b(chips)!PXM1310B_QFN-IC,H89186-001!!!F1971!APWM2!!!!
S!NC_PVDDQ_KLM_PWM3!EU1B1!3!@baseboard_fab2_lib.baseboard_fab2(sch_1):page226_i90@mstr_controller.pxm1310b(chips)!PXM1310B_QFN-IC,H89186-001!!!F1971!APWM3!!!!
S!A_TSENSE_PVDDQ_KLM!EU1B1!35!@baseboard_fab2_lib.baseboard_fab2(sch_1):page226_i90@mstr_controller.pxm1310b(chips)!PXM1310B_QFN-IC,H89186-001!!!F1971!ATSEN!!!!
S!VSENSE_PVDDQ_KLM_N!EU1B1!20!@baseboard_fab2_lib.baseboard_fab2(sch_1):page226_i90@mstr_controller.pxm1310b(chips)!PXM1310B_QFN-IC,H89186-001!!!F1971!AVREF!!!!
S!VR_PVDDQ_KLM_AVSP!EU1B1!19!@baseboard_fab2_lib.baseboard_fab2(sch_1):page226_i90@mstr_controller.pxm1310b(chips)!PXM1310B_QFN-IC,H89186-001!!!F1971!AVSEN!!!!
S!TP_PVDDQ_KLM_BREF1!EU1B1!31!@baseboard_fab2_lib.baseboard_fab2(sch_1):page226_i90@mstr_controller.pxm1310b(chips)!PXM1310B_QFN-IC,H89186-001!!!F1971!BIREF1!!!!
S!GND!EU1B1!32!@baseboard_fab2_lib.baseboard_fab2(sch_1):page226_i90@mstr_controller.pxm1310b(chips)!PXM1310B_QFN-IC,H89186-001!!!F1971!BISEN1!!!!
S!TP_PVDDQ_KLM_BPWM1!EU1B1!1!@baseboard_fab2_lib.baseboard_fab2(sch_1):page226_i90@mstr_controller.pxm1310b(chips)!PXM1310B_QFN-IC,H89186-001!!!F1971!BPWM1!!!!
S!TP_PVDDQ_KLM_BTSEN!EU1B1!34!@baseboard_fab2_lib.baseboard_fab2(sch_1):page226_i90@mstr_controller.pxm1310b(chips)!PXM1310B_QFN-IC,H89186-001!!!F1971!BTSEN!!!!
S!TP_PVDDQ_KLM_BVREF!EU1B1!30!@baseboard_fab2_lib.baseboard_fab2(sch_1):page226_i90@mstr_controller.pxm1310b(chips)!PXM1310B_QFN-IC,H89186-001!!!F1971!BVREF!!!!
S!TP_PVDDQ_KLM_BVSEN!EU1B1!29!@baseboard_fab2_lib.baseboard_fab2(sch_1):page226_i90@mstr_controller.pxm1310b(chips)!PXM1310B_QFN-IC,H89186-001!!!F1971!BVSEN!!!!
S!NC_PVDDQ_KLM_DNC0!EU1B1!2!@baseboard_fab2_lib.baseboard_fab2(sch_1):page226_i90@mstr_controller.pxm1310b(chips)!PXM1310B_QFN-IC,H89186-001!!!F1971!DNC(0)!!!!
S!NC_PVDDQ_KLM_DNC1!EU1B1!28!@baseboard_fab2_lib.baseboard_fab2(sch_1):page226_i90@mstr_controller.pxm1310b(chips)!PXM1310B_QFN-IC,H89186-001!!!F1971!DNC(1)!!!!
S!NC_PVDDQ_KLM_GP0!EU1B1!18!@baseboard_fab2_lib.baseboard_fab2(sch_1):page226_i90@mstr_controller.pxm1310b(chips)!PXM1310B_QFN-IC,H89186-001!!!F1971!MP2!!!!
S!GND!EU1B1!27!@baseboard_fab2_lib.baseboard_fab2(sch_1):page226_i90@mstr_controller.pxm1310b(chips)!PXM1310B_QFN-IC,H89186-001!!!F1971!GND!!!!
S!PU_VR_PVDDQ_KLM_FAULT1!EU1B1!13!@baseboard_fab2_lib.baseboard_fab2(sch_1):page226_i90@mstr_controller.pxm1310b(chips)!PXM1310B_QFN-IC,H89186-001!!!F1971!MP0!!!!
S!NC_PVDDQ_KLM_GP1!EU1B1!14!@baseboard_fab2_lib.baseboard_fab2(sch_1):page226_i90@mstr_controller.pxm1310b(chips)!PXM1310B_QFN-IC,H89186-001!!!F1971!MP1!!!!
S!VR_PVDDQ_KLM_AIINSEN!EU1B1!38!@baseboard_fab2_lib.baseboard_fab2(sch_1):page226_i90@mstr_controller.pxm1310b(chips)!PXM1310B_QFN-IC,H89186-001!!!F1971!IINSEN!!!!
S!NC_PVDDQ_KLM_PINALRT_N!EU1B1!12!@baseboard_fab2_lib.baseboard_fab2(sch_1):page226_i90@mstr_controller.pxm1310b(chips)!PXM1310B_QFN-IC,H89186-001!!!F1971!PINALRT_N!!!!
S!TP_PVDDQ_KLM_RESET_N!EU1B1!8!@baseboard_fab2_lib.baseboard_fab2(sch_1):page226_i90@mstr_controller.pxm1310b(chips)!PXM1310B_QFN-IC,H89186-001!!!F1971!RESET_N!!!!
S!SMB_VR_SCL_VDDQ_KLM!EU1B1!7!@baseboard_fab2_lib.baseboard_fab2(sch_1):page226_i90@mstr_controller.pxm1310b(chips)!PXM1310B_QFN-IC,H89186-001!!!F1971!SCL!!!!
S!SMB_VR_SDA_VDDQ_KLM!EU1B1!6!@baseboard_fab2_lib.baseboard_fab2(sch_1):page226_i90@mstr_controller.pxm1310b(chips)!PXM1310B_QFN-IC,H89186-001!!!F1971!SDA!!!!
S!GND!EU1B1!41!@baseboard_fab2_lib.baseboard_fab2(sch_1):page226_i90@mstr_controller.pxm1310b(chips)!PXM1310B_QFN-IC,H89186-001!!!F1971!THPAD!!!!
S!SVID_ALERT_PVDDQ_KLM!EU1B1!17!@baseboard_fab2_lib.baseboard_fab2(sch_1):page226_i90@mstr_controller.pxm1310b(chips)!PXM1310B_QFN-IC,H89186-001!!!F1971!VALRT_N!!!!
S!SVID_CLK_PVDDQ_KLM!EU1B1!15!@baseboard_fab2_lib.baseboard_fab2(sch_1):page226_i90@mstr_controller.pxm1310b(chips)!PXM1310B_QFN-IC,H89186-001!!!F1971!VCLK!!!!
S!VR_PVDDQ_KLM_VD12!EU1B1!40!@baseboard_fab2_lib.baseboard_fab2(sch_1):page226_i90@mstr_controller.pxm1310b(chips)!PXM1310B_QFN-IC,H89186-001!!!F1971!VD12!!!!
S!VR_PVDDQ_KLM_VDD!EU1B1!39!@baseboard_fab2_lib.baseboard_fab2(sch_1):page226_i90@mstr_controller.pxm1310b(chips)!PXM1310B_QFN-IC,H89186-001!!!F1971!VDD!!!!
S!SVID_VDIO_PVDDQ_KLM!EU1B1!16!@baseboard_fab2_lib.baseboard_fab2(sch_1):page226_i90@mstr_controller.pxm1310b(chips)!PXM1310B_QFN-IC,H89186-001!!!F1971!VDIO!!!!
S!VR_PVDDQ_KLM_VINSEN!EU1B1!37!@baseboard_fab2_lib.baseboard_fab2(sch_1):page226_i90@mstr_controller.pxm1310b(chips)!PXM1310B_QFN-IC,H89186-001!!!F1971!VINSEN!!!!
S!VR_PVDDQ_KLM_VREN!EU1B1!10!@baseboard_fab2_lib.baseboard_fab2(sch_1):page226_i90@mstr_controller.pxm1310b(chips)!PXM1310B_QFN-IC,H89186-001!!!F1971!AVREN!!!!
S!IRQ_PVDDQ_KLM_VRHOT_LVT3_R_N!EU1B1!11!@baseboard_fab2_lib.baseboard_fab2(sch_1):page226_i90@mstr_controller.pxm1310b(chips)!PXM1310B_QFN-IC,H89186-001!!!F1971!VRHOT_N!!!!
S!PWRGD_PVDDQ_KLM_R!EU1B1!9!@baseboard_fab2_lib.baseboard_fab2(sch_1):page226_i90@mstr_controller.pxm1310b(chips)!PXM1310B_QFN-IC,H89186-001!!!F1971!AVRRDY!!!!
S!VR_PVDDQ_KLM_XADDR1!EU1B1!36!@baseboard_fab2_lib.baseboard_fab2(sch_1):page226_i90@mstr_controller.pxm1310b(chips)!PXM1310B_QFN-IC,H89186-001!!!F1971!XADDR1!!!!
S!VR_PVDDQ_KLM_XADDR2!EU1B1!33!@baseboard_fab2_lib.baseboard_fab2(sch_1):page226_i90@mstr_controller.pxm1310b(chips)!PXM1310B_QFN-IC,H89186-001!!!F1971!XADDR2!!!!
S!VR_PVDDQ_GHJ_AIREF1!EU1G2!21!@baseboard_fab2_lib.baseboard_fab2(sch_1):page223_i90@mstr_controller.pxm1310b(chips)!PXM1310B_QFN-IC,H89186-001!!!F1970!AIREF1!!!!
S!VR_PVDDQ_GHJ_AIREF2!EU1G2!23!@baseboard_fab2_lib.baseboard_fab2(sch_1):page223_i90@mstr_controller.pxm1310b(chips)!PXM1310B_QFN-IC,H89186-001!!!F1970!AIREF2!!!!
S!TP_PVDDQ_GHJ_PH3_IMON_REF!EU1G2!25!@baseboard_fab2_lib.baseboard_fab2(sch_1):page223_i90@mstr_controller.pxm1310b(chips)!PXM1310B_QFN-IC,H89186-001!!!F1970!AIREF3!!!!
S!ISENSE_PVDDQ_GHJ_PH1_IMON!EU1G2!22!@baseboard_fab2_lib.baseboard_fab2(sch_1):page223_i90@mstr_controller.pxm1310b(chips)!PXM1310B_QFN-IC,H89186-001!!!F1970!AISEN1!!!!
S!ISENSE_PVDDQ_GHJ_PH2_IMON!EU1G2!24!@baseboard_fab2_lib.baseboard_fab2(sch_1):page223_i90@mstr_controller.pxm1310b(chips)!PXM1310B_QFN-IC,H89186-001!!!F1970!AISEN2!!!!
S!TP_PVDDQ_GHJ_PH3_IMON!EU1G2!26!@baseboard_fab2_lib.baseboard_fab2(sch_1):page223_i90@mstr_controller.pxm1310b(chips)!PXM1310B_QFN-IC,H89186-001!!!F1970!AISEN3!!!!
S!VR_PVDDQ_GHJ_PWM1!EU1G2!5!@baseboard_fab2_lib.baseboard_fab2(sch_1):page223_i90@mstr_controller.pxm1310b(chips)!PXM1310B_QFN-IC,H89186-001!!!F1970!APWM1!!!!
S!VR_PVDDQ_GHJ_PWM2!EU1G2!4!@baseboard_fab2_lib.baseboard_fab2(sch_1):page223_i90@mstr_controller.pxm1310b(chips)!PXM1310B_QFN-IC,H89186-001!!!F1970!APWM2!!!!
S!TP_PVDDQ_GHJ_PWM3!EU1G2!3!@baseboard_fab2_lib.baseboard_fab2(sch_1):page223_i90@mstr_controller.pxm1310b(chips)!PXM1310B_QFN-IC,H89186-001!!!F1970!APWM3!!!!
S!A_TSENSE_PVDDQ_GHJ!EU1G2!35!@baseboard_fab2_lib.baseboard_fab2(sch_1):page223_i90@mstr_controller.pxm1310b(chips)!PXM1310B_QFN-IC,H89186-001!!!F1970!ATSEN!!!!
S!VSENSE_PVDDQ_GHJ_N!EU1G2!20!@baseboard_fab2_lib.baseboard_fab2(sch_1):page223_i90@mstr_controller.pxm1310b(chips)!PXM1310B_QFN-IC,H89186-001!!!F1970!AVREF!!!!
S!VR_PVDDQ_GHJ_AVSP!EU1G2!19!@baseboard_fab2_lib.baseboard_fab2(sch_1):page223_i90@mstr_controller.pxm1310b(chips)!PXM1310B_QFN-IC,H89186-001!!!F1970!AVSEN!!!!
S!TP_PVDDQ_GHJ_BREF1!EU1G2!31!@baseboard_fab2_lib.baseboard_fab2(sch_1):page223_i90@mstr_controller.pxm1310b(chips)!PXM1310B_QFN-IC,H89186-001!!!F1970!BIREF1!!!!
S!GND!EU1G2!32!@baseboard_fab2_lib.baseboard_fab2(sch_1):page223_i90@mstr_controller.pxm1310b(chips)!PXM1310B_QFN-IC,H89186-001!!!F1970!BISEN1!!!!
S!TP_PVDDQ_GHJ_BPWM1!EU1G2!1!@baseboard_fab2_lib.baseboard_fab2(sch_1):page223_i90@mstr_controller.pxm1310b(chips)!PXM1310B_QFN-IC,H89186-001!!!F1970!BPWM1!!!!
S!TP_PVDDQ_GHJ_BTSEN!EU1G2!34!@baseboard_fab2_lib.baseboard_fab2(sch_1):page223_i90@mstr_controller.pxm1310b(chips)!PXM1310B_QFN-IC,H89186-001!!!F1970!BTSEN!!!!
S!TP_PVDDQ_GHJ_BVREF!EU1G2!30!@baseboard_fab2_lib.baseboard_fab2(sch_1):page223_i90@mstr_controller.pxm1310b(chips)!PXM1310B_QFN-IC,H89186-001!!!F1970!BVREF!!!!
S!TP_PVDDQ_GHJ_BVSEN!EU1G2!29!@baseboard_fab2_lib.baseboard_fab2(sch_1):page223_i90@mstr_controller.pxm1310b(chips)!PXM1310B_QFN-IC,H89186-001!!!F1970!BVSEN!!!!
S!NC_PVDDQ_GHJ_DNC0!EU1G2!2!@baseboard_fab2_lib.baseboard_fab2(sch_1):page223_i90@mstr_controller.pxm1310b(chips)!PXM1310B_QFN-IC,H89186-001!!!F1970!DNC(0)!!!!
S!NC_PVDDQ_GHJ_DNC1!EU1G2!28!@baseboard_fab2_lib.baseboard_fab2(sch_1):page223_i90@mstr_controller.pxm1310b(chips)!PXM1310B_QFN-IC,H89186-001!!!F1970!DNC(1)!!!!
S!TP_PVDDQ_GHJ_MP2!EU1G2!18!@baseboard_fab2_lib.baseboard_fab2(sch_1):page223_i90@mstr_controller.pxm1310b(chips)!PXM1310B_QFN-IC,H89186-001!!!F1970!MP2!!!!
S!GND!EU1G2!27!@baseboard_fab2_lib.baseboard_fab2(sch_1):page223_i90@mstr_controller.pxm1310b(chips)!PXM1310B_QFN-IC,H89186-001!!!F1970!GND!!!!
S!PU_VR_PVDDQ_GHJ_FAULT1!EU1G2!13!@baseboard_fab2_lib.baseboard_fab2(sch_1):page223_i90@mstr_controller.pxm1310b(chips)!PXM1310B_QFN-IC,H89186-001!!!F1970!MP0!!!!
S!TP_PVDDQ_GHJ_MP1!EU1G2!14!@baseboard_fab2_lib.baseboard_fab2(sch_1):page223_i90@mstr_controller.pxm1310b(chips)!PXM1310B_QFN-IC,H89186-001!!!F1970!MP1!!!!
S!VR_PVDDQ_GHJ_AIINSEN!EU1G2!38!@baseboard_fab2_lib.baseboard_fab2(sch_1):page223_i90@mstr_controller.pxm1310b(chips)!PXM1310B_QFN-IC,H89186-001!!!F1970!IINSEN!!!!
S!NC_PVDDQ_GHJ_PINALRT_N!EU1G2!12!@baseboard_fab2_lib.baseboard_fab2(sch_1):page223_i90@mstr_controller.pxm1310b(chips)!PXM1310B_QFN-IC,H89186-001!!!F1970!PINALRT_N!!!!
S!TP_PVDDQ_GHJ_RESET_N!EU1G2!8!@baseboard_fab2_lib.baseboard_fab2(sch_1):page223_i90@mstr_controller.pxm1310b(chips)!PXM1310B_QFN-IC,H89186-001!!!F1970!RESET_N!!!!
S!SMB_VR_SCL_VDDQ_GHJ!EU1G2!7!@baseboard_fab2_lib.baseboard_fab2(sch_1):page223_i90@mstr_controller.pxm1310b(chips)!PXM1310B_QFN-IC,H89186-001!!!F1970!SCL!!!!
S!SMB_VR_SDA_VDDQ_GHJ!EU1G2!6!@baseboard_fab2_lib.baseboard_fab2(sch_1):page223_i90@mstr_controller.pxm1310b(chips)!PXM1310B_QFN-IC,H89186-001!!!F1970!SDA!!!!
S!GND!EU1G2!41!@baseboard_fab2_lib.baseboard_fab2(sch_1):page223_i90@mstr_controller.pxm1310b(chips)!PXM1310B_QFN-IC,H89186-001!!!F1970!THPAD!!!!
S!SVID_ALERT_PVDDQ_GHJ!EU1G2!17!@baseboard_fab2_lib.baseboard_fab2(sch_1):page223_i90@mstr_controller.pxm1310b(chips)!PXM1310B_QFN-IC,H89186-001!!!F1970!VALRT_N!!!!
S!SVID_CLK_PVDDQ_GHJ!EU1G2!15!@baseboard_fab2_lib.baseboard_fab2(sch_1):page223_i90@mstr_controller.pxm1310b(chips)!PXM1310B_QFN-IC,H89186-001!!!F1970!VCLK!!!!
S!VR_PVDDQ_GHJ_VD12!EU1G2!40!@baseboard_fab2_lib.baseboard_fab2(sch_1):page223_i90@mstr_controller.pxm1310b(chips)!PXM1310B_QFN-IC,H89186-001!!!F1970!VD12!!!!
S!VR_PVDDQ_GHJ_VDD!EU1G2!39!@baseboard_fab2_lib.baseboard_fab2(sch_1):page223_i90@mstr_controller.pxm1310b(chips)!PXM1310B_QFN-IC,H89186-001!!!F1970!VDD!!!!
S!SVID_VDIO_PVDDQ_GHJ!EU1G2!16!@baseboard_fab2_lib.baseboard_fab2(sch_1):page223_i90@mstr_controller.pxm1310b(chips)!PXM1310B_QFN-IC,H89186-001!!!F1970!VDIO!!!!
S!VR_PVDDQ_GHJ_VINSEN!EU1G2!37!@baseboard_fab2_lib.baseboard_fab2(sch_1):page223_i90@mstr_controller.pxm1310b(chips)!PXM1310B_QFN-IC,H89186-001!!!F1970!VINSEN!!!!
S!VR_PVDDQ_GHJ_VREN!EU1G2!10!@baseboard_fab2_lib.baseboard_fab2(sch_1):page223_i90@mstr_controller.pxm1310b(chips)!PXM1310B_QFN-IC,H89186-001!!!F1970!AVREN!!!!
S!IRQ_PVDDQ_GHJ_VRHOT_LVT3_R_N!EU1G2!11!@baseboard_fab2_lib.baseboard_fab2(sch_1):page223_i90@mstr_controller.pxm1310b(chips)!PXM1310B_QFN-IC,H89186-001!!!F1970!VRHOT_N!!!!
S!PWRGD_PVDDQ_GHJ_R!EU1G2!9!@baseboard_fab2_lib.baseboard_fab2(sch_1):page223_i90@mstr_controller.pxm1310b(chips)!PXM1310B_QFN-IC,H89186-001!!!F1970!AVRRDY!!!!
S!VR_PVDDQ_GHJ_XADDR1!EU1G2!36!@baseboard_fab2_lib.baseboard_fab2(sch_1):page223_i90@mstr_controller.pxm1310b(chips)!PXM1310B_QFN-IC,H89186-001!!!F1970!XADDR1!!!!
S!VR_PVDDQ_GHJ_XADDR2!EU1G2!33!@baseboard_fab2_lib.baseboard_fab2(sch_1):page223_i90@mstr_controller.pxm1310b(chips)!PXM1310B_QFN-IC,H89186-001!!!F1970!XADDR2!!!!
S!VR_PVDDQ_DEF_AIREF1!EU7A5!21!@baseboard_fab2_lib.baseboard_fab2(sch_1):page218_i75@mstr_controller.pxm1310b(chips)!PXM1310B_QFN-IC,H89186-001!!!F1969!AIREF1!!!!
S!VR_PVDDQ_DEF_AIREF2!EU7A5!23!@baseboard_fab2_lib.baseboard_fab2(sch_1):page218_i75@mstr_controller.pxm1310b(chips)!PXM1310B_QFN-IC,H89186-001!!!F1969!AIREF2!!!!
S!TP_PVDDQ_DEF_PH3_IMON_REF!EU7A5!25!@baseboard_fab2_lib.baseboard_fab2(sch_1):page218_i75@mstr_controller.pxm1310b(chips)!PXM1310B_QFN-IC,H89186-001!!!F1969!AIREF3!!!!
S!ISENSE_PVDDQ_DEF_PH1_IMON!EU7A5!22!@baseboard_fab2_lib.baseboard_fab2(sch_1):page218_i75@mstr_controller.pxm1310b(chips)!PXM1310B_QFN-IC,H89186-001!!!F1969!AISEN1!!!!
S!ISENSE_PVDDQ_DEF_PH2_IMON!EU7A5!24!@baseboard_fab2_lib.baseboard_fab2(sch_1):page218_i75@mstr_controller.pxm1310b(chips)!PXM1310B_QFN-IC,H89186-001!!!F1969!AISEN2!!!!
S!TP_PVDDQ_DEF_PH3_IMON!EU7A5!26!@baseboard_fab2_lib.baseboard_fab2(sch_1):page218_i75@mstr_controller.pxm1310b(chips)!PXM1310B_QFN-IC,H89186-001!!!F1969!AISEN3!!!!
S!VR_PVDDQ_DEF_PWM1!EU7A5!5!@baseboard_fab2_lib.baseboard_fab2(sch_1):page218_i75@mstr_controller.pxm1310b(chips)!PXM1310B_QFN-IC,H89186-001!!!F1969!APWM1!!!!
S!VR_PVDDQ_DEF_PWM2!EU7A5!4!@baseboard_fab2_lib.baseboard_fab2(sch_1):page218_i75@mstr_controller.pxm1310b(chips)!PXM1310B_QFN-IC,H89186-001!!!F1969!APWM2!!!!
S!TP_PVDDQ_DEF_PWM3!EU7A5!3!@baseboard_fab2_lib.baseboard_fab2(sch_1):page218_i75@mstr_controller.pxm1310b(chips)!PXM1310B_QFN-IC,H89186-001!!!F1969!APWM3!!!!
S!A_TSENSE_PVDDQ_DEF!EU7A5!35!@baseboard_fab2_lib.baseboard_fab2(sch_1):page218_i75@mstr_controller.pxm1310b(chips)!PXM1310B_QFN-IC,H89186-001!!!F1969!ATSEN!!!!
S!VSENSE_PVDDQ_DEF_N!EU7A5!20!@baseboard_fab2_lib.baseboard_fab2(sch_1):page218_i75@mstr_controller.pxm1310b(chips)!PXM1310B_QFN-IC,H89186-001!!!F1969!AVREF!!!!
S!VR_PVDDQ_DEF_AVSP!EU7A5!19!@baseboard_fab2_lib.baseboard_fab2(sch_1):page218_i75@mstr_controller.pxm1310b(chips)!PXM1310B_QFN-IC,H89186-001!!!F1969!AVSEN!!!!
S!TP_PVDDQ_DEF_BREF1!EU7A5!31!@baseboard_fab2_lib.baseboard_fab2(sch_1):page218_i75@mstr_controller.pxm1310b(chips)!PXM1310B_QFN-IC,H89186-001!!!F1969!BIREF1!!!!
S!GND!EU7A5!32!@baseboard_fab2_lib.baseboard_fab2(sch_1):page218_i75@mstr_controller.pxm1310b(chips)!PXM1310B_QFN-IC,H89186-001!!!F1969!BISEN1!!!!
S!TP_PVDDQ_DEF_BPWM1!EU7A5!1!@baseboard_fab2_lib.baseboard_fab2(sch_1):page218_i75@mstr_controller.pxm1310b(chips)!PXM1310B_QFN-IC,H89186-001!!!F1969!BPWM1!!!!
S!TP_PVDDQ_DEF_BTSEN!EU7A5!34!@baseboard_fab2_lib.baseboard_fab2(sch_1):page218_i75@mstr_controller.pxm1310b(chips)!PXM1310B_QFN-IC,H89186-001!!!F1969!BTSEN!!!!
S!TP_PVDDQ_DEF_BVREF!EU7A5!30!@baseboard_fab2_lib.baseboard_fab2(sch_1):page218_i75@mstr_controller.pxm1310b(chips)!PXM1310B_QFN-IC,H89186-001!!!F1969!BVREF!!!!
S!TP_PVDDQ_DEF_BVSEN!EU7A5!29!@baseboard_fab2_lib.baseboard_fab2(sch_1):page218_i75@mstr_controller.pxm1310b(chips)!PXM1310B_QFN-IC,H89186-001!!!F1969!BVSEN!!!!
S!NC_PVDDQ_DEF_DNC0!EU7A5!2!@baseboard_fab2_lib.baseboard_fab2(sch_1):page218_i75@mstr_controller.pxm1310b(chips)!PXM1310B_QFN-IC,H89186-001!!!F1969!DNC(0)!!!!
S!NC_PVDDQ_DEF_DNC1!EU7A5!28!@baseboard_fab2_lib.baseboard_fab2(sch_1):page218_i75@mstr_controller.pxm1310b(chips)!PXM1310B_QFN-IC,H89186-001!!!F1969!DNC(1)!!!!
S!TP_PVDDQ_DEF_MP2!EU7A5!18!@baseboard_fab2_lib.baseboard_fab2(sch_1):page218_i75@mstr_controller.pxm1310b(chips)!PXM1310B_QFN-IC,H89186-001!!!F1969!MP2!!!!
S!GND!EU7A5!27!@baseboard_fab2_lib.baseboard_fab2(sch_1):page218_i75@mstr_controller.pxm1310b(chips)!PXM1310B_QFN-IC,H89186-001!!!F1969!GND!!!!
S!PU_VR_PVDDQ_DEF_FAULT1!EU7A5!13!@baseboard_fab2_lib.baseboard_fab2(sch_1):page218_i75@mstr_controller.pxm1310b(chips)!PXM1310B_QFN-IC,H89186-001!!!F1969!MP0!!!!
S!TP_PVDDQ_DEF_MP1!EU7A5!14!@baseboard_fab2_lib.baseboard_fab2(sch_1):page218_i75@mstr_controller.pxm1310b(chips)!PXM1310B_QFN-IC,H89186-001!!!F1969!MP1!!!!
S!VR_PVDDQ_DEF_AIINSEN!EU7A5!38!@baseboard_fab2_lib.baseboard_fab2(sch_1):page218_i75@mstr_controller.pxm1310b(chips)!PXM1310B_QFN-IC,H89186-001!!!F1969!IINSEN!!!!
S!TP_PVDDQ_DEF_PINALRT_N!EU7A5!12!@baseboard_fab2_lib.baseboard_fab2(sch_1):page218_i75@mstr_controller.pxm1310b(chips)!PXM1310B_QFN-IC,H89186-001!!!F1969!PINALRT_N!!!!
S!TP_PVDDQ_DEF_RESET_N!EU7A5!8!@baseboard_fab2_lib.baseboard_fab2(sch_1):page218_i75@mstr_controller.pxm1310b(chips)!PXM1310B_QFN-IC,H89186-001!!!F1969!RESET_N!!!!
S!SMB_VR_SCL_VDDQ_DEF!EU7A5!7!@baseboard_fab2_lib.baseboard_fab2(sch_1):page218_i75@mstr_controller.pxm1310b(chips)!PXM1310B_QFN-IC,H89186-001!!!F1969!SCL!!!!
S!SMB_VR_SDA_VDDQ_DEF!EU7A5!6!@baseboard_fab2_lib.baseboard_fab2(sch_1):page218_i75@mstr_controller.pxm1310b(chips)!PXM1310B_QFN-IC,H89186-001!!!F1969!SDA!!!!
S!GND!EU7A5!41!@baseboard_fab2_lib.baseboard_fab2(sch_1):page218_i75@mstr_controller.pxm1310b(chips)!PXM1310B_QFN-IC,H89186-001!!!F1969!THPAD!!!!
S!SVID_ALERT_PVDDQ_DEF!EU7A5!17!@baseboard_fab2_lib.baseboard_fab2(sch_1):page218_i75@mstr_controller.pxm1310b(chips)!PXM1310B_QFN-IC,H89186-001!!!F1969!VALRT_N!!!!
S!SVID_CLK_PVDDQ_DEF!EU7A5!15!@baseboard_fab2_lib.baseboard_fab2(sch_1):page218_i75@mstr_controller.pxm1310b(chips)!PXM1310B_QFN-IC,H89186-001!!!F1969!VCLK!!!!
S!VR_PVDDQ_DEF_VD12!EU7A5!40!@baseboard_fab2_lib.baseboard_fab2(sch_1):page218_i75@mstr_controller.pxm1310b(chips)!PXM1310B_QFN-IC,H89186-001!!!F1969!VD12!!!!
S!VR_PVDDQ_DEF_VDD!EU7A5!39!@baseboard_fab2_lib.baseboard_fab2(sch_1):page218_i75@mstr_controller.pxm1310b(chips)!PXM1310B_QFN-IC,H89186-001!!!F1969!VDD!!!!
S!SVID_VDIO_PVDDQ_DEF!EU7A5!16!@baseboard_fab2_lib.baseboard_fab2(sch_1):page218_i75@mstr_controller.pxm1310b(chips)!PXM1310B_QFN-IC,H89186-001!!!F1969!VDIO!!!!
S!VR_PVDDQ_DEF_VINSEN!EU7A5!37!@baseboard_fab2_lib.baseboard_fab2(sch_1):page218_i75@mstr_controller.pxm1310b(chips)!PXM1310B_QFN-IC,H89186-001!!!F1969!VINSEN!!!!
S!VR_PVDDQ_DEF_VREN!EU7A5!10!@baseboard_fab2_lib.baseboard_fab2(sch_1):page218_i75@mstr_controller.pxm1310b(chips)!PXM1310B_QFN-IC,H89186-001!!!F1969!AVREN!!!!
S!IRQ_PVDDQ_DEF_VRHOT_LVT3_R_N!EU7A5!11!@baseboard_fab2_lib.baseboard_fab2(sch_1):page218_i75@mstr_controller.pxm1310b(chips)!PXM1310B_QFN-IC,H89186-001!!!F1969!VRHOT_N!!!!
S!PWRGD_PVDDQ_DEF_R!EU7A5!9!@baseboard_fab2_lib.baseboard_fab2(sch_1):page218_i75@mstr_controller.pxm1310b(chips)!PXM1310B_QFN-IC,H89186-001!!!F1969!AVRRDY!!!!
S!VR_PVDDQ_DEF_XADDR1!EU7A5!36!@baseboard_fab2_lib.baseboard_fab2(sch_1):page218_i75@mstr_controller.pxm1310b(chips)!PXM1310B_QFN-IC,H89186-001!!!F1969!XADDR1!!!!
S!VR_PVDDQ_DEF_XADDR2!EU7A5!33!@baseboard_fab2_lib.baseboard_fab2(sch_1):page218_i75@mstr_controller.pxm1310b(chips)!PXM1310B_QFN-IC,H89186-001!!!F1969!XADDR2!!!!
S!VR_PVDDQ_ABC_AIREF1!EU7G1!21!@baseboard_fab2_lib.baseboard_fab2(sch_1):page215_i358@mstr_controller.pxm1310b(chips)!PXM1310B_QFN-IC,H89186-001!!!F1968!AIREF1!!!!
S!VR_PVDDQ_ABC_AIREF2!EU7G1!23!@baseboard_fab2_lib.baseboard_fab2(sch_1):page215_i358@mstr_controller.pxm1310b(chips)!PXM1310B_QFN-IC,H89186-001!!!F1968!AIREF2!!!!
S!TP_PVDDQ_ABC_PH3_IMON_REF!EU7G1!25!@baseboard_fab2_lib.baseboard_fab2(sch_1):page215_i358@mstr_controller.pxm1310b(chips)!PXM1310B_QFN-IC,H89186-001!!!F1968!AIREF3!!!!
S!ISENSE_PVDDQ_ABC_PH1_IMON!EU7G1!22!@baseboard_fab2_lib.baseboard_fab2(sch_1):page215_i358@mstr_controller.pxm1310b(chips)!PXM1310B_QFN-IC,H89186-001!!!F1968!AISEN1!!!!
S!ISENSE_PVDDQ_ABC_PH2_IMON!EU7G1!24!@baseboard_fab2_lib.baseboard_fab2(sch_1):page215_i358@mstr_controller.pxm1310b(chips)!PXM1310B_QFN-IC,H89186-001!!!F1968!AISEN2!!!!
S!TP_PVDDQ_ABC_PH3_IMON!EU7G1!26!@baseboard_fab2_lib.baseboard_fab2(sch_1):page215_i358@mstr_controller.pxm1310b(chips)!PXM1310B_QFN-IC,H89186-001!!!F1968!AISEN3!!!!
S!VR_PVDDQ_ABC_PWM1!EU7G1!5!@baseboard_fab2_lib.baseboard_fab2(sch_1):page215_i358@mstr_controller.pxm1310b(chips)!PXM1310B_QFN-IC,H89186-001!!!F1968!APWM1!!!!
S!VR_PVDDQ_ABC_PWM2!EU7G1!4!@baseboard_fab2_lib.baseboard_fab2(sch_1):page215_i358@mstr_controller.pxm1310b(chips)!PXM1310B_QFN-IC,H89186-001!!!F1968!APWM2!!!!
S!TP_PVDDQ_ABC_PWM3!EU7G1!3!@baseboard_fab2_lib.baseboard_fab2(sch_1):page215_i358@mstr_controller.pxm1310b(chips)!PXM1310B_QFN-IC,H89186-001!!!F1968!APWM3!!!!
S!A_TSENSE_PVDDQ_ABC!EU7G1!35!@baseboard_fab2_lib.baseboard_fab2(sch_1):page215_i358@mstr_controller.pxm1310b(chips)!PXM1310B_QFN-IC,H89186-001!!!F1968!ATSEN!!!!
S!VSENSE_PVDDQ_ABC_N!EU7G1!20!@baseboard_fab2_lib.baseboard_fab2(sch_1):page215_i358@mstr_controller.pxm1310b(chips)!PXM1310B_QFN-IC,H89186-001!!!F1968!AVREF!!!!
S!VR_PVDDQ_ABC_AVSP!EU7G1!19!@baseboard_fab2_lib.baseboard_fab2(sch_1):page215_i358@mstr_controller.pxm1310b(chips)!PXM1310B_QFN-IC,H89186-001!!!F1968!AVSEN!!!!
S!TP_PVDDQ_ABC_BREF1!EU7G1!31!@baseboard_fab2_lib.baseboard_fab2(sch_1):page215_i358@mstr_controller.pxm1310b(chips)!PXM1310B_QFN-IC,H89186-001!!!F1968!BIREF1!!!!
S!GND!EU7G1!32!@baseboard_fab2_lib.baseboard_fab2(sch_1):page215_i358@mstr_controller.pxm1310b(chips)!PXM1310B_QFN-IC,H89186-001!!!F1968!BISEN1!!!!
S!TP_PVDDQ_ABC_BPWM1!EU7G1!1!@baseboard_fab2_lib.baseboard_fab2(sch_1):page215_i358@mstr_controller.pxm1310b(chips)!PXM1310B_QFN-IC,H89186-001!!!F1968!BPWM1!!!!
S!TP_PVDDQ_ABC_BTSEN!EU7G1!34!@baseboard_fab2_lib.baseboard_fab2(sch_1):page215_i358@mstr_controller.pxm1310b(chips)!PXM1310B_QFN-IC,H89186-001!!!F1968!BTSEN!!!!
S!TP_PVDDQ_ABC_BVREF!EU7G1!30!@baseboard_fab2_lib.baseboard_fab2(sch_1):page215_i358@mstr_controller.pxm1310b(chips)!PXM1310B_QFN-IC,H89186-001!!!F1968!BVREF!!!!
S!TP_PVDDQ_ABC_BVSEN!EU7G1!29!@baseboard_fab2_lib.baseboard_fab2(sch_1):page215_i358@mstr_controller.pxm1310b(chips)!PXM1310B_QFN-IC,H89186-001!!!F1968!BVSEN!!!!
S!NC_PVDDQ_ABC_DNC0!EU7G1!2!@baseboard_fab2_lib.baseboard_fab2(sch_1):page215_i358@mstr_controller.pxm1310b(chips)!PXM1310B_QFN-IC,H89186-001!!!F1968!DNC(0)!!!!
S!NC_PVDDQ_ABC_DNC1!EU7G1!28!@baseboard_fab2_lib.baseboard_fab2(sch_1):page215_i358@mstr_controller.pxm1310b(chips)!PXM1310B_QFN-IC,H89186-001!!!F1968!DNC(1)!!!!
S!TP_PVDDQ_ABC_MP2!EU7G1!18!@baseboard_fab2_lib.baseboard_fab2(sch_1):page215_i358@mstr_controller.pxm1310b(chips)!PXM1310B_QFN-IC,H89186-001!!!F1968!MP2!!!!
S!GND!EU7G1!27!@baseboard_fab2_lib.baseboard_fab2(sch_1):page215_i358@mstr_controller.pxm1310b(chips)!PXM1310B_QFN-IC,H89186-001!!!F1968!GND!!!!
S!PU_VR_PVDDQ_ABC_FAULT1!EU7G1!13!@baseboard_fab2_lib.baseboard_fab2(sch_1):page215_i358@mstr_controller.pxm1310b(chips)!PXM1310B_QFN-IC,H89186-001!!!F1968!MP0!!!!
S!TP_PVDDQ_ABC_MP1!EU7G1!14!@baseboard_fab2_lib.baseboard_fab2(sch_1):page215_i358@mstr_controller.pxm1310b(chips)!PXM1310B_QFN-IC,H89186-001!!!F1968!MP1!!!!
S!VR_PVDDQ_ABC_AIINSEN!EU7G1!38!@baseboard_fab2_lib.baseboard_fab2(sch_1):page215_i358@mstr_controller.pxm1310b(chips)!PXM1310B_QFN-IC,H89186-001!!!F1968!IINSEN!!!!
S!TP_PVDDQ_ABC_PINALRT_N!EU7G1!12!@baseboard_fab2_lib.baseboard_fab2(sch_1):page215_i358@mstr_controller.pxm1310b(chips)!PXM1310B_QFN-IC,H89186-001!!!F1968!PINALRT_N!!!!
S!TP_PVDDQ_ABC_RESET_N!EU7G1!8!@baseboard_fab2_lib.baseboard_fab2(sch_1):page215_i358@mstr_controller.pxm1310b(chips)!PXM1310B_QFN-IC,H89186-001!!!F1968!RESET_N!!!!
S!SMB_VR_SCL_VDDQ_ABC!EU7G1!7!@baseboard_fab2_lib.baseboard_fab2(sch_1):page215_i358@mstr_controller.pxm1310b(chips)!PXM1310B_QFN-IC,H89186-001!!!F1968!SCL!!!!
S!SMB_VR_SDA_VDDQ_ABC!EU7G1!6!@baseboard_fab2_lib.baseboard_fab2(sch_1):page215_i358@mstr_controller.pxm1310b(chips)!PXM1310B_QFN-IC,H89186-001!!!F1968!SDA!!!!
S!GND!EU7G1!41!@baseboard_fab2_lib.baseboard_fab2(sch_1):page215_i358@mstr_controller.pxm1310b(chips)!PXM1310B_QFN-IC,H89186-001!!!F1968!THPAD!!!!
S!SVID_ALERT_PVDDQ_ABC!EU7G1!17!@baseboard_fab2_lib.baseboard_fab2(sch_1):page215_i358@mstr_controller.pxm1310b(chips)!PXM1310B_QFN-IC,H89186-001!!!F1968!VALRT_N!!!!
S!SVID_CLK_PVDDQ_ABC!EU7G1!15!@baseboard_fab2_lib.baseboard_fab2(sch_1):page215_i358@mstr_controller.pxm1310b(chips)!PXM1310B_QFN-IC,H89186-001!!!F1968!VCLK!!!!
S!VR_PVDDQ_ABC_VD12!EU7G1!40!@baseboard_fab2_lib.baseboard_fab2(sch_1):page215_i358@mstr_controller.pxm1310b(chips)!PXM1310B_QFN-IC,H89186-001!!!F1968!VD12!!!!
S!VR_PVDDQ_ABC_VDD!EU7G1!39!@baseboard_fab2_lib.baseboard_fab2(sch_1):page215_i358@mstr_controller.pxm1310b(chips)!PXM1310B_QFN-IC,H89186-001!!!F1968!VDD!!!!
S!SVID_VDIO_PVDDQ_ABC!EU7G1!16!@baseboard_fab2_lib.baseboard_fab2(sch_1):page215_i358@mstr_controller.pxm1310b(chips)!PXM1310B_QFN-IC,H89186-001!!!F1968!VDIO!!!!
S!VR_PVDDQ_ABC_VINSEN!EU7G1!37!@baseboard_fab2_lib.baseboard_fab2(sch_1):page215_i358@mstr_controller.pxm1310b(chips)!PXM1310B_QFN-IC,H89186-001!!!F1968!VINSEN!!!!
S!VR_PVDDQ_ABC_VREN!EU7G1!10!@baseboard_fab2_lib.baseboard_fab2(sch_1):page215_i358@mstr_controller.pxm1310b(chips)!PXM1310B_QFN-IC,H89186-001!!!F1968!AVREN!!!!
S!IRQ_PVDDQ_ABC_VRHOT_LVT3_R_N!EU7G1!11!@baseboard_fab2_lib.baseboard_fab2(sch_1):page215_i358@mstr_controller.pxm1310b(chips)!PXM1310B_QFN-IC,H89186-001!!!F1968!VRHOT_N!!!!
S!PWRGD_PVDDQ_ABC_R!EU7G1!9!@baseboard_fab2_lib.baseboard_fab2(sch_1):page215_i358@mstr_controller.pxm1310b(chips)!PXM1310B_QFN-IC,H89186-001!!!F1968!AVRRDY!!!!
S!VR_PVDDQ_ABC_XADDR1!EU7G1!36!@baseboard_fab2_lib.baseboard_fab2(sch_1):page215_i358@mstr_controller.pxm1310b(chips)!PXM1310B_QFN-IC,H89186-001!!!F1968!XADDR1!!!!
S!VR_PVDDQ_ABC_XADDR2!EU7G1!33!@baseboard_fab2_lib.baseboard_fab2(sch_1):page215_i358@mstr_controller.pxm1310b(chips)!PXM1310B_QFN-IC,H89186-001!!!F1968!XADDR2!!!!
S!VR_FET_SW_P12V_STBY_PVCCIN_CPU1!R1C13!1!@baseboard_fab2_lib.baseboard_fab2(sch_1):page206_i49@mstr_discrete.res(chips)!RES_0402-100.0K,1%,1/16W,CHIP,B!!!F1130!A!!!!
S!VR_PVCCIN_CPU1_AVINSEN!R1C13!2!@baseboard_fab2_lib.baseboard_fab2(sch_1):page206_i49@mstr_discrete.res(chips)!RES_0402-100.0K,1%,1/16W,CHIP,B!!!F1130!B!!!!
S!VR_FET_SW_P12V_STBY_PVDDQ_DEF!R3L12!1!@baseboard_fab2_lib.baseboard_fab2(sch_1):page218_i53@mstr_discrete.res(chips)!RES_0402-100.0K,1%,1/16W,CHIP,B!!!F1129!A!!!!
S!VR_PVDDQ_DEF_VINSEN!R3L12!2!@baseboard_fab2_lib.baseboard_fab2(sch_1):page218_i53@mstr_discrete.res(chips)!RES_0402-100.0K,1%,1/16W,CHIP,B!!!F1129!B!!!!
S!VR_FET_SW_P12V_STBY_PVCCIO_CPU0!R3P12!1!@baseboard_fab2_lib.baseboard_fab2(sch_1):page211_i31@mstr_discrete.res(chips)!RES_0402-100.0K,1%,1/16W,CHIP,B!!!F1128!A!!!!
S!VR_PVCCIO_CPU0_VINSEN!R3P12!2!@baseboard_fab2_lib.baseboard_fab2(sch_1):page211_i31@mstr_discrete.res(chips)!RES_0402-100.0K,1%,1/16W,CHIP,B!!!F1128!B!!!!
S!VR_FET_SW_P12V_STBY_PVCCIN_CPU0!R4D27!1!@baseboard_fab2_lib.baseboard_fab2(sch_1):page201_i54@mstr_discrete.res(chips)!RES_0402-100.0K,1%,1/16W,CHIP,B!!!F1127!A!!!!
S!VR_PVCCIN_CPU0_AVINSEN!R4D27!2!@baseboard_fab2_lib.baseboard_fab2(sch_1):page201_i54@mstr_discrete.res(chips)!RES_0402-100.0K,1%,1/16W,CHIP,B!!!F1127!B!!!!
S!VR_FET_SW_P12V_STBY_PVCCIN_CPU0!R4D60!1!@baseboard_fab2_lib.baseboard_fab2(sch_1):page213_i31@mstr_discrete.res(chips)!RES_0402-100.0K,1%,1/16W,CHIP,B!!!F1126!A!!!!
S!VR_PVCCIO_CPU1_VINSEN!R4D60!2!@baseboard_fab2_lib.baseboard_fab2(sch_1):page213_i31@mstr_discrete.res(chips)!RES_0402-100.0K,1%,1/16W,CHIP,B!!!F1126!B!!!!
S!VR_FET_SW_P12V_STBY_PVDDQ_ABC!R7F34!1!@baseboard_fab2_lib.baseboard_fab2(sch_1):page215_i336@mstr_discrete.res(chips)!RES_0402-100.0K,1%,1/16W,CHIP,B!!!F1125!A!!!!
S!VR_PVDDQ_ABC_VINSEN!R7F34!2!@baseboard_fab2_lib.baseboard_fab2(sch_1):page215_i336@mstr_discrete.res(chips)!RES_0402-100.0K,1%,1/16W,CHIP,B!!!F1125!B!!!!
S!VR_FET_SW_P12V_STBY_PVDDQ_DEF!R8A4!1!@baseboard_fab2_lib.baseboard_fab2(sch_1):page235_i165@mstr_discrete.res(chips)!RES_0402-100.0K,1%,1/16W,CHIP,B!!!F1124!A!!!!
S!VR_PVNN_PCH_VINSEN!R8A4!2!@baseboard_fab2_lib.baseboard_fab2(sch_1):page235_i165@mstr_discrete.res(chips)!RES_0402-100.0K,1%,1/16W,CHIP,B!!!F1124!B!!!!
S!VR_FET_SW_P12V_STBY_PVDDQ_KLM!R9M8!1!@baseboard_fab2_lib.baseboard_fab2(sch_1):page226_i57@mstr_discrete.res(chips)!RES_0402-100.0K,1%,1/16W,CHIP,B!!!F1123!A!!!!
S!VR_PVDDQ_KLM_VINSEN!R9M8!2!@baseboard_fab2_lib.baseboard_fab2(sch_1):page226_i57@mstr_discrete.res(chips)!RES_0402-100.0K,1%,1/16W,CHIP,B!!!F1123!B!!!!
S!VR_FET_SW_P12V_STBY_PVDDQ_GHJ!R9U11!1!@baseboard_fab2_lib.baseboard_fab2(sch_1):page223_i57@mstr_discrete.res(chips)!RES_0402-100.0K,1%,1/16W,CHIP,B!!!F1122!A!!!!
S!VR_PVDDQ_GHJ_VINSEN!R9U11!2!@baseboard_fab2_lib.baseboard_fab2(sch_1):page223_i57@mstr_discrete.res(chips)!RES_0402-100.0K,1%,1/16W,CHIP,B!!!F1122!B!!!!
S!VR_PVDDQ_KLM_XADDR1!R1B12!1!@baseboard_fab2_lib.baseboard_fab2(sch_1):page226_i78@mstr_discrete.res(chips)!RES_0402-3.16K,1%,1/16W,CHIP,GA!!!F780!A!!!!
S!GND!R1B12!2!@baseboard_fab2_lib.baseboard_fab2(sch_1):page226_i78@mstr_discrete.res(chips)!RES_0402-3.16K,1%,1/16W,CHIP,GA!!!F780!B!!!!
S!VR_PVCCIO_CPU0_XADDR1!R3N31!1!@baseboard_fab2_lib.baseboard_fab2(sch_1):page211_i52@mstr_discrete.res(chips)!RES_0402-3.16K,1%,1/16W,CHIP,GA!!!F779!A!!!!
S!GND!R3N31!2!@baseboard_fab2_lib.baseboard_fab2(sch_1):page211_i52@mstr_discrete.res(chips)!RES_0402-3.16K,1%,1/16W,CHIP,GA!!!F779!B!!!!
S!VR_PVCCIO_CPU1_XADDR1!R4D64!1!@baseboard_fab2_lib.baseboard_fab2(sch_1):page213_i42@mstr_discrete.res(chips)!RES_0402-3.16K,1%,1/16W,CHIP,GA!!!F778!A!!!!
S!GND!R4D64!2!@baseboard_fab2_lib.baseboard_fab2(sch_1):page213_i42@mstr_discrete.res(chips)!RES_0402-3.16K,1%,1/16W,CHIP,GA!!!F778!B!!!!
S!VR_PVCCIO_CPU1_XADDR2!R4E2!1!@baseboard_fab2_lib.baseboard_fab2(sch_1):page213_i65@mstr_discrete.res(chips)!RES_0402-3.16K,1%,1/16W,CHIP,GA!!!F777!A!!!!
S!GND!R4E2!2!@baseboard_fab2_lib.baseboard_fab2(sch_1):page213_i65@mstr_discrete.res(chips)!RES_0402-3.16K,1%,1/16W,CHIP,GA!!!F777!B!!!!
S!VR_PVDDQ_DEF_XADDR1!R7A10!1!@baseboard_fab2_lib.baseboard_fab2(sch_1):page218_i40@mstr_discrete.res(chips)!RES_0402-3.16K,1%,1/16W,CHIP,GA!!!F776!A!!!!
S!GND!R7A10!2!@baseboard_fab2_lib.baseboard_fab2(sch_1):page218_i40@mstr_discrete.res(chips)!RES_0402-3.16K,1%,1/16W,CHIP,GA!!!F776!B!!!!
S!VR_PVCCIN_CPU1_XADDR2!R9N7!1!@baseboard_fab2_lib.baseboard_fab2(sch_1):page206_i111@mstr_discrete.res(chips)!RES_0402-3.16K,1%,1/16W,CHIP,GA!!!F775!A!!!!
S!GND!R9N7!2!@baseboard_fab2_lib.baseboard_fab2(sch_1):page206_i111@mstr_discrete.res(chips)!RES_0402-3.16K,1%,1/16W,CHIP,GA!!!F775!B!!!!
S!VR_PVCCMCP_CPU1_XADDR2!R4C11!1!@baseboard_fab2_lib.baseboard_fab2(sch_1):page193_i170@mstr_discrete.res(chips)!RES_0402-3.16K,1%,1/16W,CHIP,GA!!!F774!A!!!!
S!GND!R4C11!2!@baseboard_fab2_lib.baseboard_fab2(sch_1):page193_i170@mstr_discrete.res(chips)!RES_0402-3.16K,1%,1/16W,CHIP,GA!!!F774!B!!!!
S!XDP_DEBUG_CONSENT_N!J9A3!1!@baseboard_fab2_lib.baseboard_fab2(sch_1):page111_i26@mstr_sconn.sconn60_c21100002(chips)!SCONN60_C21100002_SMLF-CONN,C2A!!!F135!IO1!!!!
S!TP_XDP_CPU_OBSDATA_C0!J9A3!10!@baseboard_fab2_lib.baseboard_fab2(sch_1):page111_i26@mstr_sconn.sconn60_c21100002(chips)!SCONN60_C21100002_SMLF-CONN,C2A!!!F135!IO10!!!!
S!TP_XDP_OBSDATA_A1!J9A3!11!@baseboard_fab2_lib.baseboard_fab2(sch_1):page111_i26@mstr_sconn.sconn60_c21100002(chips)!SCONN60_C21100002_SMLF-CONN,C2A!!!F135!IO11!!!!
S!TP_XDP_CPU_OBSDATA_C1!J9A3!12!@baseboard_fab2_lib.baseboard_fab2(sch_1):page111_i26@mstr_sconn.sconn60_c21100002(chips)!SCONN60_C21100002_SMLF-CONN,C2A!!!F135!IO12!!!!
S!GND!J9A3!13!@baseboard_fab2_lib.baseboard_fab2(sch_1):page111_i26@mstr_sconn.sconn60_c21100002(chips)!SCONN60_C21100002_SMLF-CONN,C2A!!!F135!IO13!!!!
S!GND!J9A3!14!@baseboard_fab2_lib.baseboard_fab2(sch_1):page111_i26@mstr_sconn.sconn60_c21100002(chips)!SCONN60_C21100002_SMLF-CONN,C2A!!!F135!IO14!!!!
S!TP_XDP_OBSDATA_A2!J9A3!15!@baseboard_fab2_lib.baseboard_fab2(sch_1):page111_i26@mstr_sconn.sconn60_c21100002(chips)!SCONN60_C21100002_SMLF-CONN,C2A!!!F135!IO15!!!!
S!TP_XDP_CPU_OBSDATA_C2!J9A3!16!@baseboard_fab2_lib.baseboard_fab2(sch_1):page111_i26@mstr_sconn.sconn60_c21100002(chips)!SCONN60_C21100002_SMLF-CONN,C2A!!!F135!IO16!!!!
S!TP_XDP_OBSDATA_A3!J9A3!17!@baseboard_fab2_lib.baseboard_fab2(sch_1):page111_i26@mstr_sconn.sconn60_c21100002(chips)!SCONN60_C21100002_SMLF-CONN,C2A!!!F135!IO17!!!!
S!TP_XDP_CPU_OBSDATA_C3!J9A3!18!@baseboard_fab2_lib.baseboard_fab2(sch_1):page111_i26@mstr_sconn.sconn60_c21100002(chips)!SCONN60_C21100002_SMLF-CONN,C2A!!!F135!IO18!!!!
S!GND!J9A3!19!@baseboard_fab2_lib.baseboard_fab2(sch_1):page111_i26@mstr_sconn.sconn60_c21100002(chips)!SCONN60_C21100002_SMLF-CONN,C2A!!!F135!IO19!!!!
S!GND!J9A3!2!@baseboard_fab2_lib.baseboard_fab2(sch_1):page111_i26@mstr_sconn.sconn60_c21100002(chips)!SCONN60_C21100002_SMLF-CONN,C2A!!!F135!IO2!!!!
S!GND!J9A3!20!@baseboard_fab2_lib.baseboard_fab2(sch_1):page111_i26@mstr_sconn.sconn60_c21100002(chips)!SCONN60_C21100002_SMLF-CONN,C2A!!!F135!IO20!!!!
S!TP_XDP_OBSFN_B0!J9A3!21!@baseboard_fab2_lib.baseboard_fab2(sch_1):page111_i26@mstr_sconn.sconn60_c21100002(chips)!SCONN60_C21100002_SMLF-CONN,C2A!!!F135!IO21!!!!
S!XDP_OBSFN_B0_MBP6_N!J9A3!22!@baseboard_fab2_lib.baseboard_fab2(sch_1):page111_i26@mstr_sconn.sconn60_c21100002(chips)!SCONN60_C21100002_SMLF-CONN,C2A!!!F135!IO22!!!!
S!TP_XDP_OBSFN_B1!J9A3!23!@baseboard_fab2_lib.baseboard_fab2(sch_1):page111_i26@mstr_sconn.sconn60_c21100002(chips)!SCONN60_C21100002_SMLF-CONN,C2A!!!F135!IO23!!!!
S!XDP_OBSFN_B1_MBP7_N!J9A3!24!@baseboard_fab2_lib.baseboard_fab2(sch_1):page111_i26@mstr_sconn.sconn60_c21100002(chips)!SCONN60_C21100002_SMLF-CONN,C2A!!!F135!IO24!!!!
S!GND!J9A3!25!@baseboard_fab2_lib.baseboard_fab2(sch_1):page111_i26@mstr_sconn.sconn60_c21100002(chips)!SCONN60_C21100002_SMLF-CONN,C2A!!!F135!IO25!!!!
S!GND!J9A3!26!@baseboard_fab2_lib.baseboard_fab2(sch_1):page111_i26@mstr_sconn.sconn60_c21100002(chips)!SCONN60_C21100002_SMLF-CONN,C2A!!!F135!IO26!!!!
S!TP_XDP_OBSDATA_B0!J9A3!27!@baseboard_fab2_lib.baseboard_fab2(sch_1):page111_i26@mstr_sconn.sconn60_c21100002(chips)!SCONN60_C21100002_SMLF-CONN,C2A!!!F135!IO27!!!!
S!TP_XDP_CPU_OBSDATA_D0!J9A3!28!@baseboard_fab2_lib.baseboard_fab2(sch_1):page111_i26@mstr_sconn.sconn60_c21100002(chips)!SCONN60_C21100002_SMLF-CONN,C2A!!!F135!IO28!!!!
S!TP_XDP_OBSDATA_B1!J9A3!29!@baseboard_fab2_lib.baseboard_fab2(sch_1):page111_i26@mstr_sconn.sconn60_c21100002(chips)!SCONN60_C21100002_SMLF-CONN,C2A!!!F135!IO29!!!!
S!XDP_PREQ_N!J9A3!3!@baseboard_fab2_lib.baseboard_fab2(sch_1):page111_i26@mstr_sconn.sconn60_c21100002(chips)!SCONN60_C21100002_SMLF-CONN,C2A!!!F135!IO3!!!!
S!TP_XDP_CPU_OBSDATA_D1!J9A3!30!@baseboard_fab2_lib.baseboard_fab2(sch_1):page111_i26@mstr_sconn.sconn60_c21100002(chips)!SCONN60_C21100002_SMLF-CONN,C2A!!!F135!IO30!!!!
S!GND!J9A3!31!@baseboard_fab2_lib.baseboard_fab2(sch_1):page111_i26@mstr_sconn.sconn60_c21100002(chips)!SCONN60_C21100002_SMLF-CONN,C2A!!!F135!IO31!!!!
S!GND!J9A3!32!@baseboard_fab2_lib.baseboard_fab2(sch_1):page111_i26@mstr_sconn.sconn60_c21100002(chips)!SCONN60_C21100002_SMLF-CONN,C2A!!!F135!IO32!!!!
S!TP_XDP_OBSDATA_B2!J9A3!33!@baseboard_fab2_lib.baseboard_fab2(sch_1):page111_i26@mstr_sconn.sconn60_c21100002(chips)!SCONN60_C21100002_SMLF-CONN,C2A!!!F135!IO33!!!!
S!TP_XDP_CPU_OBSDATA_D2!J9A3!34!@baseboard_fab2_lib.baseboard_fab2(sch_1):page111_i26@mstr_sconn.sconn60_c21100002(chips)!SCONN60_C21100002_SMLF-CONN,C2A!!!F135!IO34!!!!
S!TP_XDP_OBSDATA_B3!J9A3!35!@baseboard_fab2_lib.baseboard_fab2(sch_1):page111_i26@mstr_sconn.sconn60_c21100002(chips)!SCONN60_C21100002_SMLF-CONN,C2A!!!F135!IO35!!!!
S!TP_XDP_CPU_OBSDATA_D3!J9A3!36!@baseboard_fab2_lib.baseboard_fab2(sch_1):page111_i26@mstr_sconn.sconn60_c21100002(chips)!SCONN60_C21100002_SMLF-CONN,C2A!!!F135!IO36!!!!
S!GND!J9A3!37!@baseboard_fab2_lib.baseboard_fab2(sch_1):page111_i26@mstr_sconn.sconn60_c21100002(chips)!SCONN60_C21100002_SMLF-CONN,C2A!!!F135!IO37!!!!
S!GND!J9A3!38!@baseboard_fab2_lib.baseboard_fab2(sch_1):page111_i26@mstr_sconn.sconn60_c21100002(chips)!SCONN60_C21100002_SMLF-CONN,C2A!!!F135!IO38!!!!
S!XDP_RSMRST_N!J9A3!39!@baseboard_fab2_lib.baseboard_fab2(sch_1):page111_i26@mstr_sconn.sconn60_c21100002(chips)!SCONN60_C21100002_SMLF-CONN,C2A!!!F135!IO39!!!!
S!TP_XDP_CPU_OBSFN_C0!J9A3!4!@baseboard_fab2_lib.baseboard_fab2(sch_1):page111_i26@mstr_sconn.sconn60_c21100002(chips)!SCONN60_C21100002_SMLF-CONN,C2A!!!F135!IO4!!!!
S!CLK_100M_PCH_XDP_DP!J9A3!40!@baseboard_fab2_lib.baseboard_fab2(sch_1):page111_i26@mstr_sconn.sconn60_c21100002(chips)!SCONN60_C21100002_SMLF-CONN,C2A!!!F135!IO40!!!!
S!XDP_PWRGD_RST_N!J9A3!41!@baseboard_fab2_lib.baseboard_fab2(sch_1):page111_i26@mstr_sconn.sconn60_c21100002(chips)!SCONN60_C21100002_SMLF-CONN,C2A!!!F135!IO41!!!!
S!CLK_100M_PCH_XDP_DN!J9A3!42!@baseboard_fab2_lib.baseboard_fab2(sch_1):page111_i26@mstr_sconn.sconn60_c21100002(chips)!SCONN60_C21100002_SMLF-CONN,C2A!!!F135!IO42!!!!
S!P1V05_PCH_STBY!J9A3!43!@baseboard_fab2_lib.baseboard_fab2(sch_1):page111_i26@mstr_sconn.sconn60_c21100002(chips)!SCONN60_C21100002_SMLF-CONN,C2A!!!F135!IO43!!!!
S!P1V05_PCH_STBY!J9A3!44!@baseboard_fab2_lib.baseboard_fab2(sch_1):page111_i26@mstr_sconn.sconn60_c21100002(chips)!SCONN60_C21100002_SMLF-CONN,C2A!!!F135!IO44!!!!
S!XDP_CPU_PWR_DEBUG_N!J9A3!45!@baseboard_fab2_lib.baseboard_fab2(sch_1):page111_i26@mstr_sconn.sconn60_c21100002(chips)!SCONN60_C21100002_SMLF-CONN,C2A!!!F135!IO45!!!!
S!XDP_ITP_PMODE!J9A3!46!@baseboard_fab2_lib.baseboard_fab2(sch_1):page111_i26@mstr_sconn.sconn60_c21100002(chips)!SCONN60_C21100002_SMLF-CONN,C2A!!!F135!IO46!!!!
S!XDP_SYSPWROK!J9A3!47!@baseboard_fab2_lib.baseboard_fab2(sch_1):page111_i26@mstr_sconn.sconn60_c21100002(chips)!SCONN60_C21100002_SMLF-CONN,C2A!!!F135!IO47!!!!
S!XDP_RST_CO_N!J9A3!48!@baseboard_fab2_lib.baseboard_fab2(sch_1):page111_i26@mstr_sconn.sconn60_c21100002(chips)!SCONN60_C21100002_SMLF-CONN,C2A!!!F135!IO48!!!!
S!GND!J9A3!49!@baseboard_fab2_lib.baseboard_fab2(sch_1):page111_i26@mstr_sconn.sconn60_c21100002(chips)!SCONN60_C21100002_SMLF-CONN,C2A!!!F135!IO49!!!!
S!XDP_PRDY_N!J9A3!5!@baseboard_fab2_lib.baseboard_fab2(sch_1):page111_i26@mstr_sconn.sconn60_c21100002(chips)!SCONN60_C21100002_SMLF-CONN,C2A!!!F135!IO5!!!!
S!GND!J9A3!50!@baseboard_fab2_lib.baseboard_fab2(sch_1):page111_i26@mstr_sconn.sconn60_c21100002(chips)!SCONN60_C21100002_SMLF-CONN,C2A!!!F135!IO50!!!!
S!SMB_HOST_STBY_LVC3_SDA!J9A3!51!@baseboard_fab2_lib.baseboard_fab2(sch_1):page111_i26@mstr_sconn.sconn60_c21100002(chips)!SCONN60_C21100002_SMLF-CONN,C2A!!!F135!IO51!!!!
S!XDP_TDO!J9A3!52!@baseboard_fab2_lib.baseboard_fab2(sch_1):page111_i26@mstr_sconn.sconn60_c21100002(chips)!SCONN60_C21100002_SMLF-CONN,C2A!!!F135!IO52!!!!
S!SMB_HOST_STBY_LVC3_SCL!J9A3!53!@baseboard_fab2_lib.baseboard_fab2(sch_1):page111_i26@mstr_sconn.sconn60_c21100002(chips)!SCONN60_C21100002_SMLF-CONN,C2A!!!F135!IO53!!!!
S!XDP_TRST_N!J9A3!54!@baseboard_fab2_lib.baseboard_fab2(sch_1):page111_i26@mstr_sconn.sconn60_c21100002(chips)!SCONN60_C21100002_SMLF-CONN,C2A!!!F135!IO54!!!!
S!XDP_PCH_TCK1!J9A3!55!@baseboard_fab2_lib.baseboard_fab2(sch_1):page111_i26@mstr_sconn.sconn60_c21100002(chips)!SCONN60_C21100002_SMLF-CONN,C2A!!!F135!IO55!!!!
S!XDP_TDI!J9A3!56!@baseboard_fab2_lib.baseboard_fab2(sch_1):page111_i26@mstr_sconn.sconn60_c21100002(chips)!SCONN60_C21100002_SMLF-CONN,C2A!!!F135!IO56!!!!
S!XDP_CPU_TCK0!J9A3!57!@baseboard_fab2_lib.baseboard_fab2(sch_1):page111_i26@mstr_sconn.sconn60_c21100002(chips)!SCONN60_C21100002_SMLF-CONN,C2A!!!F135!IO57!!!!
S!XDP_TMS!J9A3!58!@baseboard_fab2_lib.baseboard_fab2(sch_1):page111_i26@mstr_sconn.sconn60_c21100002(chips)!SCONN60_C21100002_SMLF-CONN,C2A!!!F135!IO58!!!!
S!GND!J9A3!59!@baseboard_fab2_lib.baseboard_fab2(sch_1):page111_i26@mstr_sconn.sconn60_c21100002(chips)!SCONN60_C21100002_SMLF-CONN,C2A!!!F135!IO59!!!!
S!XDP_SPI_PCH_MOSI_BOOT_HALT_N!J9A3!6!@baseboard_fab2_lib.baseboard_fab2(sch_1):page111_i26@mstr_sconn.sconn60_c21100002(chips)!SCONN60_C21100002_SMLF-CONN,C2A!!!F135!IO6!!!!
S!XDP_PRESENT_N!J9A3!60!@baseboard_fab2_lib.baseboard_fab2(sch_1):page111_i26@mstr_sconn.sconn60_c21100002(chips)!SCONN60_C21100002_SMLF-CONN,C2A!!!F135!IO60!!!!
S!GND!J9A3!7!@baseboard_fab2_lib.baseboard_fab2(sch_1):page111_i26@mstr_sconn.sconn60_c21100002(chips)!SCONN60_C21100002_SMLF-CONN,C2A!!!F135!IO7!!!!
S!GND!J9A3!8!@baseboard_fab2_lib.baseboard_fab2(sch_1):page111_i26@mstr_sconn.sconn60_c21100002(chips)!SCONN60_C21100002_SMLF-CONN,C2A!!!F135!IO8!!!!
S!TP_XDP_OBSDATA_A0!J9A3!9!@baseboard_fab2_lib.baseboard_fab2(sch_1):page111_i26@mstr_sconn.sconn60_c21100002(chips)!SCONN60_C21100002_SMLF-CONN,C2A!!!F135!IO9!!!!
S!SPI_BMC_BT_CLK!U8F2!16!@baseboard_fab2_lib.baseboard_fab2(sch_1):page162_i32@mstr_memory.w25q128(chips)!W25Q128_SKT16-IC,H12709-001!!!F3!CLK!!!!
S!SPI_BMC_BT_CS_N!U8F2!7!@baseboard_fab2_lib.baseboard_fab2(sch_1):page162_i32@mstr_memory.w25q128(chips)!W25Q128_SKT16-IC,H12709-001!!!F3!CS_N!!!!
S!SPI_BMC_BT_DO!U8F2!15!@baseboard_fab2_lib.baseboard_fab2(sch_1):page162_i32@mstr_memory.w25q128(chips)!W25Q128_SKT16-IC,H12709-001!!!F3!DI_IO(0)!!!!
S!SPI_BMC_BT_DI_R!U8F2!8!@baseboard_fab2_lib.baseboard_fab2(sch_1):page162_i32@mstr_memory.w25q128(chips)!W25Q128_SKT16-IC,H12709-001!!!F3!DO_IO(1)!!!!
S!GND!U8F2!10!@baseboard_fab2_lib.baseboard_fab2(sch_1):page162_i32@mstr_memory.w25q128(chips)!W25Q128_SKT16-IC,H12709-001!!!F3!GND!!!!
S!PU_SPI_BMC_BT_HOLD_N!U8F2!1!@baseboard_fab2_lib.baseboard_fab2(sch_1):page162_i32@mstr_memory.w25q128(chips)!W25Q128_SKT16-IC,H12709-001!!!F3!HOLD_N_IO(3)!!!!
S!TP_SPI_2_0!U8F2!4!@baseboard_fab2_lib.baseboard_fab2(sch_1):page162_i32@mstr_memory.w25q128(chips)!W25Q128_SKT16-IC,H12709-001!!!F3!NC(0)!!!!
S!TP_SPI_2_1!U8F2!5!@baseboard_fab2_lib.baseboard_fab2(sch_1):page162_i32@mstr_memory.w25q128(chips)!W25Q128_SKT16-IC,H12709-001!!!F3!NC(1)!!!!
S!TP_SPI_2_2!U8F2!6!@baseboard_fab2_lib.baseboard_fab2(sch_1):page162_i32@mstr_memory.w25q128(chips)!W25Q128_SKT16-IC,H12709-001!!!F3!NC(2)!!!!
S!TP_SPI_2_3!U8F2!11!@baseboard_fab2_lib.baseboard_fab2(sch_1):page162_i32@mstr_memory.w25q128(chips)!W25Q128_SKT16-IC,H12709-001!!!F3!NC(3)!!!!
S!TP_SPI_2_4!U8F2!12!@baseboard_fab2_lib.baseboard_fab2(sch_1):page162_i32@mstr_memory.w25q128(chips)!W25Q128_SKT16-IC,H12709-001!!!F3!NC(4)!!!!
S!TP_SPI_2_5!U8F2!13!@baseboard_fab2_lib.baseboard_fab2(sch_1):page162_i32@mstr_memory.w25q128(chips)!W25Q128_SKT16-IC,H12709-001!!!F3!NC(5)!!!!
S!TP_SPI_2_6!U8F2!14!@baseboard_fab2_lib.baseboard_fab2(sch_1):page162_i32@mstr_memory.w25q128(chips)!W25Q128_SKT16-IC,H12709-001!!!F3!NC(6)!!!!
S!PU_SPI_FLASH_RESET_2_N!U8F2!3!@baseboard_fab2_lib.baseboard_fab2(sch_1):page162_i32@mstr_memory.w25q128(chips)!W25Q128_SKT16-IC,H12709-001!!!F3!RESET_N!!!!
S!P3V3_STBY!U8F2!2!@baseboard_fab2_lib.baseboard_fab2(sch_1):page162_i32@mstr_memory.w25q128(chips)!W25Q128_SKT16-IC,H12709-001!!!F3!VCC!!!!
S!PU_SPI_BMC_BT_WP_N!U8F2!9!@baseboard_fab2_lib.baseboard_fab2(sch_1):page162_i32@mstr_memory.w25q128(chips)!W25Q128_SKT16-IC,H12709-001!!!F3!WP_N_IO(2)!!!!
S!VR_PVCCIN_CPU1_AVINSEN!EU1C2!45!@baseboard_fab2_lib.baseboard_fab2(sch_1):page206_i130@mstr_controller.pxe1610b(chips)!PXE1610B_QFN-IC,H79206-001!!!F1973!VINSEN!!!!
S!A_TSENSE_PVCCIN_CPU1!EU1C2!43!@baseboard_fab2_lib.baseboard_fab2(sch_1):page206_i130@mstr_controller.pxe1610b(chips)!PXE1610B_QFN-IC,H79206-001!!!F1973!ATSEN!!!!
S!VSENSE_PVSA_CPU1_BVSP!EU1C2!35!@baseboard_fab2_lib.baseboard_fab2(sch_1):page206_i130@mstr_controller.pxe1610b(chips)!PXE1610B_QFN-IC,H79206-001!!!F1973!BVSEN!!!!
S!ISENSE_PVCCIN_CPU1_PH5_IMON!EU1C2!32!@baseboard_fab2_lib.baseboard_fab2(sch_1):page206_i130@mstr_controller.pxe1610b(chips)!PXE1610B_QFN-IC,H79206-001!!!F1973!AISEN5!!!!
S!VR_PVCCIN_CPU1_AIREF4!EU1C2!29!@baseboard_fab2_lib.baseboard_fab2(sch_1):page206_i130@mstr_controller.pxe1610b(chips)!PXE1610B_QFN-IC,H79206-001!!!F1973!AIREF4!!!!
S!ISENSE_PVCCIN_CPU1_PH2_IMON!EU1C2!26!@baseboard_fab2_lib.baseboard_fab2(sch_1):page206_i130@mstr_controller.pxe1610b(chips)!PXE1610B_QFN-IC,H79206-001!!!F1973!AISEN2!!!!
S!ISENSE_PVCCIN_CPU1_PH1_IMON!EU1C2!24!@baseboard_fab2_lib.baseboard_fab2(sch_1):page206_i130@mstr_controller.pxe1610b(chips)!PXE1610B_QFN-IC,H79206-001!!!F1973!AISEN1!!!!
S!VSENSE_PVCCIN_CPU1_AVSP!EU1C2!21!@baseboard_fab2_lib.baseboard_fab2(sch_1):page206_i130@mstr_controller.pxe1610b(chips)!PXE1610B_QFN-IC,H79206-001!!!F1973!AVSEN!!!!
S!TP_PVCCIN_CPU1_AISEN6!EU1C2!34!@baseboard_fab2_lib.baseboard_fab2(sch_1):page206_i130@mstr_controller.pxe1610b(chips)!PXE1610B_QFN-IC,H79206-001!!!F1973!AISEN6!!!!
S!VR_PVCCIN_CPU1_AIREF5!EU1C2!31!@baseboard_fab2_lib.baseboard_fab2(sch_1):page206_i130@mstr_controller.pxe1610b(chips)!PXE1610B_QFN-IC,H79206-001!!!F1973!AIREF5!!!!
S!ISENSE_PVCCIN_CPU1_PH3_IMON!EU1C2!28!@baseboard_fab2_lib.baseboard_fab2(sch_1):page206_i130@mstr_controller.pxe1610b(chips)!PXE1610B_QFN-IC,H79206-001!!!F1973!AISEN3!!!!
S!VR_PVCCIN_CPU1_AIREF2!EU1C2!25!@baseboard_fab2_lib.baseboard_fab2(sch_1):page206_i130@mstr_controller.pxe1610b(chips)!PXE1610B_QFN-IC,H79206-001!!!F1973!AIREF2!!!!
S!VR_PVCCIN_CPU1_AIREF1!EU1C2!23!@baseboard_fab2_lib.baseboard_fab2(sch_1):page206_i130@mstr_controller.pxe1610b(chips)!PXE1610B_QFN-IC,H79206-001!!!F1973!AIREF1!!!!
S!PU_VR_PVCCIN_CPU1_FLT1_SMBALT_N!EU1C2!20!@baseboard_fab2_lib.baseboard_fab2(sch_1):page206_i130@mstr_controller.pxe1610b(chips)!PXE1610B_QFN-IC,H79206-001!!!F1973!MP2!!!!
S!VR_PVCCIN_CPU1_PWM5!EU1C2!3!@baseboard_fab2_lib.baseboard_fab2(sch_1):page206_i130@mstr_controller.pxe1610b(chips)!PXE1610B_QFN-IC,H79206-001!!!F1973!APWM5!!!!
S!VR_PVCCIN_CPU1_PWM4!EU1C2!4!@baseboard_fab2_lib.baseboard_fab2(sch_1):page206_i130@mstr_controller.pxe1610b(chips)!PXE1610B_QFN-IC,H79206-001!!!F1973!APWM4!!!!
S!VR_PVCCIN_CPU1_PWM3!EU1C2!5!@baseboard_fab2_lib.baseboard_fab2(sch_1):page206_i130@mstr_controller.pxe1610b(chips)!PXE1610B_QFN-IC,H79206-001!!!F1973!APWM3!!!!
S!VR_PVCCIN_CPU1_PWM2!EU1C2!6!@baseboard_fab2_lib.baseboard_fab2(sch_1):page206_i130@mstr_controller.pxe1610b(chips)!PXE1610B_QFN-IC,H79206-001!!!F1973!APWM2!!!!
S!VR_PVCCIN_CPU1_PWM1!EU1C2!7!@baseboard_fab2_lib.baseboard_fab2(sch_1):page206_i130@mstr_controller.pxe1610b(chips)!PXE1610B_QFN-IC,H79206-001!!!F1973!APWM1!!!!
S!SMB_VR_SDA_R1!EU1C2!8!@baseboard_fab2_lib.baseboard_fab2(sch_1):page206_i130@mstr_controller.pxe1610b(chips)!PXE1610B_QFN-IC,H79206-001!!!F1973!SDA!!!!
S!TP_PVCCIN_CPU1_AIREF6!EU1C2!33!@baseboard_fab2_lib.baseboard_fab2(sch_1):page206_i130@mstr_controller.pxe1610b(chips)!PXE1610B_QFN-IC,H79206-001!!!F1973!AIREF6!!!!
S!VSENSE_PVSA_CPU1_N!EU1C2!36!@baseboard_fab2_lib.baseboard_fab2(sch_1):page206_i130@mstr_controller.pxe1610b(chips)!PXE1610B_QFN-IC,H79206-001!!!F1973!BVREF!!!!
S!TP_PVCCIN_CPU1_RESET_N!EU1C2!10!@baseboard_fab2_lib.baseboard_fab2(sch_1):page206_i130@mstr_controller.pxe1610b(chips)!PXE1610B_QFN-IC,H79206-001!!!F1973!RESET_N!!!!
S!SMB_VR_SCL_R1!EU1C2!9!@baseboard_fab2_lib.baseboard_fab2(sch_1):page206_i130@mstr_controller.pxe1610b(chips)!PXE1610B_QFN-IC,H79206-001!!!F1973!SCL!!!!
S!SVID_VALERT_VCCIN_CPU1!EU1C2!19!@baseboard_fab2_lib.baseboard_fab2(sch_1):page206_i130@mstr_controller.pxe1610b(chips)!PXE1610B_QFN-IC,H79206-001!!!F1973!VALRT_N!!!!
S!SVID_VDIO_PVCCIN_CPU1!EU1C2!18!@baseboard_fab2_lib.baseboard_fab2(sch_1):page206_i130@mstr_controller.pxe1610b(chips)!PXE1610B_QFN-IC,H79206-001!!!F1973!VDIO!!!!
S!TP_PVCCIN_CPU1_FAULT1_20!EU1C2!40!@baseboard_fab2_lib.baseboard_fab2(sch_1):page206_i130@mstr_controller.pxe1610b(chips)!PXE1610B_QFN-IC,H79206-001!!!F1973!MP4!!!!
S!PU_VR_PVCCIN_CPU1_IMON!EU1C2!39!@baseboard_fab2_lib.baseboard_fab2(sch_1):page206_i130@mstr_controller.pxe1610b(chips)!PXE1610B_QFN-IC,H79206-001!!!F1973!MP3!!!!
S!TP_PVCCIN_CPU1_APWM6!EU1C2!2!@baseboard_fab2_lib.baseboard_fab2(sch_1):page206_i130@mstr_controller.pxe1610b(chips)!PXE1610B_QFN-IC,H79206-001!!!F1973!APWM6!!!!
S!ISENSE_PVSA_CPU1_IMON!EU1C2!38!@baseboard_fab2_lib.baseboard_fab2(sch_1):page206_i130@mstr_controller.pxe1610b(chips)!PXE1610B_QFN-IC,H79206-001!!!F1973!BISEN1!!!!
S!VR_PVSA_CPU1_PWM!EU1C2!1!@baseboard_fab2_lib.baseboard_fab2(sch_1):page206_i130@mstr_controller.pxe1610b(chips)!PXE1610B_QFN-IC,H79206-001!!!F1973!BPWM1!!!!
S!VR_PVCCIN_CPU1_XADDR2!EU1C2!41!@baseboard_fab2_lib.baseboard_fab2(sch_1):page206_i130@mstr_controller.pxe1610b(chips)!PXE1610B_QFN-IC,H79206-001!!!F1973!XADDR2!!!!
S!A_TSENSE_PVSA_CPU1!EU1C2!42!@baseboard_fab2_lib.baseboard_fab2(sch_1):page206_i130@mstr_controller.pxe1610b(chips)!PXE1610B_QFN-IC,H79206-001!!!F1973!BTSEN!!!!
S!PVCCIN_PVSA_CPU1_IINSEN!EU1C2!46!@baseboard_fab2_lib.baseboard_fab2(sch_1):page206_i130@mstr_controller.pxe1610b(chips)!PXE1610B_QFN-IC,H79206-001!!!F1973!IINSEN!!!!
S!VR_PVCCIN_CPU1_XADDR1!EU1C2!44!@baseboard_fab2_lib.baseboard_fab2(sch_1):page206_i130@mstr_controller.pxe1610b(chips)!PXE1610B_QFN-IC,H79206-001!!!F1973!XADDR1!!!!
S!VSENSE_PVCCIN_CPU1_N!EU1C2!22!@baseboard_fab2_lib.baseboard_fab2(sch_1):page206_i130@mstr_controller.pxe1610b(chips)!PXE1610B_QFN-IC,H79206-001!!!F1973!AVREF!!!!
S!TP_PVCCIN_CPU1_GP1!EU1C2!16!@baseboard_fab2_lib.baseboard_fab2(sch_1):page206_i130@mstr_controller.pxe1610b(chips)!PXE1610B_QFN-IC,H79206-001!!!F1973!MP1!!!!
S!VR_PVCCIN_CPU1_VREN!EU1C2!12!@baseboard_fab2_lib.baseboard_fab2(sch_1):page206_i130@mstr_controller.pxe1610b(chips)!PXE1610B_QFN-IC,H79206-001!!!F1973!AVREN!!!!
S!VR_VRRDY_PVCCIN_CPU1!EU1C2!11!@baseboard_fab2_lib.baseboard_fab2(sch_1):page206_i130@mstr_controller.pxe1610b(chips)!PXE1610B_QFN-IC,H79206-001!!!F1973!AVRRDY!!!!
S!GND!EU1C2!49!@baseboard_fab2_lib.baseboard_fab2(sch_1):page206_i130@mstr_controller.pxe1610b(chips)!PXE1610B_QFN-IC,H79206-001!!!F1973!THPAD!!!!
S!SVID_VCLK_PVCCIN_CPU1!EU1C2!17!@baseboard_fab2_lib.baseboard_fab2(sch_1):page206_i130@mstr_controller.pxe1610b(chips)!PXE1610B_QFN-IC,H79206-001!!!F1973!VCLK!!!!
S!PWRGD_PVSA_CPU1_R!EU1C2!15!@baseboard_fab2_lib.baseboard_fab2(sch_1):page206_i130@mstr_controller.pxe1610b(chips)!PXE1610B_QFN-IC,H79206-001!!!F1973!MP0!!!!
S!IRQ_PVCCIN_CPU1_VRHOT_LVC3_R_N!EU1C2!13!@baseboard_fab2_lib.baseboard_fab2(sch_1):page206_i130@mstr_controller.pxe1610b(chips)!PXE1610B_QFN-IC,H79206-001!!!F1973!VRHOT_N!!!!
S!VR_PVCCIN_CPU1_VD12!EU1C2!48!@baseboard_fab2_lib.baseboard_fab2(sch_1):page206_i130@mstr_controller.pxe1610b(chips)!PXE1610B_QFN-IC,H79206-001!!!F1973!VD12!!!!
S!VR_PVSA_CPU1_BIREF1!EU1C2!37!@baseboard_fab2_lib.baseboard_fab2(sch_1):page206_i130@mstr_controller.pxe1610b(chips)!PXE1610B_QFN-IC,H79206-001!!!F1973!BIREF1!!!!
S!FM_PVCCIN_CPU1_PWR_IN_ALERT_N!EU1C2!14!@baseboard_fab2_lib.baseboard_fab2(sch_1):page206_i130@mstr_controller.pxe1610b(chips)!PXE1610B_QFN-IC,H79206-001!!!F1973!PINALRT_N!!!!
S!VR_PVCCIN_CPU1_VDD!EU1C2!47!@baseboard_fab2_lib.baseboard_fab2(sch_1):page206_i130@mstr_controller.pxe1610b(chips)!PXE1610B_QFN-IC,H79206-001!!!F1973!VDD!!!!
S!VR_PVCCIN_CPU1_AIREF3!EU1C2!27!@baseboard_fab2_lib.baseboard_fab2(sch_1):page206_i130@mstr_controller.pxe1610b(chips)!PXE1610B_QFN-IC,H79206-001!!!F1973!AIREF3!!!!
S!ISENSE_PVCCIN_CPU1_PH4_IMON!EU1C2!30!@baseboard_fab2_lib.baseboard_fab2(sch_1):page206_i130@mstr_controller.pxe1610b(chips)!PXE1610B_QFN-IC,H79206-001!!!F1973!AISEN4!!!!
S!VR_PVCCIN_CPU0_AVINSEN!EU4D4!45!@baseboard_fab2_lib.baseboard_fab2(sch_1):page201_i155@mstr_controller.pxe1610b(chips)!PXE1610B_QFN-IC,H79206-001!!!F1972!VINSEN!!!!
S!A_TSENSE_PVCCIN_CPU0!EU4D4!43!@baseboard_fab2_lib.baseboard_fab2(sch_1):page201_i155@mstr_controller.pxe1610b(chips)!PXE1610B_QFN-IC,H79206-001!!!F1972!ATSEN!!!!
S!VSENSE_PVSA_CPU0_BVSP!EU4D4!35!@baseboard_fab2_lib.baseboard_fab2(sch_1):page201_i155@mstr_controller.pxe1610b(chips)!PXE1610B_QFN-IC,H79206-001!!!F1972!BVSEN!!!!
S!ISENSE_PVCCIN_CPU0_PH5_IMON!EU4D4!32!@baseboard_fab2_lib.baseboard_fab2(sch_1):page201_i155@mstr_controller.pxe1610b(chips)!PXE1610B_QFN-IC,H79206-001!!!F1972!AISEN5!!!!
S!VR_PVCCIN_CPU0_AIREF4!EU4D4!29!@baseboard_fab2_lib.baseboard_fab2(sch_1):page201_i155@mstr_controller.pxe1610b(chips)!PXE1610B_QFN-IC,H79206-001!!!F1972!AIREF4!!!!
S!ISENSE_PVCCIN_CPU0_PH2_IMON!EU4D4!26!@baseboard_fab2_lib.baseboard_fab2(sch_1):page201_i155@mstr_controller.pxe1610b(chips)!PXE1610B_QFN-IC,H79206-001!!!F1972!AISEN2!!!!
S!ISENSE_PVCCIN_CPU0_PH1_IMON!EU4D4!24!@baseboard_fab2_lib.baseboard_fab2(sch_1):page201_i155@mstr_controller.pxe1610b(chips)!PXE1610B_QFN-IC,H79206-001!!!F1972!AISEN1!!!!
S!VSENSE_PVCCIN_CPU0_AVSP!EU4D4!21!@baseboard_fab2_lib.baseboard_fab2(sch_1):page201_i155@mstr_controller.pxe1610b(chips)!PXE1610B_QFN-IC,H79206-001!!!F1972!AVSEN!!!!
S!TP_PVCCIN_CPU0_AISEN6!EU4D4!34!@baseboard_fab2_lib.baseboard_fab2(sch_1):page201_i155@mstr_controller.pxe1610b(chips)!PXE1610B_QFN-IC,H79206-001!!!F1972!AISEN6!!!!
S!VR_PVCCIN_CPU0_AIREF5!EU4D4!31!@baseboard_fab2_lib.baseboard_fab2(sch_1):page201_i155@mstr_controller.pxe1610b(chips)!PXE1610B_QFN-IC,H79206-001!!!F1972!AIREF5!!!!
S!ISENSE_PVCCIN_CPU0_PH3_IMON!EU4D4!28!@baseboard_fab2_lib.baseboard_fab2(sch_1):page201_i155@mstr_controller.pxe1610b(chips)!PXE1610B_QFN-IC,H79206-001!!!F1972!AISEN3!!!!
S!VR_PVCCIN_CPU0_AIREF2!EU4D4!25!@baseboard_fab2_lib.baseboard_fab2(sch_1):page201_i155@mstr_controller.pxe1610b(chips)!PXE1610B_QFN-IC,H79206-001!!!F1972!AIREF2!!!!
S!VR_PVCCIN_CPU0_AIREF1!EU4D4!23!@baseboard_fab2_lib.baseboard_fab2(sch_1):page201_i155@mstr_controller.pxe1610b(chips)!PXE1610B_QFN-IC,H79206-001!!!F1972!AIREF1!!!!
S!PU_VR_PVCCIN_CPU0_FLT1_SMBALT_N!EU4D4!20!@baseboard_fab2_lib.baseboard_fab2(sch_1):page201_i155@mstr_controller.pxe1610b(chips)!PXE1610B_QFN-IC,H79206-001!!!F1972!MP2!!!!
S!VR_PVCCIN_CPU0_PWM5!EU4D4!3!@baseboard_fab2_lib.baseboard_fab2(sch_1):page201_i155@mstr_controller.pxe1610b(chips)!PXE1610B_QFN-IC,H79206-001!!!F1972!APWM5!!!!
S!VR_PVCCIN_CPU0_PWM4!EU4D4!4!@baseboard_fab2_lib.baseboard_fab2(sch_1):page201_i155@mstr_controller.pxe1610b(chips)!PXE1610B_QFN-IC,H79206-001!!!F1972!APWM4!!!!
S!VR_PVCCIN_CPU0_PWM3!EU4D4!5!@baseboard_fab2_lib.baseboard_fab2(sch_1):page201_i155@mstr_controller.pxe1610b(chips)!PXE1610B_QFN-IC,H79206-001!!!F1972!APWM3!!!!
S!VR_PVCCIN_CPU0_PWM2!EU4D4!6!@baseboard_fab2_lib.baseboard_fab2(sch_1):page201_i155@mstr_controller.pxe1610b(chips)!PXE1610B_QFN-IC,H79206-001!!!F1972!APWM2!!!!
S!VR_PVCCIN_CPU0_PWM1!EU4D4!7!@baseboard_fab2_lib.baseboard_fab2(sch_1):page201_i155@mstr_controller.pxe1610b(chips)!PXE1610B_QFN-IC,H79206-001!!!F1972!APWM1!!!!
S!SMB_VR_SDA_R!EU4D4!8!@baseboard_fab2_lib.baseboard_fab2(sch_1):page201_i155@mstr_controller.pxe1610b(chips)!PXE1610B_QFN-IC,H79206-001!!!F1972!SDA!!!!
S!TP_PVCCIN_CPU0_AIREF6!EU4D4!33!@baseboard_fab2_lib.baseboard_fab2(sch_1):page201_i155@mstr_controller.pxe1610b(chips)!PXE1610B_QFN-IC,H79206-001!!!F1972!AIREF6!!!!
S!VSENSE_PVSA_CPU0_N!EU4D4!36!@baseboard_fab2_lib.baseboard_fab2(sch_1):page201_i155@mstr_controller.pxe1610b(chips)!PXE1610B_QFN-IC,H79206-001!!!F1972!BVREF!!!!
S!TP_PVCCIN_CPU0_RESET!EU4D4!10!@baseboard_fab2_lib.baseboard_fab2(sch_1):page201_i155@mstr_controller.pxe1610b(chips)!PXE1610B_QFN-IC,H79206-001!!!F1972!RESET_N!!!!
S!SMB_VR_SCL_R!EU4D4!9!@baseboard_fab2_lib.baseboard_fab2(sch_1):page201_i155@mstr_controller.pxe1610b(chips)!PXE1610B_QFN-IC,H79206-001!!!F1972!SCL!!!!
S!SVID_VALERT_VCCIN_CPU0!EU4D4!19!@baseboard_fab2_lib.baseboard_fab2(sch_1):page201_i155@mstr_controller.pxe1610b(chips)!PXE1610B_QFN-IC,H79206-001!!!F1972!VALRT_N!!!!
S!SVID_VDIO_PVCCIN_CPU0!EU4D4!18!@baseboard_fab2_lib.baseboard_fab2(sch_1):page201_i155@mstr_controller.pxe1610b(chips)!PXE1610B_QFN-IC,H79206-001!!!F1972!VDIO!!!!
S!TP_PVCCIN_CPU0_FAULT1_20!EU4D4!40!@baseboard_fab2_lib.baseboard_fab2(sch_1):page201_i155@mstr_controller.pxe1610b(chips)!PXE1610B_QFN-IC,H79206-001!!!F1972!MP4!!!!
S!PU_VR_PVCCIN_CPU0_IMON!EU4D4!39!@baseboard_fab2_lib.baseboard_fab2(sch_1):page201_i155@mstr_controller.pxe1610b(chips)!PXE1610B_QFN-IC,H79206-001!!!F1972!MP3!!!!
S!TP_PVCCIN_CPU0_APWM6!EU4D4!2!@baseboard_fab2_lib.baseboard_fab2(sch_1):page201_i155@mstr_controller.pxe1610b(chips)!PXE1610B_QFN-IC,H79206-001!!!F1972!APWM6!!!!
S!ISENSE_PVSA_CPU0_IMON!EU4D4!38!@baseboard_fab2_lib.baseboard_fab2(sch_1):page201_i155@mstr_controller.pxe1610b(chips)!PXE1610B_QFN-IC,H79206-001!!!F1972!BISEN1!!!!
S!VR_PVSA_CPU0_PWM!EU4D4!1!@baseboard_fab2_lib.baseboard_fab2(sch_1):page201_i155@mstr_controller.pxe1610b(chips)!PXE1610B_QFN-IC,H79206-001!!!F1972!BPWM1!!!!
S!VR_PVCCIN_CPU0_XADDR2!EU4D4!41!@baseboard_fab2_lib.baseboard_fab2(sch_1):page201_i155@mstr_controller.pxe1610b(chips)!PXE1610B_QFN-IC,H79206-001!!!F1972!XADDR2!!!!
S!A_TSENSE_PVSA_CPU0!EU4D4!42!@baseboard_fab2_lib.baseboard_fab2(sch_1):page201_i155@mstr_controller.pxe1610b(chips)!PXE1610B_QFN-IC,H79206-001!!!F1972!BTSEN!!!!
S!PVCCIN_PVSA_CPU0_IINSEN!EU4D4!46!@baseboard_fab2_lib.baseboard_fab2(sch_1):page201_i155@mstr_controller.pxe1610b(chips)!PXE1610B_QFN-IC,H79206-001!!!F1972!IINSEN!!!!
S!VR_PVCCIN_CPU0_XADDR1!EU4D4!44!@baseboard_fab2_lib.baseboard_fab2(sch_1):page201_i155@mstr_controller.pxe1610b(chips)!PXE1610B_QFN-IC,H79206-001!!!F1972!XADDR1!!!!
S!VSENSE_PVCCIN_CPU0_N!EU4D4!22!@baseboard_fab2_lib.baseboard_fab2(sch_1):page201_i155@mstr_controller.pxe1610b(chips)!PXE1610B_QFN-IC,H79206-001!!!F1972!AVREF!!!!
S!TP_PVCCIN_CPU0_GP1!EU4D4!16!@baseboard_fab2_lib.baseboard_fab2(sch_1):page201_i155@mstr_controller.pxe1610b(chips)!PXE1610B_QFN-IC,H79206-001!!!F1972!MP1!!!!
S!VR_PVCCIN_CPU0_VREN!EU4D4!12!@baseboard_fab2_lib.baseboard_fab2(sch_1):page201_i155@mstr_controller.pxe1610b(chips)!PXE1610B_QFN-IC,H79206-001!!!F1972!AVREN!!!!
S!VR_VRRDY_PVCCIN_CPU0!EU4D4!11!@baseboard_fab2_lib.baseboard_fab2(sch_1):page201_i155@mstr_controller.pxe1610b(chips)!PXE1610B_QFN-IC,H79206-001!!!F1972!AVRRDY!!!!
S!GND!EU4D4!49!@baseboard_fab2_lib.baseboard_fab2(sch_1):page201_i155@mstr_controller.pxe1610b(chips)!PXE1610B_QFN-IC,H79206-001!!!F1972!THPAD!!!!
S!SVID_VCLK_PVCCIN_CPU0!EU4D4!17!@baseboard_fab2_lib.baseboard_fab2(sch_1):page201_i155@mstr_controller.pxe1610b(chips)!PXE1610B_QFN-IC,H79206-001!!!F1972!VCLK!!!!
S!PWRGD_PVSA_CPU0_R!EU4D4!15!@baseboard_fab2_lib.baseboard_fab2(sch_1):page201_i155@mstr_controller.pxe1610b(chips)!PXE1610B_QFN-IC,H79206-001!!!F1972!MP0!!!!
S!IRQ_PVCCIN_CPU0_VRHOT_LVC3_R_N!EU4D4!13!@baseboard_fab2_lib.baseboard_fab2(sch_1):page201_i155@mstr_controller.pxe1610b(chips)!PXE1610B_QFN-IC,H79206-001!!!F1972!VRHOT_N!!!!
S!VR_PVCCIN_CPU0_VD12!EU4D4!48!@baseboard_fab2_lib.baseboard_fab2(sch_1):page201_i155@mstr_controller.pxe1610b(chips)!PXE1610B_QFN-IC,H79206-001!!!F1972!VD12!!!!
S!VR_PVSA_CPU0_BIREF1!EU4D4!37!@baseboard_fab2_lib.baseboard_fab2(sch_1):page201_i155@mstr_controller.pxe1610b(chips)!PXE1610B_QFN-IC,H79206-001!!!F1972!BIREF1!!!!
S!FM_PVCCIN_CPU0_PWR_IN_ALERT_N!EU4D4!14!@baseboard_fab2_lib.baseboard_fab2(sch_1):page201_i155@mstr_controller.pxe1610b(chips)!PXE1610B_QFN-IC,H79206-001!!!F1972!PINALRT_N!!!!
S!VR_PVCCIN_CPU0_VDD!EU4D4!47!@baseboard_fab2_lib.baseboard_fab2(sch_1):page201_i155@mstr_controller.pxe1610b(chips)!PXE1610B_QFN-IC,H79206-001!!!F1972!VDD!!!!
S!VR_PVCCIN_CPU0_AIREF3!EU4D4!27!@baseboard_fab2_lib.baseboard_fab2(sch_1):page201_i155@mstr_controller.pxe1610b(chips)!PXE1610B_QFN-IC,H79206-001!!!F1972!AIREF3!!!!
S!ISENSE_PVCCIN_CPU0_PH4_IMON!EU4D4!30!@baseboard_fab2_lib.baseboard_fab2(sch_1):page201_i155@mstr_controller.pxe1610b(chips)!PXE1610B_QFN-IC,H79206-001!!!F1972!AISEN4!!!!
S!A_PG_P12V_MAIN!R8D40!1!@baseboard_fab2_lib.baseboard_fab2(sch_1):page196_i113@mstr_discrete.res(chips)!RES_0402-3.74K,1%,1/16W,CHIP,GA!!!F760!A!!!!
S!GND!R8D40!2!@baseboard_fab2_lib.baseboard_fab2(sch_1):page196_i113@mstr_discrete.res(chips)!RES_0402-3.74K,1%,1/16W,CHIP,GA!!!F760!B!!!!
S!JTAG_MCP_TCK_R!J9B4!1!@baseboard_fab2_lib.baseboard_fab2(sch_1):page113_i175@mstr_sconn.sconn10_c12536004(chips)!SCONN10_C12536004_SMLF-CONN,C1A!!!F242!IO1!!!!
S!GND!J9B4!10!@baseboard_fab2_lib.baseboard_fab2(sch_1):page113_i175@mstr_sconn.sconn10_c12536004(chips)!SCONN10_C12536004_SMLF-CONN,C1A!!!F242!IO10!!!!
S!GND!J9B4!2!@baseboard_fab2_lib.baseboard_fab2(sch_1):page113_i175@mstr_sconn.sconn10_c12536004(chips)!SCONN10_C12536004_SMLF-CONN,C1A!!!F242!IO2!!!!
S!JTAG_MCP_MUX_TDO!J9B4!3!@baseboard_fab2_lib.baseboard_fab2(sch_1):page113_i175@mstr_sconn.sconn10_c12536004(chips)!SCONN10_C12536004_SMLF-CONN,C1A!!!F242!IO3!!!!
S!P1V8_MCP_CPU0!J9B4!4!@baseboard_fab2_lib.baseboard_fab2(sch_1):page113_i175@mstr_sconn.sconn10_c12536004(chips)!SCONN10_C12536004_SMLF-CONN,C1A!!!F242!IO4!!!!
S!JTAG_MCP_TMS_R!J9B4!5!@baseboard_fab2_lib.baseboard_fab2(sch_1):page113_i175@mstr_sconn.sconn10_c12536004(chips)!SCONN10_C12536004_SMLF-CONN,C1A!!!F242!IO5!!!!
S!JTAG_MCP_TRST_N!J9B4!6!@baseboard_fab2_lib.baseboard_fab2(sch_1):page113_i175@mstr_sconn.sconn10_c12536004(chips)!SCONN10_C12536004_SMLF-CONN,C1A!!!F242!IO6!!!!
S!PWRGD_CPU0_G_R!J9B4!7!@baseboard_fab2_lib.baseboard_fab2(sch_1):page113_i175@mstr_sconn.sconn10_c12536004(chips)!SCONN10_C12536004_SMLF-CONN,C1A!!!F242!IO7!!!!
S!TP_JTAG_MCP_IO8_RSVD!J9B4!8!@baseboard_fab2_lib.baseboard_fab2(sch_1):page113_i175@mstr_sconn.sconn10_c12536004(chips)!SCONN10_C12536004_SMLF-CONN,C1A!!!F242!IO8!!!!
S!JTAG_MCP_MUX_TDI!J9B4!9!@baseboard_fab2_lib.baseboard_fab2(sch_1):page113_i175@mstr_sconn.sconn10_c12536004(chips)!SCONN10_C12536004_SMLF-CONN,C1A!!!F242!IO9!!!!
S!VR_PVDDQ_KLM_PH2_BOOT!C1A8!1!@baseboard_fab2_lib.baseboard_fab2(sch_1):page227_i75@mstr_discrete.cap(chips)!CAP_0402-0.220UF,16V,10%,X7R,AA!!!F4076!A!!!!
S!VR_PVDDQ_KLM_PH2_PHASE!C1A8!2!@baseboard_fab2_lib.baseboard_fab2(sch_1):page227_i75@mstr_discrete.cap(chips)!CAP_0402-0.220UF,16V,10%,X7R,AA!!!F4076!B!!!!
S!VR_PVDDQ_KLM_PH1_BOOT!C1A18!1!@baseboard_fab2_lib.baseboard_fab2(sch_1):page227_i44@mstr_discrete.cap(chips)!CAP_0402-0.220UF,16V,10%,X7R,AA!!!F4075!A!!!!
S!VR_PVDDQ_KLM_PH1_PHASE!C1A18!2!@baseboard_fab2_lib.baseboard_fab2(sch_1):page227_i44@mstr_discrete.cap(chips)!CAP_0402-0.220UF,16V,10%,X7R,AA!!!F4075!B!!!!
S!VR_PVSA_CPU1_BOOT!C1C12!1!@baseboard_fab2_lib.baseboard_fab2(sch_1):page210_i24@mstr_discrete.cap(chips)!CAP_0402-0.220UF,16V,10%,X7R,AA!!!F4074!A!!!!
S!VR_PVSA_CPU1_PHASE!C1C12!2!@baseboard_fab2_lib.baseboard_fab2(sch_1):page210_i24@mstr_discrete.cap(chips)!CAP_0402-0.220UF,16V,10%,X7R,AA!!!F4074!B!!!!
S!VR_PVCCIN_CPU1_PH5_BOOT!C1C24!1!@baseboard_fab2_lib.baseboard_fab2(sch_1):page209_i20@mstr_discrete.cap(chips)!CAP_0402-0.220UF,16V,10%,X7R,AA!!!F4073!A!!!!
S!VR_PVCCIN_CPU1_PH5_PHASE!C1C24!2!@baseboard_fab2_lib.baseboard_fab2(sch_1):page209_i20@mstr_discrete.cap(chips)!CAP_0402-0.220UF,16V,10%,X7R,AA!!!F4073!B!!!!
S!VR_PVCCIN_CPU1_PH4_BOOT!C1D10!1!@baseboard_fab2_lib.baseboard_fab2(sch_1):page208_i48@mstr_discrete.cap(chips)!CAP_0402-0.220UF,16V,10%,X7R,AA!!!F4072!A!!!!
S!VR_PVCCIN_CPU1_PH4_PHASE!C1D10!2!@baseboard_fab2_lib.baseboard_fab2(sch_1):page208_i48@mstr_discrete.cap(chips)!CAP_0402-0.220UF,16V,10%,X7R,AA!!!F4072!B!!!!
S!VR_PVCCIN_CPU1_PH3_BOOT!C1D20!1!@baseboard_fab2_lib.baseboard_fab2(sch_1):page208_i40@mstr_discrete.cap(chips)!CAP_0402-0.220UF,16V,10%,X7R,AA!!!F4071!A!!!!
S!VR_PVCCIN_CPU1_PH3_PHASE!C1D20!2!@baseboard_fab2_lib.baseboard_fab2(sch_1):page208_i40@mstr_discrete.cap(chips)!CAP_0402-0.220UF,16V,10%,X7R,AA!!!F4071!B!!!!
S!VR_PVDDQ_GHJ_PH2_BOOT!C1F26!1!@baseboard_fab2_lib.baseboard_fab2(sch_1):page224_i75@mstr_discrete.cap(chips)!CAP_0402-0.220UF,16V,10%,X7R,AA!!!F4068!A!!!!
S!VR_PVDDQ_GHJ_PH2_PHASE!C1F26!2!@baseboard_fab2_lib.baseboard_fab2(sch_1):page224_i75@mstr_discrete.cap(chips)!CAP_0402-0.220UF,16V,10%,X7R,AA!!!F4068!B!!!!
S!VR_PVDDQ_GHJ_PH1_BOOT!C1G11!1!@baseboard_fab2_lib.baseboard_fab2(sch_1):page224_i44@mstr_discrete.cap(chips)!CAP_0402-0.220UF,16V,10%,X7R,AA!!!F4067!A!!!!
S!VR_PVDDQ_GHJ_PH1_PHASE!C1G11!2!@baseboard_fab2_lib.baseboard_fab2(sch_1):page224_i44@mstr_discrete.cap(chips)!CAP_0402-0.220UF,16V,10%,X7R,AA!!!F4067!B!!!!
S!VR_PVSA_CPU0_BOOT!C4C8!1!@baseboard_fab2_lib.baseboard_fab2(sch_1):page205_i25@mstr_discrete.cap(chips)!CAP_0402-0.220UF,16V,10%,X7R,AA!!!F4066!A!!!!
S!VR_PVSA_CPU0_PHASE!C4C8!2!@baseboard_fab2_lib.baseboard_fab2(sch_1):page205_i25@mstr_discrete.cap(chips)!CAP_0402-0.220UF,16V,10%,X7R,AA!!!F4066!B!!!!
S!VR_PVCCIN_CPU0_PH5_BOOT!C4C17!1!@baseboard_fab2_lib.baseboard_fab2(sch_1):page204_i22@mstr_discrete.cap(chips)!CAP_0402-0.220UF,16V,10%,X7R,AA!!!F4065!A!!!!
S!VR_PVCCIN_CPU0_PH5_PHASE!C4C17!2!@baseboard_fab2_lib.baseboard_fab2(sch_1):page204_i22@mstr_discrete.cap(chips)!CAP_0402-0.220UF,16V,10%,X7R,AA!!!F4065!B!!!!
S!VR_PVCCIN_CPU0_PH4_BOOT!C4D9!1!@baseboard_fab2_lib.baseboard_fab2(sch_1):page203_i3@mstr_discrete.cap(chips)!CAP_0402-0.220UF,16V,10%,X7R,AA!!!F4064!A!!!!
S!VR_PVCCIN_CPU0_PH4_PHASE!C4D9!2!@baseboard_fab2_lib.baseboard_fab2(sch_1):page203_i3@mstr_discrete.cap(chips)!CAP_0402-0.220UF,16V,10%,X7R,AA!!!F4064!B!!!!
S!VR_PVCCIN_CPU0_PH3_BOOT!C4D28!1!@baseboard_fab2_lib.baseboard_fab2(sch_1):page203_i42@mstr_discrete.cap(chips)!CAP_0402-0.220UF,16V,10%,X7R,AA!!!F4063!A!!!!
S!VR_PVCCIN_CPU0_PH3_PHASE!C4D28!2!@baseboard_fab2_lib.baseboard_fab2(sch_1):page203_i42@mstr_discrete.cap(chips)!CAP_0402-0.220UF,16V,10%,X7R,AA!!!F4063!B!!!!
S!VR_PVCCIN_CPU0_PH2_BOOT!C4D50!1!@baseboard_fab2_lib.baseboard_fab2(sch_1):page202_i32@mstr_discrete.cap(chips)!CAP_0402-0.220UF,16V,10%,X7R,AA!!!F4062!A!!!!
S!VR_PVCCIN_CPU0_PH2_PHASE!C4D50!2!@baseboard_fab2_lib.baseboard_fab2(sch_1):page202_i32@mstr_discrete.cap(chips)!CAP_0402-0.220UF,16V,10%,X7R,AA!!!F4062!B!!!!
S!VR_PVCCIN_CPU0_PH1_BOOT!C4E17!1!@baseboard_fab2_lib.baseboard_fab2(sch_1):page202_i22@mstr_discrete.cap(chips)!CAP_0402-0.220UF,16V,10%,X7R,AA!!!F4061!A!!!!
S!VR_PVCCIN_CPU0_PH1_PHASE!C4E17!2!@baseboard_fab2_lib.baseboard_fab2(sch_1):page202_i22@mstr_discrete.cap(chips)!CAP_0402-0.220UF,16V,10%,X7R,AA!!!F4061!B!!!!
S!VR_PVCCIO_CPU1_PH1_BOOT!C4E18!1!@baseboard_fab2_lib.baseboard_fab2(sch_1):page214_i78@mstr_discrete.cap(chips)!CAP_0402-0.220UF,16V,10%,X7R,AA!!!F4060!A!!!!
S!VR_PVCCIO_CPU1_PH1_PHASE!C4E18!2!@baseboard_fab2_lib.baseboard_fab2(sch_1):page214_i78@mstr_discrete.cap(chips)!CAP_0402-0.220UF,16V,10%,X7R,AA!!!F4060!B!!!!
S!VR_PVNN_PCH_PH1_BOOT!C3L30!1!@baseboard_fab2_lib.baseboard_fab2(sch_1):page236_i21@mstr_discrete.cap(chips)!CAP_0402-0.220UF,16V,10%,X7R,AA!!!F4059!A!!!!
S!VR_PVNN_PCH_PH1_PHASE!C3L30!2!@baseboard_fab2_lib.baseboard_fab2(sch_1):page236_i21@mstr_discrete.cap(chips)!CAP_0402-0.220UF,16V,10%,X7R,AA!!!F4059!B!!!!
S!VR_P1V05_PCH_STBY_PH1_BOOT!C3L28!1!@baseboard_fab2_lib.baseboard_fab2(sch_1):page236_i34@mstr_discrete.cap(chips)!CAP_0402-0.220UF,16V,10%,X7R,AA!!!F4058!A!!!!
S!VR_P1V05_PCH_STBY_PH1_PHASE!C3L28!2!@baseboard_fab2_lib.baseboard_fab2(sch_1):page236_i34@mstr_discrete.cap(chips)!CAP_0402-0.220UF,16V,10%,X7R,AA!!!F4058!B!!!!
S!VR_PVDDQ_DEF_PH1_BOOT!C7A12!1!@baseboard_fab2_lib.baseboard_fab2(sch_1):page219_i44@mstr_discrete.cap(chips)!CAP_0402-0.220UF,16V,10%,X7R,AA!!!F4057!A!!!!
S!VR_PVDDQ_DEF_PH1_PHASE!C7A12!2!@baseboard_fab2_lib.baseboard_fab2(sch_1):page219_i44@mstr_discrete.cap(chips)!CAP_0402-0.220UF,16V,10%,X7R,AA!!!F4057!B!!!!
S!VR_PVDDQ_DEF_PH2_BOOT!C7A22!1!@baseboard_fab2_lib.baseboard_fab2(sch_1):page219_i75@mstr_discrete.cap(chips)!CAP_0402-0.220UF,16V,10%,X7R,AA!!!F4056!A!!!!
S!VR_PVDDQ_DEF_PH2_PHASE!C7A22!2!@baseboard_fab2_lib.baseboard_fab2(sch_1):page219_i75@mstr_discrete.cap(chips)!CAP_0402-0.220UF,16V,10%,X7R,AA!!!F4056!B!!!!
S!VR_PVCCIO_CPU0_PH1_BOOT!C7C14!1!@baseboard_fab2_lib.baseboard_fab2(sch_1):page212_i37@mstr_discrete.cap(chips)!CAP_0402-0.220UF,16V,10%,X7R,AA!!!F4055!A!!!!
S!VR_PVCCIO_CPU0_PH1_PHASE!C7C14!2!@baseboard_fab2_lib.baseboard_fab2(sch_1):page212_i37@mstr_discrete.cap(chips)!CAP_0402-0.220UF,16V,10%,X7R,AA!!!F4055!B!!!!
S!VR_PVDDQ_ABC_PH1_BOOT!C7G31!1!@baseboard_fab2_lib.baseboard_fab2(sch_1):page216_i44@mstr_discrete.cap(chips)!CAP_0402-0.220UF,16V,10%,X7R,AA!!!F4054!A!!!!
S!VR_PVDDQ_ABC_PH1_PHASE!C7G31!2!@baseboard_fab2_lib.baseboard_fab2(sch_1):page216_i44@mstr_discrete.cap(chips)!CAP_0402-0.220UF,16V,10%,X7R,AA!!!F4054!B!!!!
S!VR_PVDDQ_ABC_PH2_BOOT!C7G38!1!@baseboard_fab2_lib.baseboard_fab2(sch_1):page216_i75@mstr_discrete.cap(chips)!CAP_0402-0.220UF,16V,10%,X7R,AA!!!F4053!A!!!!
S!VR_PVDDQ_ABC_PH2_PHASE!C7G38!2!@baseboard_fab2_lib.baseboard_fab2(sch_1):page216_i75@mstr_discrete.cap(chips)!CAP_0402-0.220UF,16V,10%,X7R,AA!!!F4053!B!!!!
S!VR_PVCCIN_CPU1_PH2_BOOT!C1D36!1!@baseboard_fab2_lib.baseboard_fab2(sch_1):page207_i38@mstr_discrete.cap(chips)!CAP_0402-0.220UF,16V,10%,X7R,AA!!!F4070!A!!!!
S!VR_PVCCIN_CPU1_PH2_PHASE!C1D36!2!@baseboard_fab2_lib.baseboard_fab2(sch_1):page207_i38@mstr_discrete.cap(chips)!CAP_0402-0.220UF,16V,10%,X7R,AA!!!F4070!B!!!!
S!VR_PVCCIN_CPU1_PH1_BOOT!C1E11!1!@baseboard_fab2_lib.baseboard_fab2(sch_1):page207_i30@mstr_discrete.cap(chips)!CAP_0402-0.220UF,16V,10%,X7R,AA!!!F4069!A!!!!
S!VR_PVCCIN_CPU1_PH1_PHASE!C1E11!2!@baseboard_fab2_lib.baseboard_fab2(sch_1):page207_i30@mstr_discrete.cap(chips)!CAP_0402-0.220UF,16V,10%,X7R,AA!!!F4069!B!!!!
S!GND!J8A3!7!@baseboard_fab2_lib.baseboard_fab2(sch_1):page172_i17@mstr_conn.conn7_e82125014(chips)!CONN7_E82125014_PIP_TH-CONN,E8A!!!F2237!GND(0)!!!!
S!GND!J8A3!4!@baseboard_fab2_lib.baseboard_fab2(sch_1):page172_i17@mstr_conn.conn7_e82125014(chips)!CONN7_E82125014_PIP_TH-CONN,E8A!!!F2237!GND(1)!!!!
S!GND!J8A3!1!@baseboard_fab2_lib.baseboard_fab2(sch_1):page172_i17@mstr_conn.conn7_e82125014(chips)!CONN7_E82125014_PIP_TH-CONN,E8A!!!F2237!GND(2)!!!!
S!GND!J8A3!MH1!@baseboard_fab2_lib.baseboard_fab2(sch_1):page172_i17@mstr_conn.conn7_e82125014(chips)!CONN7_E82125014_PIP_TH-CONN,E8A!!!F2237!MH1!!!!
S!GND!J8A3!MH2!@baseboard_fab2_lib.baseboard_fab2(sch_1):page172_i17@mstr_conn.conn7_e82125014(chips)!CONN7_E82125014_PIP_TH-CONN,E8A!!!F2237!MH2!!!!
S!SATA6G_S1_RX_C_DP!J8A3!5!@baseboard_fab2_lib.baseboard_fab2(sch_1):page172_i17@mstr_conn.conn7_e82125014(chips)!CONN7_E82125014_PIP_TH-CONN,E8A!!!F2237!SATA_RXN!!!!
S!SATA6G_S1_RX_C_DN!J8A3!6!@baseboard_fab2_lib.baseboard_fab2(sch_1):page172_i17@mstr_conn.conn7_e82125014(chips)!CONN7_E82125014_PIP_TH-CONN,E8A!!!F2237!SATA_RXP!!!!
S!SATA6G_S1_TX_C_DN!J8A3!3!@baseboard_fab2_lib.baseboard_fab2(sch_1):page172_i17@mstr_conn.conn7_e82125014(chips)!CONN7_E82125014_PIP_TH-CONN,E8A!!!F2237!SATA_TXN!!!!
S!SATA6G_S1_TX_C_DP!J8A3!2!@baseboard_fab2_lib.baseboard_fab2(sch_1):page172_i17@mstr_conn.conn7_e82125014(chips)!CONN7_E82125014_PIP_TH-CONN,E8A!!!F2237!SATA_TXP!!!!
S!GND!J2M1!7!@baseboard_fab2_lib.baseboard_fab2(sch_1):page172_i52@mstr_conn.conn7_e82125014(chips)!CONN7_E82125014_PIP_TH-EMPTY,EA!!!F2236!GND(0)!!!!
S!GND!J2M1!4!@baseboard_fab2_lib.baseboard_fab2(sch_1):page172_i52@mstr_conn.conn7_e82125014(chips)!CONN7_E82125014_PIP_TH-EMPTY,EA!!!F2236!GND(1)!!!!
S!GND!J2M1!1!@baseboard_fab2_lib.baseboard_fab2(sch_1):page172_i52@mstr_conn.conn7_e82125014(chips)!CONN7_E82125014_PIP_TH-EMPTY,EA!!!F2236!GND(2)!!!!
S!GND!J2M1!MH1!@baseboard_fab2_lib.baseboard_fab2(sch_1):page172_i52@mstr_conn.conn7_e82125014(chips)!CONN7_E82125014_PIP_TH-EMPTY,EA!!!F2236!MH1!!!!
S!GND!J2M1!MH2!@baseboard_fab2_lib.baseboard_fab2(sch_1):page172_i52@mstr_conn.conn7_e82125014(chips)!CONN7_E82125014_PIP_TH-EMPTY,EA!!!F2236!MH2!!!!
S!SATA6G_S1_RX_C_DP!J2M1!5!@baseboard_fab2_lib.baseboard_fab2(sch_1):page172_i52@mstr_conn.conn7_e82125014(chips)!CONN7_E82125014_PIP_TH-EMPTY,EA!!!F2236!SATA_RXN!!!!
S!SATA6G_S1_RX_C_DN!J2M1!6!@baseboard_fab2_lib.baseboard_fab2(sch_1):page172_i52@mstr_conn.conn7_e82125014(chips)!CONN7_E82125014_PIP_TH-EMPTY,EA!!!F2236!SATA_RXP!!!!
S!SATA6G_S1_TX_C_DN!J2M1!3!@baseboard_fab2_lib.baseboard_fab2(sch_1):page172_i52@mstr_conn.conn7_e82125014(chips)!CONN7_E82125014_PIP_TH-EMPTY,EA!!!F2236!SATA_TXN!!!!
S!SATA6G_S1_TX_C_DP!J2M1!2!@baseboard_fab2_lib.baseboard_fab2(sch_1):page172_i52@mstr_conn.conn7_e82125014(chips)!CONN7_E82125014_PIP_TH-EMPTY,EA!!!F2236!SATA_TXP!!!!
S!VR_PVCCIO_CPU1_PH1_BOOT!EU4E2!33!@baseboard_fab2_lib.baseboard_fab2(sch_1):page214_i126@mstr_discrete.ir354xx(chips)!IR354XX_SM-IR35412,IC,H73684-0A!!!F2060!BOOST!!!!
S!P5V_STBY!EU4E2!35!@baseboard_fab2_lib.baseboard_fab2(sch_1):page214_i126@mstr_discrete.ir354xx(chips)!IR354XX_SM-IR35412,IC,H73684-0A!!!F2060!EN!!!!
S!TP_PVCCIO_CPU1_GL_0!EU4E2!6!@baseboard_fab2_lib.baseboard_fab2(sch_1):page214_i126@mstr_discrete.ir354xx(chips)!IR354XX_SM-IR35412,IC,H73684-0A!!!F2060!GL(0)!!!!
S!TP_PVCCIO_CPU1_GL_1!EU4E2!41!@baseboard_fab2_lib.baseboard_fab2(sch_1):page214_i126@mstr_discrete.ir354xx(chips)!IR354XX_SM-IR35412,IC,H73684-0A!!!F2060!GL(1)!!!!
S!ISENSE_PVCCIO_CPU1_PH1_IMON!EU4E2!38!@baseboard_fab2_lib.baseboard_fab2(sch_1):page214_i126@mstr_discrete.ir354xx(chips)!IR354XX_SM-IR35412,IC,H73684-0A!!!F2060!IOUT!!!!
S!GND!EU4E2!2!@baseboard_fab2_lib.baseboard_fab2(sch_1):page214_i126@mstr_discrete.ir354xx(chips)!IR354XX_SM-IR35412,IC,H73684-0A!!!F2060!LGND!!!!
S!NC_PVCCIO_CPU1_PH1_P31!EU4E2!31!@baseboard_fab2_lib.baseboard_fab2(sch_1):page214_i126@mstr_discrete.ir354xx(chips)!IR354XX_SM-IR35412,IC,H73684-0A!!!F2060!NC!!!!
S!VR_PVCCIO_CPU1_OCSET!EU4E2!37!@baseboard_fab2_lib.baseboard_fab2(sch_1):page214_i126@mstr_discrete.ir354xx(chips)!IR354XX_SM-IR35412,IC,H73684-0A!!!F2060!OCSET!!!!
S!GND!EU4E2!5!@baseboard_fab2_lib.baseboard_fab2(sch_1):page214_i126@mstr_discrete.ir354xx(chips)!IR354XX_SM-IR35412,IC,H73684-0A!!!F2060!PGND(0)!!!!
S!GND!EU4E2!7!@baseboard_fab2_lib.baseboard_fab2(sch_1):page214_i126@mstr_discrete.ir354xx(chips)!IR354XX_SM-IR35412,IC,H73684-0A!!!F2060!PGND(1)!!!!
S!GND!EU4E2!40!@baseboard_fab2_lib.baseboard_fab2(sch_1):page214_i126@mstr_discrete.ir354xx(chips)!IR354XX_SM-IR35412,IC,H73684-0A!!!F2060!PGND(2)!!!!
S!VR_PVCCIO_CPU1_PH1_PHASE!EU4E2!32!@baseboard_fab2_lib.baseboard_fab2(sch_1):page214_i126@mstr_discrete.ir354xx(chips)!IR354XX_SM-IR35412,IC,H73684-0A!!!F2060!PHASE!!!!
S!VR_PVCCIO_CPU1_PWM1!EU4E2!34!@baseboard_fab2_lib.baseboard_fab2(sch_1):page214_i126@mstr_discrete.ir354xx(chips)!IR354XX_SM-IR35412,IC,H73684-0A!!!F2060!PWM!!!!
S!VR_PVCCIO_CPU1_AIREF1!EU4E2!39!@baseboard_fab2_lib.baseboard_fab2(sch_1):page214_i126@mstr_discrete.ir354xx(chips)!IR354XX_SM-IR35412,IC,H73684-0A!!!F2060!REFIN!!!!
S!VR_PVCCIO_CPU1_PH1_SW!EU4E2!10!@baseboard_fab2_lib.baseboard_fab2(sch_1):page214_i126@mstr_discrete.ir354xx(chips)!IR354XX_SM-IR35412,IC,H73684-0A!!!F2060!SW!!!!
S!A_TSENSE_PVCCIO_CPU1!EU4E2!36!@baseboard_fab2_lib.baseboard_fab2(sch_1):page214_i126@mstr_discrete.ir354xx(chips)!IR354XX_SM-IR35412,IC,H73684-0A!!!F2060!TOUT_FLT!!!!
S!VR_PVCCIO_CPU1_PH1_VCIN!EU4E2!3!@baseboard_fab2_lib.baseboard_fab2(sch_1):page214_i126@mstr_discrete.ir354xx(chips)!IR354XX_SM-IR35412,IC,H73684-0A!!!F2060!VCC!!!!
S!P5V_STBY!EU4E2!4!@baseboard_fab2_lib.baseboard_fab2(sch_1):page214_i126@mstr_discrete.ir354xx(chips)!IR354XX_SM-IR35412,IC,H73684-0A!!!F2060!VDRV!!!!
S!VR_FET_SW_P12V_STBY_PVCCIN_CPU0!EU4E2!25!@baseboard_fab2_lib.baseboard_fab2(sch_1):page214_i126@mstr_discrete.ir354xx(chips)!IR354XX_SM-IR35412,IC,H73684-0A!!!F2060!VIN(0)!!!!
S!VR_FET_SW_P12V_STBY_PVCCIN_CPU0!EU4E2!30!@baseboard_fab2_lib.baseboard_fab2(sch_1):page214_i126@mstr_discrete.ir354xx(chips)!IR354XX_SM-IR35412,IC,H73684-0A!!!F2060!VIN(1)!!!!
S!PVCCIO_CPU1!EU4E2!1!@baseboard_fab2_lib.baseboard_fab2(sch_1):page214_i126@mstr_discrete.ir354xx(chips)!IR354XX_SM-IR35412,IC,H73684-0A!!!F2060!VOS!!!!
S!VR_P1V05_PCH_STBY_PH1_BOOT!EU7A2!33!@baseboard_fab2_lib.baseboard_fab2(sch_1):page236_i117@mstr_discrete.ir354xx(chips)!IR354XX_SM-IR35412,IC,H73684-0A!!!F2059!BOOST!!!!
S!P5V_STBY!EU7A2!35!@baseboard_fab2_lib.baseboard_fab2(sch_1):page236_i117@mstr_discrete.ir354xx(chips)!IR354XX_SM-IR35412,IC,H73684-0A!!!F2059!EN!!!!
S!TP_P1V05_PCH_GL_0!EU7A2!6!@baseboard_fab2_lib.baseboard_fab2(sch_1):page236_i117@mstr_discrete.ir354xx(chips)!IR354XX_SM-IR35412,IC,H73684-0A!!!F2059!GL(0)!!!!
S!TP_P1V05_PCH_GL_1!EU7A2!41!@baseboard_fab2_lib.baseboard_fab2(sch_1):page236_i117@mstr_discrete.ir354xx(chips)!IR354XX_SM-IR35412,IC,H73684-0A!!!F2059!GL(1)!!!!
S!ISENSE_P1V05_PCH_STBY_PH1_IMON!EU7A2!38!@baseboard_fab2_lib.baseboard_fab2(sch_1):page236_i117@mstr_discrete.ir354xx(chips)!IR354XX_SM-IR35412,IC,H73684-0A!!!F2059!IOUT!!!!
S!GND!EU7A2!2!@baseboard_fab2_lib.baseboard_fab2(sch_1):page236_i117@mstr_discrete.ir354xx(chips)!IR354XX_SM-IR35412,IC,H73684-0A!!!F2059!LGND!!!!
S!NC_P1V05_PCH_STBY_PH1_P31!EU7A2!31!@baseboard_fab2_lib.baseboard_fab2(sch_1):page236_i117@mstr_discrete.ir354xx(chips)!IR354XX_SM-IR35412,IC,H73684-0A!!!F2059!NC!!!!
S!VR_P1V05_PCH_STBY_OCSET!EU7A2!37!@baseboard_fab2_lib.baseboard_fab2(sch_1):page236_i117@mstr_discrete.ir354xx(chips)!IR354XX_SM-IR35412,IC,H73684-0A!!!F2059!OCSET!!!!
S!GND!EU7A2!5!@baseboard_fab2_lib.baseboard_fab2(sch_1):page236_i117@mstr_discrete.ir354xx(chips)!IR354XX_SM-IR35412,IC,H73684-0A!!!F2059!PGND(0)!!!!
S!GND!EU7A2!7!@baseboard_fab2_lib.baseboard_fab2(sch_1):page236_i117@mstr_discrete.ir354xx(chips)!IR354XX_SM-IR35412,IC,H73684-0A!!!F2059!PGND(1)!!!!
S!GND!EU7A2!40!@baseboard_fab2_lib.baseboard_fab2(sch_1):page236_i117@mstr_discrete.ir354xx(chips)!IR354XX_SM-IR35412,IC,H73684-0A!!!F2059!PGND(2)!!!!
S!VR_P1V05_PCH_STBY_PH1_PHASE!EU7A2!32!@baseboard_fab2_lib.baseboard_fab2(sch_1):page236_i117@mstr_discrete.ir354xx(chips)!IR354XX_SM-IR35412,IC,H73684-0A!!!F2059!PHASE!!!!
S!VR_P1V05_PCH_STBY_PWM1!EU7A2!34!@baseboard_fab2_lib.baseboard_fab2(sch_1):page236_i117@mstr_discrete.ir354xx(chips)!IR354XX_SM-IR35412,IC,H73684-0A!!!F2059!PWM!!!!
S!VR_P1V05_PCH_BIREF1!EU7A2!39!@baseboard_fab2_lib.baseboard_fab2(sch_1):page236_i117@mstr_discrete.ir354xx(chips)!IR354XX_SM-IR35412,IC,H73684-0A!!!F2059!REFIN!!!!
S!VR_P1V05_PCH_STBY_PH1_PHASE_SW!EU7A2!10!@baseboard_fab2_lib.baseboard_fab2(sch_1):page236_i117@mstr_discrete.ir354xx(chips)!IR354XX_SM-IR35412,IC,H73684-0A!!!F2059!SW!!!!
S!A_TSENSE_P1V05_PCH_STBY_TMON!EU7A2!36!@baseboard_fab2_lib.baseboard_fab2(sch_1):page236_i117@mstr_discrete.ir354xx(chips)!IR354XX_SM-IR35412,IC,H73684-0A!!!F2059!TOUT_FLT!!!!
S!VR_P1V05_PCH_STBY_PH1_VCIN!EU7A2!3!@baseboard_fab2_lib.baseboard_fab2(sch_1):page236_i117@mstr_discrete.ir354xx(chips)!IR354XX_SM-IR35412,IC,H73684-0A!!!F2059!VCC!!!!
S!P5V_STBY!EU7A2!4!@baseboard_fab2_lib.baseboard_fab2(sch_1):page236_i117@mstr_discrete.ir354xx(chips)!IR354XX_SM-IR35412,IC,H73684-0A!!!F2059!VDRV!!!!
S!VR_FET_SW_P12V_STBY_PVDDQ_DEF!EU7A2!25!@baseboard_fab2_lib.baseboard_fab2(sch_1):page236_i117@mstr_discrete.ir354xx(chips)!IR354XX_SM-IR35412,IC,H73684-0A!!!F2059!VIN(0)!!!!
S!VR_FET_SW_P12V_STBY_PVDDQ_DEF!EU7A2!30!@baseboard_fab2_lib.baseboard_fab2(sch_1):page236_i117@mstr_discrete.ir354xx(chips)!IR354XX_SM-IR35412,IC,H73684-0A!!!F2059!VIN(1)!!!!
S!P1V05_PCH_STBY!EU7A2!1!@baseboard_fab2_lib.baseboard_fab2(sch_1):page236_i117@mstr_discrete.ir354xx(chips)!IR354XX_SM-IR35412,IC,H73684-0A!!!F2059!VOS!!!!
S!VR_PVNN_PCH_PH1_BOOT!EU7A3!33!@baseboard_fab2_lib.baseboard_fab2(sch_1):page236_i116@mstr_discrete.ir354xx(chips)!IR354XX_SM-IR35412,IC,H73684-0A!!!F2058!BOOST!!!!
S!P5V_STBY!EU7A3!35!@baseboard_fab2_lib.baseboard_fab2(sch_1):page236_i116@mstr_discrete.ir354xx(chips)!IR354XX_SM-IR35412,IC,H73684-0A!!!F2058!EN!!!!
S!TP_PVNN_PCH_GL_0!EU7A3!6!@baseboard_fab2_lib.baseboard_fab2(sch_1):page236_i116@mstr_discrete.ir354xx(chips)!IR354XX_SM-IR35412,IC,H73684-0A!!!F2058!GL(0)!!!!
S!TP_PVNN_PCH_GL_1!EU7A3!41!@baseboard_fab2_lib.baseboard_fab2(sch_1):page236_i116@mstr_discrete.ir354xx(chips)!IR354XX_SM-IR35412,IC,H73684-0A!!!F2058!GL(1)!!!!
S!ISENSE_PVNN_PCH_PH1_IMON!EU7A3!38!@baseboard_fab2_lib.baseboard_fab2(sch_1):page236_i116@mstr_discrete.ir354xx(chips)!IR354XX_SM-IR35412,IC,H73684-0A!!!F2058!IOUT!!!!
S!GND!EU7A3!2!@baseboard_fab2_lib.baseboard_fab2(sch_1):page236_i116@mstr_discrete.ir354xx(chips)!IR354XX_SM-IR35412,IC,H73684-0A!!!F2058!LGND!!!!
S!NC_PVNN_PCH_PH1_P31!EU7A3!31!@baseboard_fab2_lib.baseboard_fab2(sch_1):page236_i116@mstr_discrete.ir354xx(chips)!IR354XX_SM-IR35412,IC,H73684-0A!!!F2058!NC!!!!
S!VR_PVNN_PCH_STBY_OCSET!EU7A3!37!@baseboard_fab2_lib.baseboard_fab2(sch_1):page236_i116@mstr_discrete.ir354xx(chips)!IR354XX_SM-IR35412,IC,H73684-0A!!!F2058!OCSET!!!!
S!GND!EU7A3!5!@baseboard_fab2_lib.baseboard_fab2(sch_1):page236_i116@mstr_discrete.ir354xx(chips)!IR354XX_SM-IR35412,IC,H73684-0A!!!F2058!PGND(0)!!!!
S!GND!EU7A3!7!@baseboard_fab2_lib.baseboard_fab2(sch_1):page236_i116@mstr_discrete.ir354xx(chips)!IR354XX_SM-IR35412,IC,H73684-0A!!!F2058!PGND(1)!!!!
S!GND!EU7A3!40!@baseboard_fab2_lib.baseboard_fab2(sch_1):page236_i116@mstr_discrete.ir354xx(chips)!IR354XX_SM-IR35412,IC,H73684-0A!!!F2058!PGND(2)!!!!
S!VR_PVNN_PCH_PH1_PHASE!EU7A3!32!@baseboard_fab2_lib.baseboard_fab2(sch_1):page236_i116@mstr_discrete.ir354xx(chips)!IR354XX_SM-IR35412,IC,H73684-0A!!!F2058!PHASE!!!!
S!VR_PVNN_PCH_PWM1!EU7A3!34!@baseboard_fab2_lib.baseboard_fab2(sch_1):page236_i116@mstr_discrete.ir354xx(chips)!IR354XX_SM-IR35412,IC,H73684-0A!!!F2058!PWM!!!!
S!VR_PVNN_PCH_AIREF1!EU7A3!39!@baseboard_fab2_lib.baseboard_fab2(sch_1):page236_i116@mstr_discrete.ir354xx(chips)!IR354XX_SM-IR35412,IC,H73684-0A!!!F2058!REFIN!!!!
S!VR_PVNN_PCH_PH1_PHASE_SW!EU7A3!10!@baseboard_fab2_lib.baseboard_fab2(sch_1):page236_i116@mstr_discrete.ir354xx(chips)!IR354XX_SM-IR35412,IC,H73684-0A!!!F2058!SW!!!!
S!A_TSENSE_PVNN_PCH_TMON!EU7A3!36!@baseboard_fab2_lib.baseboard_fab2(sch_1):page236_i116@mstr_discrete.ir354xx(chips)!IR354XX_SM-IR35412,IC,H73684-0A!!!F2058!TOUT_FLT!!!!
S!VR_PVNN_PCH_PH1_VCIN!EU7A3!3!@baseboard_fab2_lib.baseboard_fab2(sch_1):page236_i116@mstr_discrete.ir354xx(chips)!IR354XX_SM-IR35412,IC,H73684-0A!!!F2058!VCC!!!!
S!P5V_STBY!EU7A3!4!@baseboard_fab2_lib.baseboard_fab2(sch_1):page236_i116@mstr_discrete.ir354xx(chips)!IR354XX_SM-IR35412,IC,H73684-0A!!!F2058!VDRV!!!!
S!VR_FET_SW_P12V_STBY_PVDDQ_DEF!EU7A3!25!@baseboard_fab2_lib.baseboard_fab2(sch_1):page236_i116@mstr_discrete.ir354xx(chips)!IR354XX_SM-IR35412,IC,H73684-0A!!!F2058!VIN(0)!!!!
S!VR_FET_SW_P12V_STBY_PVDDQ_DEF!EU7A3!30!@baseboard_fab2_lib.baseboard_fab2(sch_1):page236_i116@mstr_discrete.ir354xx(chips)!IR354XX_SM-IR35412,IC,H73684-0A!!!F2058!VIN(1)!!!!
S!PVNN_PCH_STBY!EU7A3!1!@baseboard_fab2_lib.baseboard_fab2(sch_1):page236_i116@mstr_discrete.ir354xx(chips)!IR354XX_SM-IR35412,IC,H73684-0A!!!F2058!VOS!!!!
S!VR_PVCCIO_CPU0_PH1_BOOT!EU7C1!33!@baseboard_fab2_lib.baseboard_fab2(sch_1):page212_i101@mstr_discrete.ir354xx(chips)!IR354XX_SM-IR35412,IC,H73684-0A!!!F2057!BOOST!!!!
S!P5V_STBY!EU7C1!35!@baseboard_fab2_lib.baseboard_fab2(sch_1):page212_i101@mstr_discrete.ir354xx(chips)!IR354XX_SM-IR35412,IC,H73684-0A!!!F2057!EN!!!!
S!TP_PVCCIO_CPU0_GL_0!EU7C1!6!@baseboard_fab2_lib.baseboard_fab2(sch_1):page212_i101@mstr_discrete.ir354xx(chips)!IR354XX_SM-IR35412,IC,H73684-0A!!!F2057!GL(0)!!!!
S!TP_PVCCIO_CPU0_GL_1!EU7C1!41!@baseboard_fab2_lib.baseboard_fab2(sch_1):page212_i101@mstr_discrete.ir354xx(chips)!IR354XX_SM-IR35412,IC,H73684-0A!!!F2057!GL(1)!!!!
S!ISENSE_PVCCIO_CPU0_PH1_IMON!EU7C1!38!@baseboard_fab2_lib.baseboard_fab2(sch_1):page212_i101@mstr_discrete.ir354xx(chips)!IR354XX_SM-IR35412,IC,H73684-0A!!!F2057!IOUT!!!!
S!GND!EU7C1!2!@baseboard_fab2_lib.baseboard_fab2(sch_1):page212_i101@mstr_discrete.ir354xx(chips)!IR354XX_SM-IR35412,IC,H73684-0A!!!F2057!LGND!!!!
S!NC_PVCCIO_CPU0_PH1_P31!EU7C1!31!@baseboard_fab2_lib.baseboard_fab2(sch_1):page212_i101@mstr_discrete.ir354xx(chips)!IR354XX_SM-IR35412,IC,H73684-0A!!!F2057!NC!!!!
S!VR_PVCCIO_CPU0_OCSET!EU7C1!37!@baseboard_fab2_lib.baseboard_fab2(sch_1):page212_i101@mstr_discrete.ir354xx(chips)!IR354XX_SM-IR35412,IC,H73684-0A!!!F2057!OCSET!!!!
S!GND!EU7C1!5!@baseboard_fab2_lib.baseboard_fab2(sch_1):page212_i101@mstr_discrete.ir354xx(chips)!IR354XX_SM-IR35412,IC,H73684-0A!!!F2057!PGND(0)!!!!
S!GND!EU7C1!7!@baseboard_fab2_lib.baseboard_fab2(sch_1):page212_i101@mstr_discrete.ir354xx(chips)!IR354XX_SM-IR35412,IC,H73684-0A!!!F2057!PGND(1)!!!!
S!GND!EU7C1!40!@baseboard_fab2_lib.baseboard_fab2(sch_1):page212_i101@mstr_discrete.ir354xx(chips)!IR354XX_SM-IR35412,IC,H73684-0A!!!F2057!PGND(2)!!!!
S!VR_PVCCIO_CPU0_PH1_PHASE!EU7C1!32!@baseboard_fab2_lib.baseboard_fab2(sch_1):page212_i101@mstr_discrete.ir354xx(chips)!IR354XX_SM-IR35412,IC,H73684-0A!!!F2057!PHASE!!!!
S!VR_PVCCIO_CPU0_PWM1!EU7C1!34!@baseboard_fab2_lib.baseboard_fab2(sch_1):page212_i101@mstr_discrete.ir354xx(chips)!IR354XX_SM-IR35412,IC,H73684-0A!!!F2057!PWM!!!!
S!VR_PVCCIO_CPU0_AIREF1!EU7C1!39!@baseboard_fab2_lib.baseboard_fab2(sch_1):page212_i101@mstr_discrete.ir354xx(chips)!IR354XX_SM-IR35412,IC,H73684-0A!!!F2057!REFIN!!!!
S!VR_PVCCIO_CPU0_PH1_SW!EU7C1!10!@baseboard_fab2_lib.baseboard_fab2(sch_1):page212_i101@mstr_discrete.ir354xx(chips)!IR354XX_SM-IR35412,IC,H73684-0A!!!F2057!SW!!!!
S!A_TSENSE_PVCCIO_CPU0!EU7C1!36!@baseboard_fab2_lib.baseboard_fab2(sch_1):page212_i101@mstr_discrete.ir354xx(chips)!IR354XX_SM-IR35412,IC,H73684-0A!!!F2057!TOUT_FLT!!!!
S!VR_PVCCIO_CPU0_PH1_VCIN!EU7C1!3!@baseboard_fab2_lib.baseboard_fab2(sch_1):page212_i101@mstr_discrete.ir354xx(chips)!IR354XX_SM-IR35412,IC,H73684-0A!!!F2057!VCC!!!!
S!P5V_STBY!EU7C1!4!@baseboard_fab2_lib.baseboard_fab2(sch_1):page212_i101@mstr_discrete.ir354xx(chips)!IR354XX_SM-IR35412,IC,H73684-0A!!!F2057!VDRV!!!!
S!VR_FET_SW_P12V_STBY_PVCCIO_CPU0!EU7C1!25!@baseboard_fab2_lib.baseboard_fab2(sch_1):page212_i101@mstr_discrete.ir354xx(chips)!IR354XX_SM-IR35412,IC,H73684-0A!!!F2057!VIN(0)!!!!
S!VR_FET_SW_P12V_STBY_PVCCIO_CPU0!EU7C1!30!@baseboard_fab2_lib.baseboard_fab2(sch_1):page212_i101@mstr_discrete.ir354xx(chips)!IR354XX_SM-IR35412,IC,H73684-0A!!!F2057!VIN(1)!!!!
S!PVCCIO_CPU0!EU7C1!1!@baseboard_fab2_lib.baseboard_fab2(sch_1):page212_i101@mstr_discrete.ir354xx(chips)!IR354XX_SM-IR35412,IC,H73684-0A!!!F2057!VOS!!!!
S!VR_PVSA_CPU1_BOOT!EU1C1!33!@baseboard_fab2_lib.baseboard_fab2(sch_1):page210_i51@mstr_discrete.ir354xx(chips)!IR354XX_SM-IR35412,IC,H73684-0A!!!F2062!BOOST!!!!
S!P5V_STBY!EU1C1!35!@baseboard_fab2_lib.baseboard_fab2(sch_1):page210_i51@mstr_discrete.ir354xx(chips)!IR354XX_SM-IR35412,IC,H73684-0A!!!F2062!EN!!!!
S!TP_PVSA_CPU1_GL_0!EU1C1!6!@baseboard_fab2_lib.baseboard_fab2(sch_1):page210_i51@mstr_discrete.ir354xx(chips)!IR354XX_SM-IR35412,IC,H73684-0A!!!F2062!GL(0)!!!!
S!TP_PVSA_CPU1_GL_1!EU1C1!41!@baseboard_fab2_lib.baseboard_fab2(sch_1):page210_i51@mstr_discrete.ir354xx(chips)!IR354XX_SM-IR35412,IC,H73684-0A!!!F2062!GL(1)!!!!
S!ISENSE_PVSA_CPU1_IMON!EU1C1!38!@baseboard_fab2_lib.baseboard_fab2(sch_1):page210_i51@mstr_discrete.ir354xx(chips)!IR354XX_SM-IR35412,IC,H73684-0A!!!F2062!IOUT!!!!
S!GND!EU1C1!2!@baseboard_fab2_lib.baseboard_fab2(sch_1):page210_i51@mstr_discrete.ir354xx(chips)!IR354XX_SM-IR35412,IC,H73684-0A!!!F2062!LGND!!!!
S!NC_PVSA_CPU1_P31!EU1C1!31!@baseboard_fab2_lib.baseboard_fab2(sch_1):page210_i51@mstr_discrete.ir354xx(chips)!IR354XX_SM-IR35412,IC,H73684-0A!!!F2062!NC!!!!
S!VR_PVSA_CPU1_OCSET!EU1C1!37!@baseboard_fab2_lib.baseboard_fab2(sch_1):page210_i51@mstr_discrete.ir354xx(chips)!IR354XX_SM-IR35412,IC,H73684-0A!!!F2062!OCSET!!!!
S!GND!EU1C1!5!@baseboard_fab2_lib.baseboard_fab2(sch_1):page210_i51@mstr_discrete.ir354xx(chips)!IR354XX_SM-IR35412,IC,H73684-0A!!!F2062!PGND(0)!!!!
S!GND!EU1C1!7!@baseboard_fab2_lib.baseboard_fab2(sch_1):page210_i51@mstr_discrete.ir354xx(chips)!IR354XX_SM-IR35412,IC,H73684-0A!!!F2062!PGND(1)!!!!
S!GND!EU1C1!40!@baseboard_fab2_lib.baseboard_fab2(sch_1):page210_i51@mstr_discrete.ir354xx(chips)!IR354XX_SM-IR35412,IC,H73684-0A!!!F2062!PGND(2)!!!!
S!VR_PVSA_CPU1_PHASE!EU1C1!32!@baseboard_fab2_lib.baseboard_fab2(sch_1):page210_i51@mstr_discrete.ir354xx(chips)!IR354XX_SM-IR35412,IC,H73684-0A!!!F2062!PHASE!!!!
S!VR_PVSA_CPU1_PWM!EU1C1!34!@baseboard_fab2_lib.baseboard_fab2(sch_1):page210_i51@mstr_discrete.ir354xx(chips)!IR354XX_SM-IR35412,IC,H73684-0A!!!F2062!PWM!!!!
S!VR_PVSA_CPU1_BIREF1!EU1C1!39!@baseboard_fab2_lib.baseboard_fab2(sch_1):page210_i51@mstr_discrete.ir354xx(chips)!IR354XX_SM-IR35412,IC,H73684-0A!!!F2062!REFIN!!!!
S!VR_PVSA_CPU1_PHASE_SW!EU1C1!10!@baseboard_fab2_lib.baseboard_fab2(sch_1):page210_i51@mstr_discrete.ir354xx(chips)!IR354XX_SM-IR35412,IC,H73684-0A!!!F2062!SW!!!!
S!A_TSENSE_PVSA_CPU1!EU1C1!36!@baseboard_fab2_lib.baseboard_fab2(sch_1):page210_i51@mstr_discrete.ir354xx(chips)!IR354XX_SM-IR35412,IC,H73684-0A!!!F2062!TOUT_FLT!!!!
S!VR_PVSA_CPU1_VCIN!EU1C1!3!@baseboard_fab2_lib.baseboard_fab2(sch_1):page210_i51@mstr_discrete.ir354xx(chips)!IR354XX_SM-IR35412,IC,H73684-0A!!!F2062!VCC!!!!
S!P5V_STBY!EU1C1!4!@baseboard_fab2_lib.baseboard_fab2(sch_1):page210_i51@mstr_discrete.ir354xx(chips)!IR354XX_SM-IR35412,IC,H73684-0A!!!F2062!VDRV!!!!
S!VR_FET_SW_P12V_STBY_PVCCIN_CPU1!EU1C1!25!@baseboard_fab2_lib.baseboard_fab2(sch_1):page210_i51@mstr_discrete.ir354xx(chips)!IR354XX_SM-IR35412,IC,H73684-0A!!!F2062!VIN(0)!!!!
S!VR_FET_SW_P12V_STBY_PVCCIN_CPU1!EU1C1!30!@baseboard_fab2_lib.baseboard_fab2(sch_1):page210_i51@mstr_discrete.ir354xx(chips)!IR354XX_SM-IR35412,IC,H73684-0A!!!F2062!VIN(1)!!!!
S!PVSA_CPU1!EU1C1!1!@baseboard_fab2_lib.baseboard_fab2(sch_1):page210_i51@mstr_discrete.ir354xx(chips)!IR354XX_SM-IR35412,IC,H73684-0A!!!F2062!VOS!!!!
S!VR_PVSA_CPU0_BOOT!EU4C1!33!@baseboard_fab2_lib.baseboard_fab2(sch_1):page205_i46@mstr_discrete.ir354xx(chips)!IR354XX_SM-IR35412,IC,H73684-0A!!!F2061!BOOST!!!!
S!P5V_STBY!EU4C1!35!@baseboard_fab2_lib.baseboard_fab2(sch_1):page205_i46@mstr_discrete.ir354xx(chips)!IR354XX_SM-IR35412,IC,H73684-0A!!!F2061!EN!!!!
S!TP_PVSA_CPU0_GL_0!EU4C1!6!@baseboard_fab2_lib.baseboard_fab2(sch_1):page205_i46@mstr_discrete.ir354xx(chips)!IR354XX_SM-IR35412,IC,H73684-0A!!!F2061!GL(0)!!!!
S!TP_PVSA_CPU0_GL_1!EU4C1!41!@baseboard_fab2_lib.baseboard_fab2(sch_1):page205_i46@mstr_discrete.ir354xx(chips)!IR354XX_SM-IR35412,IC,H73684-0A!!!F2061!GL(1)!!!!
S!ISENSE_PVSA_CPU0_IMON!EU4C1!38!@baseboard_fab2_lib.baseboard_fab2(sch_1):page205_i46@mstr_discrete.ir354xx(chips)!IR354XX_SM-IR35412,IC,H73684-0A!!!F2061!IOUT!!!!
S!GND!EU4C1!2!@baseboard_fab2_lib.baseboard_fab2(sch_1):page205_i46@mstr_discrete.ir354xx(chips)!IR354XX_SM-IR35412,IC,H73684-0A!!!F2061!LGND!!!!
S!NC_PVSA_CPU0_P31!EU4C1!31!@baseboard_fab2_lib.baseboard_fab2(sch_1):page205_i46@mstr_discrete.ir354xx(chips)!IR354XX_SM-IR35412,IC,H73684-0A!!!F2061!NC!!!!
S!VR_PVSA_CPU0_OCSET!EU4C1!37!@baseboard_fab2_lib.baseboard_fab2(sch_1):page205_i46@mstr_discrete.ir354xx(chips)!IR354XX_SM-IR35412,IC,H73684-0A!!!F2061!OCSET!!!!
S!GND!EU4C1!5!@baseboard_fab2_lib.baseboard_fab2(sch_1):page205_i46@mstr_discrete.ir354xx(chips)!IR354XX_SM-IR35412,IC,H73684-0A!!!F2061!PGND(0)!!!!
S!GND!EU4C1!7!@baseboard_fab2_lib.baseboard_fab2(sch_1):page205_i46@mstr_discrete.ir354xx(chips)!IR354XX_SM-IR35412,IC,H73684-0A!!!F2061!PGND(1)!!!!
S!GND!EU4C1!40!@baseboard_fab2_lib.baseboard_fab2(sch_1):page205_i46@mstr_discrete.ir354xx(chips)!IR354XX_SM-IR35412,IC,H73684-0A!!!F2061!PGND(2)!!!!
S!VR_PVSA_CPU0_PHASE!EU4C1!32!@baseboard_fab2_lib.baseboard_fab2(sch_1):page205_i46@mstr_discrete.ir354xx(chips)!IR354XX_SM-IR35412,IC,H73684-0A!!!F2061!PHASE!!!!
S!VR_PVSA_CPU0_PWM!EU4C1!34!@baseboard_fab2_lib.baseboard_fab2(sch_1):page205_i46@mstr_discrete.ir354xx(chips)!IR354XX_SM-IR35412,IC,H73684-0A!!!F2061!PWM!!!!
S!VR_PVSA_CPU0_BIREF1!EU4C1!39!@baseboard_fab2_lib.baseboard_fab2(sch_1):page205_i46@mstr_discrete.ir354xx(chips)!IR354XX_SM-IR35412,IC,H73684-0A!!!F2061!REFIN!!!!
S!VR_PVSA_CPU0_PHASE_SW!EU4C1!10!@baseboard_fab2_lib.baseboard_fab2(sch_1):page205_i46@mstr_discrete.ir354xx(chips)!IR354XX_SM-IR35412,IC,H73684-0A!!!F2061!SW!!!!
S!A_TSENSE_PVSA_CPU0!EU4C1!36!@baseboard_fab2_lib.baseboard_fab2(sch_1):page205_i46@mstr_discrete.ir354xx(chips)!IR354XX_SM-IR35412,IC,H73684-0A!!!F2061!TOUT_FLT!!!!
S!VR_PVSA_CPU0_VCIN!EU4C1!3!@baseboard_fab2_lib.baseboard_fab2(sch_1):page205_i46@mstr_discrete.ir354xx(chips)!IR354XX_SM-IR35412,IC,H73684-0A!!!F2061!VCC!!!!
S!P5V_STBY!EU4C1!4!@baseboard_fab2_lib.baseboard_fab2(sch_1):page205_i46@mstr_discrete.ir354xx(chips)!IR354XX_SM-IR35412,IC,H73684-0A!!!F2061!VDRV!!!!
S!VR_FET_SW_P12V_STBY_PVCCIN_CPU0!EU4C1!25!@baseboard_fab2_lib.baseboard_fab2(sch_1):page205_i46@mstr_discrete.ir354xx(chips)!IR354XX_SM-IR35412,IC,H73684-0A!!!F2061!VIN(0)!!!!
S!VR_FET_SW_P12V_STBY_PVCCIN_CPU0!EU4C1!30!@baseboard_fab2_lib.baseboard_fab2(sch_1):page205_i46@mstr_discrete.ir354xx(chips)!IR354XX_SM-IR35412,IC,H73684-0A!!!F2061!VIN(1)!!!!
S!PVSA_CPU0!EU4C1!1!@baseboard_fab2_lib.baseboard_fab2(sch_1):page205_i46@mstr_discrete.ir354xx(chips)!IR354XX_SM-IR35412,IC,H73684-0A!!!F2061!VOS!!!!
S!PVCCIO_CPU0!R5D6!1!@baseboard_fab2_lib.baseboard_fab2(sch_1):page37_i312@mstr_discrete.res(chips)!RES_0402-10.0,1%,1/16W,EMPTY,GA!!!F1334!A!!!!
S!VSENSE_PMAX_CPU0!R5D6!2!@baseboard_fab2_lib.baseboard_fab2(sch_1):page37_i312@mstr_discrete.res(chips)!RES_0402-10.0,1%,1/16W,EMPTY,GA!!!F1334!B!!!!
S!PVCCIO_CPU1!R3D32!1!@baseboard_fab2_lib.baseboard_fab2(sch_1):page71_i53@mstr_discrete.res(chips)!RES_0402-10.0,1%,1/16W,EMPTY,GA!!!F1333!A!!!!
S!VSENSE_PMAX_CPU1!R3D32!2!@baseboard_fab2_lib.baseboard_fab2(sch_1):page71_i53@mstr_discrete.res(chips)!RES_0402-10.0,1%,1/16W,EMPTY,GA!!!F1333!B!!!!
S!VR_PVSA_CPU0_OCSET!R4C13!1!@baseboard_fab2_lib.baseboard_fab2(sch_1):page205_i62@mstr_discrete.res(chips)!RES_0402-68.1K,1%,1/16W,EMPTY,A!!!F333!A!!!!
S!GND!R4C13!2!@baseboard_fab2_lib.baseboard_fab2(sch_1):page205_i62@mstr_discrete.res(chips)!RES_0402-68.1K,1%,1/16W,EMPTY,A!!!F333!B!!!!
S!VR_PVCCIN_CPU0_PH2_OCSET!R4E19!1!@baseboard_fab2_lib.baseboard_fab2(sch_1):page202_i67@mstr_discrete.res(chips)!RES_0402-68.1K,1%,1/16W,EMPTY,A!!!F332!A!!!!
S!GND!R4E19!2!@baseboard_fab2_lib.baseboard_fab2(sch_1):page202_i67@mstr_discrete.res(chips)!RES_0402-68.1K,1%,1/16W,EMPTY,A!!!F332!B!!!!
S!VR_PVCCIN_CPU0_PH1_OCSET!R4E22!1!@baseboard_fab2_lib.baseboard_fab2(sch_1):page202_i65@mstr_discrete.res(chips)!RES_0402-68.1K,1%,1/16W,EMPTY,A!!!F331!A!!!!
S!GND!R4E22!2!@baseboard_fab2_lib.baseboard_fab2(sch_1):page202_i65@mstr_discrete.res(chips)!RES_0402-68.1K,1%,1/16W,EMPTY,A!!!F331!B!!!!
S!VR_PVCCIN_CPU0_PH3_OCSET!R4D72!1!@baseboard_fab2_lib.baseboard_fab2(sch_1):page203_i89@mstr_discrete.res(chips)!RES_0402-68.1K,1%,1/16W,EMPTY,A!!!F330!A!!!!
S!GND!R4D72!2!@baseboard_fab2_lib.baseboard_fab2(sch_1):page203_i89@mstr_discrete.res(chips)!RES_0402-68.1K,1%,1/16W,EMPTY,A!!!F330!B!!!!
S!VR_PVCCIN_CPU0_PH4_OCSET!R4D71!1!@baseboard_fab2_lib.baseboard_fab2(sch_1):page203_i91@mstr_discrete.res(chips)!RES_0402-68.1K,1%,1/16W,EMPTY,A!!!F329!A!!!!
S!GND!R4D71!2!@baseboard_fab2_lib.baseboard_fab2(sch_1):page203_i91@mstr_discrete.res(chips)!RES_0402-68.1K,1%,1/16W,EMPTY,A!!!F329!B!!!!
S!VR_PVCCIN_CPU0_PH5_OCSET!R4D68!1!@baseboard_fab2_lib.baseboard_fab2(sch_1):page204_i83@mstr_discrete.res(chips)!RES_0402-68.1K,1%,1/16W,EMPTY,A!!!F328!A!!!!
S!GND!R4D68!2!@baseboard_fab2_lib.baseboard_fab2(sch_1):page204_i83@mstr_discrete.res(chips)!RES_0402-68.1K,1%,1/16W,EMPTY,A!!!F328!B!!!!
S!VR_PVCCIO_CPU0_OCSET!R7C25!1!@baseboard_fab2_lib.baseboard_fab2(sch_1):page212_i103@mstr_discrete.res(chips)!RES_0402-68.1K,1%,1/16W,EMPTY,A!!!F327!A!!!!
S!GND!R7C25!2!@baseboard_fab2_lib.baseboard_fab2(sch_1):page212_i103@mstr_discrete.res(chips)!RES_0402-68.1K,1%,1/16W,EMPTY,A!!!F327!B!!!!
S!VR_PVCCIO_CPU1_OCSET!R4E21!1!@baseboard_fab2_lib.baseboard_fab2(sch_1):page214_i127@mstr_discrete.res(chips)!RES_0402-68.1K,1%,1/16W,EMPTY,A!!!F326!A!!!!
S!GND!R4E21!2!@baseboard_fab2_lib.baseboard_fab2(sch_1):page214_i127@mstr_discrete.res(chips)!RES_0402-68.1K,1%,1/16W,EMPTY,A!!!F326!B!!!!
S!VR_PVDDQ_ABC_PH1_OCSET!R7G25!1!@baseboard_fab2_lib.baseboard_fab2(sch_1):page216_i104@mstr_discrete.res(chips)!RES_0402-68.1K,1%,1/16W,EMPTY,A!!!F325!A!!!!
S!GND!R7G25!2!@baseboard_fab2_lib.baseboard_fab2(sch_1):page216_i104@mstr_discrete.res(chips)!RES_0402-68.1K,1%,1/16W,EMPTY,A!!!F325!B!!!!
S!VR_PVDDQ_ABC_PH2_OCSET!R7G30!1!@baseboard_fab2_lib.baseboard_fab2(sch_1):page216_i106@mstr_discrete.res(chips)!RES_0402-68.1K,1%,1/16W,EMPTY,A!!!F324!A!!!!
S!GND!R7G30!2!@baseboard_fab2_lib.baseboard_fab2(sch_1):page216_i106@mstr_discrete.res(chips)!RES_0402-68.1K,1%,1/16W,EMPTY,A!!!F324!B!!!!
S!VR_PVDDQ_DEF_PH1_OCSET!R7A20!1!@baseboard_fab2_lib.baseboard_fab2(sch_1):page219_i108@mstr_discrete.res(chips)!RES_0402-68.1K,1%,1/16W,EMPTY,A!!!F323!A!!!!
S!GND!R7A20!2!@baseboard_fab2_lib.baseboard_fab2(sch_1):page219_i108@mstr_discrete.res(chips)!RES_0402-68.1K,1%,1/16W,EMPTY,A!!!F323!B!!!!
S!VR_PVDDQ_DEF_PH2_OCSET!R7A21!1!@baseboard_fab2_lib.baseboard_fab2(sch_1):page219_i110@mstr_discrete.res(chips)!RES_0402-68.1K,1%,1/16W,EMPTY,A!!!F322!A!!!!
S!GND!R7A21!2!@baseboard_fab2_lib.baseboard_fab2(sch_1):page219_i110@mstr_discrete.res(chips)!RES_0402-68.1K,1%,1/16W,EMPTY,A!!!F322!B!!!!
S!VR_PVDDQ_GHJ_PH1_OCSET!R1G26!1!@baseboard_fab2_lib.baseboard_fab2(sch_1):page224_i112@mstr_discrete.res(chips)!RES_0402-68.1K,1%,1/16W,EMPTY,A!!!F321!A!!!!
S!GND!R1G26!2!@baseboard_fab2_lib.baseboard_fab2(sch_1):page224_i112@mstr_discrete.res(chips)!RES_0402-68.1K,1%,1/16W,EMPTY,A!!!F321!B!!!!
S!VR_PVDDQ_GHJ_PH2_OCSET!R1G25!1!@baseboard_fab2_lib.baseboard_fab2(sch_1):page224_i114@mstr_discrete.res(chips)!RES_0402-68.1K,1%,1/16W,EMPTY,A!!!F320!A!!!!
S!GND!R1G25!2!@baseboard_fab2_lib.baseboard_fab2(sch_1):page224_i114@mstr_discrete.res(chips)!RES_0402-68.1K,1%,1/16W,EMPTY,A!!!F320!B!!!!
S!VR_PVDDQ_KLM_PH2_OCSET!R1A2!1!@baseboard_fab2_lib.baseboard_fab2(sch_1):page227_i105@mstr_discrete.res(chips)!RES_0402-68.1K,1%,1/16W,EMPTY,A!!!F319!A!!!!
S!GND!R1A2!2!@baseboard_fab2_lib.baseboard_fab2(sch_1):page227_i105@mstr_discrete.res(chips)!RES_0402-68.1K,1%,1/16W,EMPTY,A!!!F319!B!!!!
S!VR_PVDDQ_KLM_PH1_OCSET!R1A3!1!@baseboard_fab2_lib.baseboard_fab2(sch_1):page227_i103@mstr_discrete.res(chips)!RES_0402-68.1K,1%,1/16W,EMPTY,A!!!F318!A!!!!
S!GND!R1A3!2!@baseboard_fab2_lib.baseboard_fab2(sch_1):page227_i103@mstr_discrete.res(chips)!RES_0402-68.1K,1%,1/16W,EMPTY,A!!!F318!B!!!!
S!VR_PVNN_PCH_STBY_OCSET!R3L15!1!@baseboard_fab2_lib.baseboard_fab2(sch_1):page236_i118@mstr_discrete.res(chips)!RES_0402-68.1K,1%,1/16W,EMPTY,A!!!F317!A!!!!
S!GND!R3L15!2!@baseboard_fab2_lib.baseboard_fab2(sch_1):page236_i118@mstr_discrete.res(chips)!RES_0402-68.1K,1%,1/16W,EMPTY,A!!!F317!B!!!!
S!VR_P1V05_PCH_STBY_OCSET!R3L14!1!@baseboard_fab2_lib.baseboard_fab2(sch_1):page236_i120@mstr_discrete.res(chips)!RES_0402-68.1K,1%,1/16W,EMPTY,A!!!F316!A!!!!
S!GND!R3L14!2!@baseboard_fab2_lib.baseboard_fab2(sch_1):page236_i120@mstr_discrete.res(chips)!RES_0402-68.1K,1%,1/16W,EMPTY,A!!!F316!B!!!!
S!VR_PVCCIN_CPU1_PH2_OCSET!R1E13!1!@baseboard_fab2_lib.baseboard_fab2(sch_1):page207_i67@mstr_discrete.res(chips)!RES_0402-68.1K,1%,1/16W,EMPTY,A!!!F339!A!!!!
S!GND!R1E13!2!@baseboard_fab2_lib.baseboard_fab2(sch_1):page207_i67@mstr_discrete.res(chips)!RES_0402-68.1K,1%,1/16W,EMPTY,A!!!F339!B!!!!
S!VR_PVCCIN_CPU1_PH1_OCSET!R1E14!1!@baseboard_fab2_lib.baseboard_fab2(sch_1):page207_i68@mstr_discrete.res(chips)!RES_0402-68.1K,1%,1/16W,EMPTY,A!!!F338!A!!!!
S!GND!R1E14!2!@baseboard_fab2_lib.baseboard_fab2(sch_1):page207_i68@mstr_discrete.res(chips)!RES_0402-68.1K,1%,1/16W,EMPTY,A!!!F338!B!!!!
S!VR_PVCCIN_CPU1_PH3_OCSET!R1D55!1!@baseboard_fab2_lib.baseboard_fab2(sch_1):page208_i76@mstr_discrete.res(chips)!RES_0402-68.1K,1%,1/16W,EMPTY,A!!!F337!A!!!!
S!GND!R1D55!2!@baseboard_fab2_lib.baseboard_fab2(sch_1):page208_i76@mstr_discrete.res(chips)!RES_0402-68.1K,1%,1/16W,EMPTY,A!!!F337!B!!!!
S!VR_PVCCIN_CPU1_PH4_OCSET!R1D54!1!@baseboard_fab2_lib.baseboard_fab2(sch_1):page208_i75@mstr_discrete.res(chips)!RES_0402-68.1K,1%,1/16W,EMPTY,A!!!F336!A!!!!
S!GND!R1D54!2!@baseboard_fab2_lib.baseboard_fab2(sch_1):page208_i75@mstr_discrete.res(chips)!RES_0402-68.1K,1%,1/16W,EMPTY,A!!!F336!B!!!!
S!VR_PVCCIN_CPU1_PH5_OCSET!R1D52!1!@baseboard_fab2_lib.baseboard_fab2(sch_1):page209_i59@mstr_discrete.res(chips)!RES_0402-68.1K,1%,1/16W,EMPTY,A!!!F335!A!!!!
S!GND!R1D52!2!@baseboard_fab2_lib.baseboard_fab2(sch_1):page209_i59@mstr_discrete.res(chips)!RES_0402-68.1K,1%,1/16W,EMPTY,A!!!F335!B!!!!
S!VR_PVSA_CPU1_OCSET!R1C37!1!@baseboard_fab2_lib.baseboard_fab2(sch_1):page210_i52@mstr_discrete.res(chips)!RES_0402-68.1K,1%,1/16W,EMPTY,A!!!F334!A!!!!
S!GND!R1C37!2!@baseboard_fab2_lib.baseboard_fab2(sch_1):page210_i52@mstr_discrete.res(chips)!RES_0402-68.1K,1%,1/16W,EMPTY,A!!!F334!B!!!!
S!PVCCIN_CPU0!R5P1!1!@baseboard_fab2_lib.baseboard_fab2(sch_1):page37_i309@mstr_discrete.res(chips)!RES_0603-100.0K,1%,1/10W,CHIP,A!!!F273!A!!!!
S!VSENSE_VCCINR2PMAX_CPU0!R5P1!2!@baseboard_fab2_lib.baseboard_fab2(sch_1):page37_i309@mstr_discrete.res(chips)!RES_0603-100.0K,1%,1/10W,CHIP,A!!!F273!B!!!!
S!PVCCIN_CPU1!RT8P1!1!@baseboard_fab2_lib.baseboard_fab2(sch_1):page71_i49@mstr_discrete.res(chips)!RES_0603-100.0K,1%,1/10W,CHIP,A!!!F272!A!!!!
S!VSENSE_VCCINR2PMAX_CPU1!RT8P1!2!@baseboard_fab2_lib.baseboard_fab2(sch_1):page71_i49@mstr_discrete.res(chips)!RES_0603-100.0K,1%,1/10W,CHIP,A!!!F272!B!!!!
S!VR_PVDDQ_KLM_PH2_BOOT!EU1A1!33!@baseboard_fab2_lib.baseboard_fab2(sch_1):page227_i102@mstr_discrete.ir354xx(chips)!IR354XX_SM-IR35411,IC,H73688-0A!!!F2080!BOOST!!!!
S!P5V_STBY!EU1A1!35!@baseboard_fab2_lib.baseboard_fab2(sch_1):page227_i102@mstr_discrete.ir354xx(chips)!IR354XX_SM-IR35411,IC,H73688-0A!!!F2080!EN!!!!
S!TP_PVDDQ_KLM_PH2_GL_0!EU1A1!6!@baseboard_fab2_lib.baseboard_fab2(sch_1):page227_i102@mstr_discrete.ir354xx(chips)!IR354XX_SM-IR35411,IC,H73688-0A!!!F2080!GL(0)!!!!
S!TP_PVDDQ_KLM_PH2_GL_1!EU1A1!41!@baseboard_fab2_lib.baseboard_fab2(sch_1):page227_i102@mstr_discrete.ir354xx(chips)!IR354XX_SM-IR35411,IC,H73688-0A!!!F2080!GL(1)!!!!
S!ISENSE_PVDDQ_KLM_PH2_IMON!EU1A1!38!@baseboard_fab2_lib.baseboard_fab2(sch_1):page227_i102@mstr_discrete.ir354xx(chips)!IR354XX_SM-IR35411,IC,H73688-0A!!!F2080!IOUT!!!!
S!GND!EU1A1!2!@baseboard_fab2_lib.baseboard_fab2(sch_1):page227_i102@mstr_discrete.ir354xx(chips)!IR354XX_SM-IR35411,IC,H73688-0A!!!F2080!LGND!!!!
S!NC_PVDDQ_KLM_PH2_P31!EU1A1!31!@baseboard_fab2_lib.baseboard_fab2(sch_1):page227_i102@mstr_discrete.ir354xx(chips)!IR354XX_SM-IR35411,IC,H73688-0A!!!F2080!NC!!!!
S!VR_PVDDQ_KLM_PH2_OCSET!EU1A1!37!@baseboard_fab2_lib.baseboard_fab2(sch_1):page227_i102@mstr_discrete.ir354xx(chips)!IR354XX_SM-IR35411,IC,H73688-0A!!!F2080!OCSET!!!!
S!GND!EU1A1!5!@baseboard_fab2_lib.baseboard_fab2(sch_1):page227_i102@mstr_discrete.ir354xx(chips)!IR354XX_SM-IR35411,IC,H73688-0A!!!F2080!PGND(0)!!!!
S!GND!EU1A1!7!@baseboard_fab2_lib.baseboard_fab2(sch_1):page227_i102@mstr_discrete.ir354xx(chips)!IR354XX_SM-IR35411,IC,H73688-0A!!!F2080!PGND(1)!!!!
S!GND!EU1A1!40!@baseboard_fab2_lib.baseboard_fab2(sch_1):page227_i102@mstr_discrete.ir354xx(chips)!IR354XX_SM-IR35411,IC,H73688-0A!!!F2080!PGND(2)!!!!
S!VR_PVDDQ_KLM_PH2_PHASE!EU1A1!32!@baseboard_fab2_lib.baseboard_fab2(sch_1):page227_i102@mstr_discrete.ir354xx(chips)!IR354XX_SM-IR35411,IC,H73688-0A!!!F2080!PHASE!!!!
S!VR_PVDDQ_KLM_PWM2!EU1A1!34!@baseboard_fab2_lib.baseboard_fab2(sch_1):page227_i102@mstr_discrete.ir354xx(chips)!IR354XX_SM-IR35411,IC,H73688-0A!!!F2080!PWM!!!!
S!VR_PVDDQ_KLM_AIREF2!EU1A1!39!@baseboard_fab2_lib.baseboard_fab2(sch_1):page227_i102@mstr_discrete.ir354xx(chips)!IR354XX_SM-IR35411,IC,H73688-0A!!!F2080!REFIN!!!!
S!VR_PVDDQ_KLM_PH2_SW!EU1A1!10!@baseboard_fab2_lib.baseboard_fab2(sch_1):page227_i102@mstr_discrete.ir354xx(chips)!IR354XX_SM-IR35411,IC,H73688-0A!!!F2080!SW!!!!
S!A_TSENSE_PVDDQ_KLM!EU1A1!36!@baseboard_fab2_lib.baseboard_fab2(sch_1):page227_i102@mstr_discrete.ir354xx(chips)!IR354XX_SM-IR35411,IC,H73688-0A!!!F2080!TOUT_FLT!!!!
S!VR_PVDDQ_KLM_PH2_VCIN!EU1A1!3!@baseboard_fab2_lib.baseboard_fab2(sch_1):page227_i102@mstr_discrete.ir354xx(chips)!IR354XX_SM-IR35411,IC,H73688-0A!!!F2080!VCC!!!!
S!P5V_STBY!EU1A1!4!@baseboard_fab2_lib.baseboard_fab2(sch_1):page227_i102@mstr_discrete.ir354xx(chips)!IR354XX_SM-IR35411,IC,H73688-0A!!!F2080!VDRV!!!!
S!VR_FET_SW_P12V_STBY_PVDDQ_KLM!EU1A1!25!@baseboard_fab2_lib.baseboard_fab2(sch_1):page227_i102@mstr_discrete.ir354xx(chips)!IR354XX_SM-IR35411,IC,H73688-0A!!!F2080!VIN(0)!!!!
S!VR_FET_SW_P12V_STBY_PVDDQ_KLM!EU1A1!30!@baseboard_fab2_lib.baseboard_fab2(sch_1):page227_i102@mstr_discrete.ir354xx(chips)!IR354XX_SM-IR35411,IC,H73688-0A!!!F2080!VIN(1)!!!!
S!PVDDQ_KLM!EU1A1!1!@baseboard_fab2_lib.baseboard_fab2(sch_1):page227_i102@mstr_discrete.ir354xx(chips)!IR354XX_SM-IR35411,IC,H73688-0A!!!F2080!VOS!!!!
S!VR_PVDDQ_KLM_PH1_BOOT!EU1A2!33!@baseboard_fab2_lib.baseboard_fab2(sch_1):page227_i101@mstr_discrete.ir354xx(chips)!IR354XX_SM-IR35411,IC,H73688-0A!!!F2079!BOOST!!!!
S!P5V_STBY!EU1A2!35!@baseboard_fab2_lib.baseboard_fab2(sch_1):page227_i101@mstr_discrete.ir354xx(chips)!IR354XX_SM-IR35411,IC,H73688-0A!!!F2079!EN!!!!
S!TP_PVDDQ_KLM_PH1_GL_0!EU1A2!6!@baseboard_fab2_lib.baseboard_fab2(sch_1):page227_i101@mstr_discrete.ir354xx(chips)!IR354XX_SM-IR35411,IC,H73688-0A!!!F2079!GL(0)!!!!
S!TP_PVDDQ_KLM_PH1_GL_1!EU1A2!41!@baseboard_fab2_lib.baseboard_fab2(sch_1):page227_i101@mstr_discrete.ir354xx(chips)!IR354XX_SM-IR35411,IC,H73688-0A!!!F2079!GL(1)!!!!
S!ISENSE_PVDDQ_KLM_PH1_IMON!EU1A2!38!@baseboard_fab2_lib.baseboard_fab2(sch_1):page227_i101@mstr_discrete.ir354xx(chips)!IR354XX_SM-IR35411,IC,H73688-0A!!!F2079!IOUT!!!!
S!GND!EU1A2!2!@baseboard_fab2_lib.baseboard_fab2(sch_1):page227_i101@mstr_discrete.ir354xx(chips)!IR354XX_SM-IR35411,IC,H73688-0A!!!F2079!LGND!!!!
S!NC_PVDDQ_KLM_PH1_P31!EU1A2!31!@baseboard_fab2_lib.baseboard_fab2(sch_1):page227_i101@mstr_discrete.ir354xx(chips)!IR354XX_SM-IR35411,IC,H73688-0A!!!F2079!NC!!!!
S!VR_PVDDQ_KLM_PH1_OCSET!EU1A2!37!@baseboard_fab2_lib.baseboard_fab2(sch_1):page227_i101@mstr_discrete.ir354xx(chips)!IR354XX_SM-IR35411,IC,H73688-0A!!!F2079!OCSET!!!!
S!GND!EU1A2!5!@baseboard_fab2_lib.baseboard_fab2(sch_1):page227_i101@mstr_discrete.ir354xx(chips)!IR354XX_SM-IR35411,IC,H73688-0A!!!F2079!PGND(0)!!!!
S!GND!EU1A2!7!@baseboard_fab2_lib.baseboard_fab2(sch_1):page227_i101@mstr_discrete.ir354xx(chips)!IR354XX_SM-IR35411,IC,H73688-0A!!!F2079!PGND(1)!!!!
S!GND!EU1A2!40!@baseboard_fab2_lib.baseboard_fab2(sch_1):page227_i101@mstr_discrete.ir354xx(chips)!IR354XX_SM-IR35411,IC,H73688-0A!!!F2079!PGND(2)!!!!
S!VR_PVDDQ_KLM_PH1_PHASE!EU1A2!32!@baseboard_fab2_lib.baseboard_fab2(sch_1):page227_i101@mstr_discrete.ir354xx(chips)!IR354XX_SM-IR35411,IC,H73688-0A!!!F2079!PHASE!!!!
S!VR_PVDDQ_KLM_PWM1!EU1A2!34!@baseboard_fab2_lib.baseboard_fab2(sch_1):page227_i101@mstr_discrete.ir354xx(chips)!IR354XX_SM-IR35411,IC,H73688-0A!!!F2079!PWM!!!!
S!VR_PVDDQ_KLM_AIREF1!EU1A2!39!@baseboard_fab2_lib.baseboard_fab2(sch_1):page227_i101@mstr_discrete.ir354xx(chips)!IR354XX_SM-IR35411,IC,H73688-0A!!!F2079!REFIN!!!!
S!VR_PVDDQ_KLM_PH1_SW!EU1A2!10!@baseboard_fab2_lib.baseboard_fab2(sch_1):page227_i101@mstr_discrete.ir354xx(chips)!IR354XX_SM-IR35411,IC,H73688-0A!!!F2079!SW!!!!
S!A_TSENSE_PVDDQ_KLM!EU1A2!36!@baseboard_fab2_lib.baseboard_fab2(sch_1):page227_i101@mstr_discrete.ir354xx(chips)!IR354XX_SM-IR35411,IC,H73688-0A!!!F2079!TOUT_FLT!!!!
S!VR_PVDDQ_KLM_PH1_VCIN!EU1A2!3!@baseboard_fab2_lib.baseboard_fab2(sch_1):page227_i101@mstr_discrete.ir354xx(chips)!IR354XX_SM-IR35411,IC,H73688-0A!!!F2079!VCC!!!!
S!P5V_STBY!EU1A2!4!@baseboard_fab2_lib.baseboard_fab2(sch_1):page227_i101@mstr_discrete.ir354xx(chips)!IR354XX_SM-IR35411,IC,H73688-0A!!!F2079!VDRV!!!!
S!VR_FET_SW_P12V_STBY_PVDDQ_KLM!EU1A2!25!@baseboard_fab2_lib.baseboard_fab2(sch_1):page227_i101@mstr_discrete.ir354xx(chips)!IR354XX_SM-IR35411,IC,H73688-0A!!!F2079!VIN(0)!!!!
S!VR_FET_SW_P12V_STBY_PVDDQ_KLM!EU1A2!30!@baseboard_fab2_lib.baseboard_fab2(sch_1):page227_i101@mstr_discrete.ir354xx(chips)!IR354XX_SM-IR35411,IC,H73688-0A!!!F2079!VIN(1)!!!!
S!PVDDQ_KLM!EU1A2!1!@baseboard_fab2_lib.baseboard_fab2(sch_1):page227_i101@mstr_discrete.ir354xx(chips)!IR354XX_SM-IR35411,IC,H73688-0A!!!F2079!VOS!!!!
S!VR_PVDDQ_GHJ_PH2_BOOT!EU1F1!33!@baseboard_fab2_lib.baseboard_fab2(sch_1):page224_i111@mstr_discrete.ir354xx(chips)!IR354XX_SM-IR35411,IC,H73688-0A!!!F2073!BOOST!!!!
S!P5V_STBY!EU1F1!35!@baseboard_fab2_lib.baseboard_fab2(sch_1):page224_i111@mstr_discrete.ir354xx(chips)!IR354XX_SM-IR35411,IC,H73688-0A!!!F2073!EN!!!!
S!TP_PVDDQ_GHJ_PH2_GL_0!EU1F1!6!@baseboard_fab2_lib.baseboard_fab2(sch_1):page224_i111@mstr_discrete.ir354xx(chips)!IR354XX_SM-IR35411,IC,H73688-0A!!!F2073!GL(0)!!!!
S!TP_PVDDQ_GHJ_PH2_GL_1!EU1F1!41!@baseboard_fab2_lib.baseboard_fab2(sch_1):page224_i111@mstr_discrete.ir354xx(chips)!IR354XX_SM-IR35411,IC,H73688-0A!!!F2073!GL(1)!!!!
S!ISENSE_PVDDQ_GHJ_PH2_IMON!EU1F1!38!@baseboard_fab2_lib.baseboard_fab2(sch_1):page224_i111@mstr_discrete.ir354xx(chips)!IR354XX_SM-IR35411,IC,H73688-0A!!!F2073!IOUT!!!!
S!GND!EU1F1!2!@baseboard_fab2_lib.baseboard_fab2(sch_1):page224_i111@mstr_discrete.ir354xx(chips)!IR354XX_SM-IR35411,IC,H73688-0A!!!F2073!LGND!!!!
S!NC_PVDDQ_GHJ_PH2_P31!EU1F1!31!@baseboard_fab2_lib.baseboard_fab2(sch_1):page224_i111@mstr_discrete.ir354xx(chips)!IR354XX_SM-IR35411,IC,H73688-0A!!!F2073!NC!!!!
S!VR_PVDDQ_GHJ_PH2_OCSET!EU1F1!37!@baseboard_fab2_lib.baseboard_fab2(sch_1):page224_i111@mstr_discrete.ir354xx(chips)!IR354XX_SM-IR35411,IC,H73688-0A!!!F2073!OCSET!!!!
S!GND!EU1F1!5!@baseboard_fab2_lib.baseboard_fab2(sch_1):page224_i111@mstr_discrete.ir354xx(chips)!IR354XX_SM-IR35411,IC,H73688-0A!!!F2073!PGND(0)!!!!
S!GND!EU1F1!7!@baseboard_fab2_lib.baseboard_fab2(sch_1):page224_i111@mstr_discrete.ir354xx(chips)!IR354XX_SM-IR35411,IC,H73688-0A!!!F2073!PGND(1)!!!!
S!GND!EU1F1!40!@baseboard_fab2_lib.baseboard_fab2(sch_1):page224_i111@mstr_discrete.ir354xx(chips)!IR354XX_SM-IR35411,IC,H73688-0A!!!F2073!PGND(2)!!!!
S!VR_PVDDQ_GHJ_PH2_PHASE!EU1F1!32!@baseboard_fab2_lib.baseboard_fab2(sch_1):page224_i111@mstr_discrete.ir354xx(chips)!IR354XX_SM-IR35411,IC,H73688-0A!!!F2073!PHASE!!!!
S!VR_PVDDQ_GHJ_PWM2!EU1F1!34!@baseboard_fab2_lib.baseboard_fab2(sch_1):page224_i111@mstr_discrete.ir354xx(chips)!IR354XX_SM-IR35411,IC,H73688-0A!!!F2073!PWM!!!!
S!VR_PVDDQ_GHJ_AIREF2!EU1F1!39!@baseboard_fab2_lib.baseboard_fab2(sch_1):page224_i111@mstr_discrete.ir354xx(chips)!IR354XX_SM-IR35411,IC,H73688-0A!!!F2073!REFIN!!!!
S!VR_PVDDQ_GHJ_PH2_SW!EU1F1!10!@baseboard_fab2_lib.baseboard_fab2(sch_1):page224_i111@mstr_discrete.ir354xx(chips)!IR354XX_SM-IR35411,IC,H73688-0A!!!F2073!SW!!!!
S!A_TSENSE_PVDDQ_GHJ!EU1F1!36!@baseboard_fab2_lib.baseboard_fab2(sch_1):page224_i111@mstr_discrete.ir354xx(chips)!IR354XX_SM-IR35411,IC,H73688-0A!!!F2073!TOUT_FLT!!!!
S!VR_PVDDQ_GHJ_PH2_VCIN!EU1F1!3!@baseboard_fab2_lib.baseboard_fab2(sch_1):page224_i111@mstr_discrete.ir354xx(chips)!IR354XX_SM-IR35411,IC,H73688-0A!!!F2073!VCC!!!!
S!P5V_STBY!EU1F1!4!@baseboard_fab2_lib.baseboard_fab2(sch_1):page224_i111@mstr_discrete.ir354xx(chips)!IR354XX_SM-IR35411,IC,H73688-0A!!!F2073!VDRV!!!!
S!VR_FET_SW_P12V_STBY_PVDDQ_GHJ!EU1F1!25!@baseboard_fab2_lib.baseboard_fab2(sch_1):page224_i111@mstr_discrete.ir354xx(chips)!IR354XX_SM-IR35411,IC,H73688-0A!!!F2073!VIN(0)!!!!
S!VR_FET_SW_P12V_STBY_PVDDQ_GHJ!EU1F1!30!@baseboard_fab2_lib.baseboard_fab2(sch_1):page224_i111@mstr_discrete.ir354xx(chips)!IR354XX_SM-IR35411,IC,H73688-0A!!!F2073!VIN(1)!!!!
S!PVDDQ_GHJ!EU1F1!1!@baseboard_fab2_lib.baseboard_fab2(sch_1):page224_i111@mstr_discrete.ir354xx(chips)!IR354XX_SM-IR35411,IC,H73688-0A!!!F2073!VOS!!!!
S!VR_PVDDQ_GHJ_PH1_BOOT!EU1G1!33!@baseboard_fab2_lib.baseboard_fab2(sch_1):page224_i110@mstr_discrete.ir354xx(chips)!IR354XX_SM-IR35411,IC,H73688-0A!!!F2072!BOOST!!!!
S!P5V_STBY!EU1G1!35!@baseboard_fab2_lib.baseboard_fab2(sch_1):page224_i110@mstr_discrete.ir354xx(chips)!IR354XX_SM-IR35411,IC,H73688-0A!!!F2072!EN!!!!
S!TP_PVDDQ_GHJ_PH1_GL_0!EU1G1!6!@baseboard_fab2_lib.baseboard_fab2(sch_1):page224_i110@mstr_discrete.ir354xx(chips)!IR354XX_SM-IR35411,IC,H73688-0A!!!F2072!GL(0)!!!!
S!TP_PVDDQ_GHJ_PH1_GL_1!EU1G1!41!@baseboard_fab2_lib.baseboard_fab2(sch_1):page224_i110@mstr_discrete.ir354xx(chips)!IR354XX_SM-IR35411,IC,H73688-0A!!!F2072!GL(1)!!!!
S!ISENSE_PVDDQ_GHJ_PH1_IMON!EU1G1!38!@baseboard_fab2_lib.baseboard_fab2(sch_1):page224_i110@mstr_discrete.ir354xx(chips)!IR354XX_SM-IR35411,IC,H73688-0A!!!F2072!IOUT!!!!
S!GND!EU1G1!2!@baseboard_fab2_lib.baseboard_fab2(sch_1):page224_i110@mstr_discrete.ir354xx(chips)!IR354XX_SM-IR35411,IC,H73688-0A!!!F2072!LGND!!!!
S!NC_PVDDQ_GHJ_PH1_P31!EU1G1!31!@baseboard_fab2_lib.baseboard_fab2(sch_1):page224_i110@mstr_discrete.ir354xx(chips)!IR354XX_SM-IR35411,IC,H73688-0A!!!F2072!NC!!!!
S!VR_PVDDQ_GHJ_PH1_OCSET!EU1G1!37!@baseboard_fab2_lib.baseboard_fab2(sch_1):page224_i110@mstr_discrete.ir354xx(chips)!IR354XX_SM-IR35411,IC,H73688-0A!!!F2072!OCSET!!!!
S!GND!EU1G1!5!@baseboard_fab2_lib.baseboard_fab2(sch_1):page224_i110@mstr_discrete.ir354xx(chips)!IR354XX_SM-IR35411,IC,H73688-0A!!!F2072!PGND(0)!!!!
S!GND!EU1G1!7!@baseboard_fab2_lib.baseboard_fab2(sch_1):page224_i110@mstr_discrete.ir354xx(chips)!IR354XX_SM-IR35411,IC,H73688-0A!!!F2072!PGND(1)!!!!
S!GND!EU1G1!40!@baseboard_fab2_lib.baseboard_fab2(sch_1):page224_i110@mstr_discrete.ir354xx(chips)!IR354XX_SM-IR35411,IC,H73688-0A!!!F2072!PGND(2)!!!!
S!VR_PVDDQ_GHJ_PH1_PHASE!EU1G1!32!@baseboard_fab2_lib.baseboard_fab2(sch_1):page224_i110@mstr_discrete.ir354xx(chips)!IR354XX_SM-IR35411,IC,H73688-0A!!!F2072!PHASE!!!!
S!VR_PVDDQ_GHJ_PWM1!EU1G1!34!@baseboard_fab2_lib.baseboard_fab2(sch_1):page224_i110@mstr_discrete.ir354xx(chips)!IR354XX_SM-IR35411,IC,H73688-0A!!!F2072!PWM!!!!
S!VR_PVDDQ_GHJ_AIREF1!EU1G1!39!@baseboard_fab2_lib.baseboard_fab2(sch_1):page224_i110@mstr_discrete.ir354xx(chips)!IR354XX_SM-IR35411,IC,H73688-0A!!!F2072!REFIN!!!!
S!VR_PVDDQ_GHJ_PH1_SW!EU1G1!10!@baseboard_fab2_lib.baseboard_fab2(sch_1):page224_i110@mstr_discrete.ir354xx(chips)!IR354XX_SM-IR35411,IC,H73688-0A!!!F2072!SW!!!!
S!A_TSENSE_PVDDQ_GHJ!EU1G1!36!@baseboard_fab2_lib.baseboard_fab2(sch_1):page224_i110@mstr_discrete.ir354xx(chips)!IR354XX_SM-IR35411,IC,H73688-0A!!!F2072!TOUT_FLT!!!!
S!VR_PVDDQ_GHJ_PH1_VCIN!EU1G1!3!@baseboard_fab2_lib.baseboard_fab2(sch_1):page224_i110@mstr_discrete.ir354xx(chips)!IR354XX_SM-IR35411,IC,H73688-0A!!!F2072!VCC!!!!
S!P5V_STBY!EU1G1!4!@baseboard_fab2_lib.baseboard_fab2(sch_1):page224_i110@mstr_discrete.ir354xx(chips)!IR354XX_SM-IR35411,IC,H73688-0A!!!F2072!VDRV!!!!
S!VR_FET_SW_P12V_STBY_PVDDQ_GHJ!EU1G1!25!@baseboard_fab2_lib.baseboard_fab2(sch_1):page224_i110@mstr_discrete.ir354xx(chips)!IR354XX_SM-IR35411,IC,H73688-0A!!!F2072!VIN(0)!!!!
S!VR_FET_SW_P12V_STBY_PVDDQ_GHJ!EU1G1!30!@baseboard_fab2_lib.baseboard_fab2(sch_1):page224_i110@mstr_discrete.ir354xx(chips)!IR354XX_SM-IR35411,IC,H73688-0A!!!F2072!VIN(1)!!!!
S!PVDDQ_GHJ!EU1G1!1!@baseboard_fab2_lib.baseboard_fab2(sch_1):page224_i110@mstr_discrete.ir354xx(chips)!IR354XX_SM-IR35411,IC,H73688-0A!!!F2072!VOS!!!!
S!VR_PVDDQ_DEF_PH1_BOOT!EU7A1!33!@baseboard_fab2_lib.baseboard_fab2(sch_1):page219_i106@mstr_discrete.ir354xx(chips)!IR354XX_SM-IR35411,IC,H73688-0A!!!F2066!BOOST!!!!
S!P5V_STBY!EU7A1!35!@baseboard_fab2_lib.baseboard_fab2(sch_1):page219_i106@mstr_discrete.ir354xx(chips)!IR354XX_SM-IR35411,IC,H73688-0A!!!F2066!EN!!!!
S!TP_PVDDQ_DEF_PH1_GL_0!EU7A1!6!@baseboard_fab2_lib.baseboard_fab2(sch_1):page219_i106@mstr_discrete.ir354xx(chips)!IR354XX_SM-IR35411,IC,H73688-0A!!!F2066!GL(0)!!!!
S!TP_PVDDQ_DEF_PH1_GL_1!EU7A1!41!@baseboard_fab2_lib.baseboard_fab2(sch_1):page219_i106@mstr_discrete.ir354xx(chips)!IR354XX_SM-IR35411,IC,H73688-0A!!!F2066!GL(1)!!!!
S!ISENSE_PVDDQ_DEF_PH1_IMON!EU7A1!38!@baseboard_fab2_lib.baseboard_fab2(sch_1):page219_i106@mstr_discrete.ir354xx(chips)!IR354XX_SM-IR35411,IC,H73688-0A!!!F2066!IOUT!!!!
S!GND!EU7A1!2!@baseboard_fab2_lib.baseboard_fab2(sch_1):page219_i106@mstr_discrete.ir354xx(chips)!IR354XX_SM-IR35411,IC,H73688-0A!!!F2066!LGND!!!!
S!NC_PVDDQ_DEF_PH1_P31!EU7A1!31!@baseboard_fab2_lib.baseboard_fab2(sch_1):page219_i106@mstr_discrete.ir354xx(chips)!IR354XX_SM-IR35411,IC,H73688-0A!!!F2066!NC!!!!
S!VR_PVDDQ_DEF_PH1_OCSET!EU7A1!37!@baseboard_fab2_lib.baseboard_fab2(sch_1):page219_i106@mstr_discrete.ir354xx(chips)!IR354XX_SM-IR35411,IC,H73688-0A!!!F2066!OCSET!!!!
S!GND!EU7A1!5!@baseboard_fab2_lib.baseboard_fab2(sch_1):page219_i106@mstr_discrete.ir354xx(chips)!IR354XX_SM-IR35411,IC,H73688-0A!!!F2066!PGND(0)!!!!
S!GND!EU7A1!7!@baseboard_fab2_lib.baseboard_fab2(sch_1):page219_i106@mstr_discrete.ir354xx(chips)!IR354XX_SM-IR35411,IC,H73688-0A!!!F2066!PGND(1)!!!!
S!GND!EU7A1!40!@baseboard_fab2_lib.baseboard_fab2(sch_1):page219_i106@mstr_discrete.ir354xx(chips)!IR354XX_SM-IR35411,IC,H73688-0A!!!F2066!PGND(2)!!!!
S!VR_PVDDQ_DEF_PH1_PHASE!EU7A1!32!@baseboard_fab2_lib.baseboard_fab2(sch_1):page219_i106@mstr_discrete.ir354xx(chips)!IR354XX_SM-IR35411,IC,H73688-0A!!!F2066!PHASE!!!!
S!VR_PVDDQ_DEF_PWM1!EU7A1!34!@baseboard_fab2_lib.baseboard_fab2(sch_1):page219_i106@mstr_discrete.ir354xx(chips)!IR354XX_SM-IR35411,IC,H73688-0A!!!F2066!PWM!!!!
S!VR_PVDDQ_DEF_AIREF1!EU7A1!39!@baseboard_fab2_lib.baseboard_fab2(sch_1):page219_i106@mstr_discrete.ir354xx(chips)!IR354XX_SM-IR35411,IC,H73688-0A!!!F2066!REFIN!!!!
S!VR_PVDDQ_DEF_PH1_SW!EU7A1!10!@baseboard_fab2_lib.baseboard_fab2(sch_1):page219_i106@mstr_discrete.ir354xx(chips)!IR354XX_SM-IR35411,IC,H73688-0A!!!F2066!SW!!!!
S!A_TSENSE_PVDDQ_DEF!EU7A1!36!@baseboard_fab2_lib.baseboard_fab2(sch_1):page219_i106@mstr_discrete.ir354xx(chips)!IR354XX_SM-IR35411,IC,H73688-0A!!!F2066!TOUT_FLT!!!!
S!VR_PVDDQ_DEF_PH1_VCIN!EU7A1!3!@baseboard_fab2_lib.baseboard_fab2(sch_1):page219_i106@mstr_discrete.ir354xx(chips)!IR354XX_SM-IR35411,IC,H73688-0A!!!F2066!VCC!!!!
S!P5V_STBY!EU7A1!4!@baseboard_fab2_lib.baseboard_fab2(sch_1):page219_i106@mstr_discrete.ir354xx(chips)!IR354XX_SM-IR35411,IC,H73688-0A!!!F2066!VDRV!!!!
S!VR_FET_SW_P12V_STBY_PVDDQ_DEF!EU7A1!25!@baseboard_fab2_lib.baseboard_fab2(sch_1):page219_i106@mstr_discrete.ir354xx(chips)!IR354XX_SM-IR35411,IC,H73688-0A!!!F2066!VIN(0)!!!!
S!VR_FET_SW_P12V_STBY_PVDDQ_DEF!EU7A1!30!@baseboard_fab2_lib.baseboard_fab2(sch_1):page219_i106@mstr_discrete.ir354xx(chips)!IR354XX_SM-IR35411,IC,H73688-0A!!!F2066!VIN(1)!!!!
S!PVDDQ_DEF!EU7A1!1!@baseboard_fab2_lib.baseboard_fab2(sch_1):page219_i106@mstr_discrete.ir354xx(chips)!IR354XX_SM-IR35411,IC,H73688-0A!!!F2066!VOS!!!!
S!VR_PVDDQ_DEF_PH2_BOOT!EU7A4!33!@baseboard_fab2_lib.baseboard_fab2(sch_1):page219_i107@mstr_discrete.ir354xx(chips)!IR354XX_SM-IR35411,IC,H73688-0A!!!F2065!BOOST!!!!
S!P5V_STBY!EU7A4!35!@baseboard_fab2_lib.baseboard_fab2(sch_1):page219_i107@mstr_discrete.ir354xx(chips)!IR354XX_SM-IR35411,IC,H73688-0A!!!F2065!EN!!!!
S!TP_PVDDQ_DEF_PH2_GL_0!EU7A4!6!@baseboard_fab2_lib.baseboard_fab2(sch_1):page219_i107@mstr_discrete.ir354xx(chips)!IR354XX_SM-IR35411,IC,H73688-0A!!!F2065!GL(0)!!!!
S!TP_PVDDQ_DEF_PH2_GL_1!EU7A4!41!@baseboard_fab2_lib.baseboard_fab2(sch_1):page219_i107@mstr_discrete.ir354xx(chips)!IR354XX_SM-IR35411,IC,H73688-0A!!!F2065!GL(1)!!!!
S!ISENSE_PVDDQ_DEF_PH2_IMON!EU7A4!38!@baseboard_fab2_lib.baseboard_fab2(sch_1):page219_i107@mstr_discrete.ir354xx(chips)!IR354XX_SM-IR35411,IC,H73688-0A!!!F2065!IOUT!!!!
S!GND!EU7A4!2!@baseboard_fab2_lib.baseboard_fab2(sch_1):page219_i107@mstr_discrete.ir354xx(chips)!IR354XX_SM-IR35411,IC,H73688-0A!!!F2065!LGND!!!!
S!NC_PVDDQ_DEF_PH2_P31!EU7A4!31!@baseboard_fab2_lib.baseboard_fab2(sch_1):page219_i107@mstr_discrete.ir354xx(chips)!IR354XX_SM-IR35411,IC,H73688-0A!!!F2065!NC!!!!
S!VR_PVDDQ_DEF_PH2_OCSET!EU7A4!37!@baseboard_fab2_lib.baseboard_fab2(sch_1):page219_i107@mstr_discrete.ir354xx(chips)!IR354XX_SM-IR35411,IC,H73688-0A!!!F2065!OCSET!!!!
S!GND!EU7A4!5!@baseboard_fab2_lib.baseboard_fab2(sch_1):page219_i107@mstr_discrete.ir354xx(chips)!IR354XX_SM-IR35411,IC,H73688-0A!!!F2065!PGND(0)!!!!
S!GND!EU7A4!7!@baseboard_fab2_lib.baseboard_fab2(sch_1):page219_i107@mstr_discrete.ir354xx(chips)!IR354XX_SM-IR35411,IC,H73688-0A!!!F2065!PGND(1)!!!!
S!GND!EU7A4!40!@baseboard_fab2_lib.baseboard_fab2(sch_1):page219_i107@mstr_discrete.ir354xx(chips)!IR354XX_SM-IR35411,IC,H73688-0A!!!F2065!PGND(2)!!!!
S!VR_PVDDQ_DEF_PH2_PHASE!EU7A4!32!@baseboard_fab2_lib.baseboard_fab2(sch_1):page219_i107@mstr_discrete.ir354xx(chips)!IR354XX_SM-IR35411,IC,H73688-0A!!!F2065!PHASE!!!!
S!VR_PVDDQ_DEF_PWM2!EU7A4!34!@baseboard_fab2_lib.baseboard_fab2(sch_1):page219_i107@mstr_discrete.ir354xx(chips)!IR354XX_SM-IR35411,IC,H73688-0A!!!F2065!PWM!!!!
S!VR_PVDDQ_DEF_AIREF2!EU7A4!39!@baseboard_fab2_lib.baseboard_fab2(sch_1):page219_i107@mstr_discrete.ir354xx(chips)!IR354XX_SM-IR35411,IC,H73688-0A!!!F2065!REFIN!!!!
S!VR_PVDDQ_DEF_PH2_SW!EU7A4!10!@baseboard_fab2_lib.baseboard_fab2(sch_1):page219_i107@mstr_discrete.ir354xx(chips)!IR354XX_SM-IR35411,IC,H73688-0A!!!F2065!SW!!!!
S!A_TSENSE_PVDDQ_DEF!EU7A4!36!@baseboard_fab2_lib.baseboard_fab2(sch_1):page219_i107@mstr_discrete.ir354xx(chips)!IR354XX_SM-IR35411,IC,H73688-0A!!!F2065!TOUT_FLT!!!!
S!VR_PVDDQ_DEF_PH2_VCIN!EU7A4!3!@baseboard_fab2_lib.baseboard_fab2(sch_1):page219_i107@mstr_discrete.ir354xx(chips)!IR354XX_SM-IR35411,IC,H73688-0A!!!F2065!VCC!!!!
S!P5V_STBY!EU7A4!4!@baseboard_fab2_lib.baseboard_fab2(sch_1):page219_i107@mstr_discrete.ir354xx(chips)!IR354XX_SM-IR35411,IC,H73688-0A!!!F2065!VDRV!!!!
S!VR_FET_SW_P12V_STBY_PVDDQ_DEF!EU7A4!25!@baseboard_fab2_lib.baseboard_fab2(sch_1):page219_i107@mstr_discrete.ir354xx(chips)!IR354XX_SM-IR35411,IC,H73688-0A!!!F2065!VIN(0)!!!!
S!VR_FET_SW_P12V_STBY_PVDDQ_DEF!EU7A4!30!@baseboard_fab2_lib.baseboard_fab2(sch_1):page219_i107@mstr_discrete.ir354xx(chips)!IR354XX_SM-IR35411,IC,H73688-0A!!!F2065!VIN(1)!!!!
S!PVDDQ_DEF!EU7A4!1!@baseboard_fab2_lib.baseboard_fab2(sch_1):page219_i107@mstr_discrete.ir354xx(chips)!IR354XX_SM-IR35411,IC,H73688-0A!!!F2065!VOS!!!!
S!VR_PVDDQ_ABC_PH1_BOOT!EU7G2!33!@baseboard_fab2_lib.baseboard_fab2(sch_1):page216_i102@mstr_discrete.ir354xx(chips)!IR354XX_SM-IR35411,IC,H73688-0A!!!F2064!BOOST!!!!
S!P5V_STBY!EU7G2!35!@baseboard_fab2_lib.baseboard_fab2(sch_1):page216_i102@mstr_discrete.ir354xx(chips)!IR354XX_SM-IR35411,IC,H73688-0A!!!F2064!EN!!!!
S!TP_PVDDQ_ABC_PH1_GL_0!EU7G2!6!@baseboard_fab2_lib.baseboard_fab2(sch_1):page216_i102@mstr_discrete.ir354xx(chips)!IR354XX_SM-IR35411,IC,H73688-0A!!!F2064!GL(0)!!!!
S!TP_PVDDQ_ABC_PH1_GL_1!EU7G2!41!@baseboard_fab2_lib.baseboard_fab2(sch_1):page216_i102@mstr_discrete.ir354xx(chips)!IR354XX_SM-IR35411,IC,H73688-0A!!!F2064!GL(1)!!!!
S!ISENSE_PVDDQ_ABC_PH1_IMON!EU7G2!38!@baseboard_fab2_lib.baseboard_fab2(sch_1):page216_i102@mstr_discrete.ir354xx(chips)!IR354XX_SM-IR35411,IC,H73688-0A!!!F2064!IOUT!!!!
S!GND!EU7G2!2!@baseboard_fab2_lib.baseboard_fab2(sch_1):page216_i102@mstr_discrete.ir354xx(chips)!IR354XX_SM-IR35411,IC,H73688-0A!!!F2064!LGND!!!!
S!NC_PVDDQ_ABC_PH1_P31!EU7G2!31!@baseboard_fab2_lib.baseboard_fab2(sch_1):page216_i102@mstr_discrete.ir354xx(chips)!IR354XX_SM-IR35411,IC,H73688-0A!!!F2064!NC!!!!
S!VR_PVDDQ_ABC_PH1_OCSET!EU7G2!37!@baseboard_fab2_lib.baseboard_fab2(sch_1):page216_i102@mstr_discrete.ir354xx(chips)!IR354XX_SM-IR35411,IC,H73688-0A!!!F2064!OCSET!!!!
S!GND!EU7G2!5!@baseboard_fab2_lib.baseboard_fab2(sch_1):page216_i102@mstr_discrete.ir354xx(chips)!IR354XX_SM-IR35411,IC,H73688-0A!!!F2064!PGND(0)!!!!
S!GND!EU7G2!7!@baseboard_fab2_lib.baseboard_fab2(sch_1):page216_i102@mstr_discrete.ir354xx(chips)!IR354XX_SM-IR35411,IC,H73688-0A!!!F2064!PGND(1)!!!!
S!GND!EU7G2!40!@baseboard_fab2_lib.baseboard_fab2(sch_1):page216_i102@mstr_discrete.ir354xx(chips)!IR354XX_SM-IR35411,IC,H73688-0A!!!F2064!PGND(2)!!!!
S!VR_PVDDQ_ABC_PH1_PHASE!EU7G2!32!@baseboard_fab2_lib.baseboard_fab2(sch_1):page216_i102@mstr_discrete.ir354xx(chips)!IR354XX_SM-IR35411,IC,H73688-0A!!!F2064!PHASE!!!!
S!VR_PVDDQ_ABC_PWM1!EU7G2!34!@baseboard_fab2_lib.baseboard_fab2(sch_1):page216_i102@mstr_discrete.ir354xx(chips)!IR354XX_SM-IR35411,IC,H73688-0A!!!F2064!PWM!!!!
S!VR_PVDDQ_ABC_AIREF1!EU7G2!39!@baseboard_fab2_lib.baseboard_fab2(sch_1):page216_i102@mstr_discrete.ir354xx(chips)!IR354XX_SM-IR35411,IC,H73688-0A!!!F2064!REFIN!!!!
S!VR_PVDDQ_ABC_PH1_SW!EU7G2!10!@baseboard_fab2_lib.baseboard_fab2(sch_1):page216_i102@mstr_discrete.ir354xx(chips)!IR354XX_SM-IR35411,IC,H73688-0A!!!F2064!SW!!!!
S!A_TSENSE_PVDDQ_ABC!EU7G2!36!@baseboard_fab2_lib.baseboard_fab2(sch_1):page216_i102@mstr_discrete.ir354xx(chips)!IR354XX_SM-IR35411,IC,H73688-0A!!!F2064!TOUT_FLT!!!!
S!VR_PVDDQ_ABC_PH1_VCIN!EU7G2!3!@baseboard_fab2_lib.baseboard_fab2(sch_1):page216_i102@mstr_discrete.ir354xx(chips)!IR354XX_SM-IR35411,IC,H73688-0A!!!F2064!VCC!!!!
S!P5V_STBY!EU7G2!4!@baseboard_fab2_lib.baseboard_fab2(sch_1):page216_i102@mstr_discrete.ir354xx(chips)!IR354XX_SM-IR35411,IC,H73688-0A!!!F2064!VDRV!!!!
S!VR_FET_SW_P12V_STBY_PVDDQ_ABC!EU7G2!25!@baseboard_fab2_lib.baseboard_fab2(sch_1):page216_i102@mstr_discrete.ir354xx(chips)!IR354XX_SM-IR35411,IC,H73688-0A!!!F2064!VIN(0)!!!!
S!VR_FET_SW_P12V_STBY_PVDDQ_ABC!EU7G2!30!@baseboard_fab2_lib.baseboard_fab2(sch_1):page216_i102@mstr_discrete.ir354xx(chips)!IR354XX_SM-IR35411,IC,H73688-0A!!!F2064!VIN(1)!!!!
S!PVDDQ_ABC!EU7G2!1!@baseboard_fab2_lib.baseboard_fab2(sch_1):page216_i102@mstr_discrete.ir354xx(chips)!IR354XX_SM-IR35411,IC,H73688-0A!!!F2064!VOS!!!!
S!VR_PVDDQ_ABC_PH2_BOOT!EU7G3!33!@baseboard_fab2_lib.baseboard_fab2(sch_1):page216_i103@mstr_discrete.ir354xx(chips)!IR354XX_SM-IR35411,IC,H73688-0A!!!F2063!BOOST!!!!
S!P5V_STBY!EU7G3!35!@baseboard_fab2_lib.baseboard_fab2(sch_1):page216_i103@mstr_discrete.ir354xx(chips)!IR354XX_SM-IR35411,IC,H73688-0A!!!F2063!EN!!!!
S!TP_PVDDQ_ABC_PH2_GL_0!EU7G3!6!@baseboard_fab2_lib.baseboard_fab2(sch_1):page216_i103@mstr_discrete.ir354xx(chips)!IR354XX_SM-IR35411,IC,H73688-0A!!!F2063!GL(0)!!!!
S!TP_PVDDQ_ABC_PH2_GL_1!EU7G3!41!@baseboard_fab2_lib.baseboard_fab2(sch_1):page216_i103@mstr_discrete.ir354xx(chips)!IR354XX_SM-IR35411,IC,H73688-0A!!!F2063!GL(1)!!!!
S!ISENSE_PVDDQ_ABC_PH2_IMON!EU7G3!38!@baseboard_fab2_lib.baseboard_fab2(sch_1):page216_i103@mstr_discrete.ir354xx(chips)!IR354XX_SM-IR35411,IC,H73688-0A!!!F2063!IOUT!!!!
S!GND!EU7G3!2!@baseboard_fab2_lib.baseboard_fab2(sch_1):page216_i103@mstr_discrete.ir354xx(chips)!IR354XX_SM-IR35411,IC,H73688-0A!!!F2063!LGND!!!!
S!NC_PVDDQ_ABC_PH2_P31!EU7G3!31!@baseboard_fab2_lib.baseboard_fab2(sch_1):page216_i103@mstr_discrete.ir354xx(chips)!IR354XX_SM-IR35411,IC,H73688-0A!!!F2063!NC!!!!
S!VR_PVDDQ_ABC_PH2_OCSET!EU7G3!37!@baseboard_fab2_lib.baseboard_fab2(sch_1):page216_i103@mstr_discrete.ir354xx(chips)!IR354XX_SM-IR35411,IC,H73688-0A!!!F2063!OCSET!!!!
S!GND!EU7G3!5!@baseboard_fab2_lib.baseboard_fab2(sch_1):page216_i103@mstr_discrete.ir354xx(chips)!IR354XX_SM-IR35411,IC,H73688-0A!!!F2063!PGND(0)!!!!
S!GND!EU7G3!7!@baseboard_fab2_lib.baseboard_fab2(sch_1):page216_i103@mstr_discrete.ir354xx(chips)!IR354XX_SM-IR35411,IC,H73688-0A!!!F2063!PGND(1)!!!!
S!GND!EU7G3!40!@baseboard_fab2_lib.baseboard_fab2(sch_1):page216_i103@mstr_discrete.ir354xx(chips)!IR354XX_SM-IR35411,IC,H73688-0A!!!F2063!PGND(2)!!!!
S!VR_PVDDQ_ABC_PH2_PHASE!EU7G3!32!@baseboard_fab2_lib.baseboard_fab2(sch_1):page216_i103@mstr_discrete.ir354xx(chips)!IR354XX_SM-IR35411,IC,H73688-0A!!!F2063!PHASE!!!!
S!VR_PVDDQ_ABC_PWM2!EU7G3!34!@baseboard_fab2_lib.baseboard_fab2(sch_1):page216_i103@mstr_discrete.ir354xx(chips)!IR354XX_SM-IR35411,IC,H73688-0A!!!F2063!PWM!!!!
S!VR_PVDDQ_ABC_AIREF2!EU7G3!39!@baseboard_fab2_lib.baseboard_fab2(sch_1):page216_i103@mstr_discrete.ir354xx(chips)!IR354XX_SM-IR35411,IC,H73688-0A!!!F2063!REFIN!!!!
S!VR_PVDDQ_ABC_PH2_SW!EU7G3!10!@baseboard_fab2_lib.baseboard_fab2(sch_1):page216_i103@mstr_discrete.ir354xx(chips)!IR354XX_SM-IR35411,IC,H73688-0A!!!F2063!SW!!!!
S!A_TSENSE_PVDDQ_ABC!EU7G3!36!@baseboard_fab2_lib.baseboard_fab2(sch_1):page216_i103@mstr_discrete.ir354xx(chips)!IR354XX_SM-IR35411,IC,H73688-0A!!!F2063!TOUT_FLT!!!!
S!VR_PVDDQ_ABC_PH2_VCIN!EU7G3!3!@baseboard_fab2_lib.baseboard_fab2(sch_1):page216_i103@mstr_discrete.ir354xx(chips)!IR354XX_SM-IR35411,IC,H73688-0A!!!F2063!VCC!!!!
S!P5V_STBY!EU7G3!4!@baseboard_fab2_lib.baseboard_fab2(sch_1):page216_i103@mstr_discrete.ir354xx(chips)!IR354XX_SM-IR35411,IC,H73688-0A!!!F2063!VDRV!!!!
S!VR_FET_SW_P12V_STBY_PVDDQ_ABC!EU7G3!25!@baseboard_fab2_lib.baseboard_fab2(sch_1):page216_i103@mstr_discrete.ir354xx(chips)!IR354XX_SM-IR35411,IC,H73688-0A!!!F2063!VIN(0)!!!!
S!VR_FET_SW_P12V_STBY_PVDDQ_ABC!EU7G3!30!@baseboard_fab2_lib.baseboard_fab2(sch_1):page216_i103@mstr_discrete.ir354xx(chips)!IR354XX_SM-IR35411,IC,H73688-0A!!!F2063!VIN(1)!!!!
S!PVDDQ_ABC!EU7G3!1!@baseboard_fab2_lib.baseboard_fab2(sch_1):page216_i103@mstr_discrete.ir354xx(chips)!IR354XX_SM-IR35411,IC,H73688-0A!!!F2063!VOS!!!!
S!VR_PVCCIN_CPU0_PH2_BOOT!EU4D6!33!@baseboard_fab2_lib.baseboard_fab2(sch_1):page202_i64@mstr_discrete.ir354xx(chips)!IR354XX_SM-IR35411,IC,H73688-0A!!!F2068!BOOST!!!!
S!P5V_STBY!EU4D6!35!@baseboard_fab2_lib.baseboard_fab2(sch_1):page202_i64@mstr_discrete.ir354xx(chips)!IR354XX_SM-IR35411,IC,H73688-0A!!!F2068!EN!!!!
S!TP_PVCCIN_CPU0_PH2_GL_0!EU4D6!6!@baseboard_fab2_lib.baseboard_fab2(sch_1):page202_i64@mstr_discrete.ir354xx(chips)!IR354XX_SM-IR35411,IC,H73688-0A!!!F2068!GL(0)!!!!
S!TP_PVCCIN_CPU0_PH2_GL_1!EU4D6!41!@baseboard_fab2_lib.baseboard_fab2(sch_1):page202_i64@mstr_discrete.ir354xx(chips)!IR354XX_SM-IR35411,IC,H73688-0A!!!F2068!GL(1)!!!!
S!ISENSE_PVCCIN_CPU0_PH2_IMON!EU4D6!38!@baseboard_fab2_lib.baseboard_fab2(sch_1):page202_i64@mstr_discrete.ir354xx(chips)!IR354XX_SM-IR35411,IC,H73688-0A!!!F2068!IOUT!!!!
S!GND!EU4D6!2!@baseboard_fab2_lib.baseboard_fab2(sch_1):page202_i64@mstr_discrete.ir354xx(chips)!IR354XX_SM-IR35411,IC,H73688-0A!!!F2068!LGND!!!!
S!NC_PVCCIN_CPU0_PH2_P31!EU4D6!31!@baseboard_fab2_lib.baseboard_fab2(sch_1):page202_i64@mstr_discrete.ir354xx(chips)!IR354XX_SM-IR35411,IC,H73688-0A!!!F2068!NC!!!!
S!VR_PVCCIN_CPU0_PH2_OCSET!EU4D6!37!@baseboard_fab2_lib.baseboard_fab2(sch_1):page202_i64@mstr_discrete.ir354xx(chips)!IR354XX_SM-IR35411,IC,H73688-0A!!!F2068!OCSET!!!!
S!GND!EU4D6!5!@baseboard_fab2_lib.baseboard_fab2(sch_1):page202_i64@mstr_discrete.ir354xx(chips)!IR354XX_SM-IR35411,IC,H73688-0A!!!F2068!PGND(0)!!!!
S!GND!EU4D6!7!@baseboard_fab2_lib.baseboard_fab2(sch_1):page202_i64@mstr_discrete.ir354xx(chips)!IR354XX_SM-IR35411,IC,H73688-0A!!!F2068!PGND(1)!!!!
S!GND!EU4D6!40!@baseboard_fab2_lib.baseboard_fab2(sch_1):page202_i64@mstr_discrete.ir354xx(chips)!IR354XX_SM-IR35411,IC,H73688-0A!!!F2068!PGND(2)!!!!
S!VR_PVCCIN_CPU0_PH2_PHASE!EU4D6!32!@baseboard_fab2_lib.baseboard_fab2(sch_1):page202_i64@mstr_discrete.ir354xx(chips)!IR354XX_SM-IR35411,IC,H73688-0A!!!F2068!PHASE!!!!
S!VR_PVCCIN_CPU0_PWM2!EU4D6!34!@baseboard_fab2_lib.baseboard_fab2(sch_1):page202_i64@mstr_discrete.ir354xx(chips)!IR354XX_SM-IR35411,IC,H73688-0A!!!F2068!PWM!!!!
S!VR_PVCCIN_CPU0_AIREF2!EU4D6!39!@baseboard_fab2_lib.baseboard_fab2(sch_1):page202_i64@mstr_discrete.ir354xx(chips)!IR354XX_SM-IR35411,IC,H73688-0A!!!F2068!REFIN!!!!
S!VR_PVCCIN_CPU0_PHASE2!EU4D6!10!@baseboard_fab2_lib.baseboard_fab2(sch_1):page202_i64@mstr_discrete.ir354xx(chips)!IR354XX_SM-IR35411,IC,H73688-0A!!!F2068!SW!!!!
S!A_TSENSE_PVCCIN_CPU0!EU4D6!36!@baseboard_fab2_lib.baseboard_fab2(sch_1):page202_i64@mstr_discrete.ir354xx(chips)!IR354XX_SM-IR35411,IC,H73688-0A!!!F2068!TOUT_FLT!!!!
S!VR_PVCCIN_CPU0_PH2_VCIN!EU4D6!3!@baseboard_fab2_lib.baseboard_fab2(sch_1):page202_i64@mstr_discrete.ir354xx(chips)!IR354XX_SM-IR35411,IC,H73688-0A!!!F2068!VCC!!!!
S!P5V_STBY!EU4D6!4!@baseboard_fab2_lib.baseboard_fab2(sch_1):page202_i64@mstr_discrete.ir354xx(chips)!IR354XX_SM-IR35411,IC,H73688-0A!!!F2068!VDRV!!!!
S!VR_FET_SW_P12V_STBY_PVCCIN_CPU0!EU4D6!25!@baseboard_fab2_lib.baseboard_fab2(sch_1):page202_i64@mstr_discrete.ir354xx(chips)!IR354XX_SM-IR35411,IC,H73688-0A!!!F2068!VIN(0)!!!!
S!VR_FET_SW_P12V_STBY_PVCCIN_CPU0!EU4D6!30!@baseboard_fab2_lib.baseboard_fab2(sch_1):page202_i64@mstr_discrete.ir354xx(chips)!IR354XX_SM-IR35411,IC,H73688-0A!!!F2068!VIN(1)!!!!
S!PVCCIN_CPU0!EU4D6!1!@baseboard_fab2_lib.baseboard_fab2(sch_1):page202_i64@mstr_discrete.ir354xx(chips)!IR354XX_SM-IR35411,IC,H73688-0A!!!F2068!VOS!!!!
S!VR_PVCCIN_CPU1_PH5_BOOT!EU1C3!33!@baseboard_fab2_lib.baseboard_fab2(sch_1):page209_i56@mstr_discrete.ir354xx(chips)!IR354XX_SM-IR35411,IC,H73688-0A!!!F2078!BOOST!!!!
S!P5V_STBY!EU1C3!35!@baseboard_fab2_lib.baseboard_fab2(sch_1):page209_i56@mstr_discrete.ir354xx(chips)!IR354XX_SM-IR35411,IC,H73688-0A!!!F2078!EN!!!!
S!TP_PVCCIN_CPU1_PH5_GL_0!EU1C3!6!@baseboard_fab2_lib.baseboard_fab2(sch_1):page209_i56@mstr_discrete.ir354xx(chips)!IR354XX_SM-IR35411,IC,H73688-0A!!!F2078!GL(0)!!!!
S!TP_PVCCIN_CPU1_PH5_GL_1!EU1C3!41!@baseboard_fab2_lib.baseboard_fab2(sch_1):page209_i56@mstr_discrete.ir354xx(chips)!IR354XX_SM-IR35411,IC,H73688-0A!!!F2078!GL(1)!!!!
S!ISENSE_PVCCIN_CPU1_PH5_IMON!EU1C3!38!@baseboard_fab2_lib.baseboard_fab2(sch_1):page209_i56@mstr_discrete.ir354xx(chips)!IR354XX_SM-IR35411,IC,H73688-0A!!!F2078!IOUT!!!!
S!GND!EU1C3!2!@baseboard_fab2_lib.baseboard_fab2(sch_1):page209_i56@mstr_discrete.ir354xx(chips)!IR354XX_SM-IR35411,IC,H73688-0A!!!F2078!LGND!!!!
S!NC_PVCCIN_CPU1_PH5_P31!EU1C3!31!@baseboard_fab2_lib.baseboard_fab2(sch_1):page209_i56@mstr_discrete.ir354xx(chips)!IR354XX_SM-IR35411,IC,H73688-0A!!!F2078!NC!!!!
S!VR_PVCCIN_CPU1_PH5_OCSET!EU1C3!37!@baseboard_fab2_lib.baseboard_fab2(sch_1):page209_i56@mstr_discrete.ir354xx(chips)!IR354XX_SM-IR35411,IC,H73688-0A!!!F2078!OCSET!!!!
S!GND!EU1C3!5!@baseboard_fab2_lib.baseboard_fab2(sch_1):page209_i56@mstr_discrete.ir354xx(chips)!IR354XX_SM-IR35411,IC,H73688-0A!!!F2078!PGND(0)!!!!
S!GND!EU1C3!7!@baseboard_fab2_lib.baseboard_fab2(sch_1):page209_i56@mstr_discrete.ir354xx(chips)!IR354XX_SM-IR35411,IC,H73688-0A!!!F2078!PGND(1)!!!!
S!GND!EU1C3!40!@baseboard_fab2_lib.baseboard_fab2(sch_1):page209_i56@mstr_discrete.ir354xx(chips)!IR354XX_SM-IR35411,IC,H73688-0A!!!F2078!PGND(2)!!!!
S!VR_PVCCIN_CPU1_PH5_PHASE!EU1C3!32!@baseboard_fab2_lib.baseboard_fab2(sch_1):page209_i56@mstr_discrete.ir354xx(chips)!IR354XX_SM-IR35411,IC,H73688-0A!!!F2078!PHASE!!!!
S!VR_PVCCIN_CPU1_PWM5!EU1C3!34!@baseboard_fab2_lib.baseboard_fab2(sch_1):page209_i56@mstr_discrete.ir354xx(chips)!IR354XX_SM-IR35411,IC,H73688-0A!!!F2078!PWM!!!!
S!VR_PVCCIN_CPU1_AIREF5!EU1C3!39!@baseboard_fab2_lib.baseboard_fab2(sch_1):page209_i56@mstr_discrete.ir354xx(chips)!IR354XX_SM-IR35411,IC,H73688-0A!!!F2078!REFIN!!!!
S!VR_PVCCIN_CPU1_PHASE5!EU1C3!10!@baseboard_fab2_lib.baseboard_fab2(sch_1):page209_i56@mstr_discrete.ir354xx(chips)!IR354XX_SM-IR35411,IC,H73688-0A!!!F2078!SW!!!!
S!A_TSENSE_PVCCIN_CPU1!EU1C3!36!@baseboard_fab2_lib.baseboard_fab2(sch_1):page209_i56@mstr_discrete.ir354xx(chips)!IR354XX_SM-IR35411,IC,H73688-0A!!!F2078!TOUT_FLT!!!!
S!VR_PVCCIN_CPU1_PH5_VCIN!EU1C3!3!@baseboard_fab2_lib.baseboard_fab2(sch_1):page209_i56@mstr_discrete.ir354xx(chips)!IR354XX_SM-IR35411,IC,H73688-0A!!!F2078!VCC!!!!
S!P5V_STBY!EU1C3!4!@baseboard_fab2_lib.baseboard_fab2(sch_1):page209_i56@mstr_discrete.ir354xx(chips)!IR354XX_SM-IR35411,IC,H73688-0A!!!F2078!VDRV!!!!
S!VR_FET_SW_P12V_STBY_PVCCIN_CPU1!EU1C3!25!@baseboard_fab2_lib.baseboard_fab2(sch_1):page209_i56@mstr_discrete.ir354xx(chips)!IR354XX_SM-IR35411,IC,H73688-0A!!!F2078!VIN(0)!!!!
S!VR_FET_SW_P12V_STBY_PVCCIN_CPU1!EU1C3!30!@baseboard_fab2_lib.baseboard_fab2(sch_1):page209_i56@mstr_discrete.ir354xx(chips)!IR354XX_SM-IR35411,IC,H73688-0A!!!F2078!VIN(1)!!!!
S!PVCCIN_CPU1!EU1C3!1!@baseboard_fab2_lib.baseboard_fab2(sch_1):page209_i56@mstr_discrete.ir354xx(chips)!IR354XX_SM-IR35411,IC,H73688-0A!!!F2078!VOS!!!!
S!VR_PVCCIN_CPU1_PH4_BOOT!EU1D1!33!@baseboard_fab2_lib.baseboard_fab2(sch_1):page208_i71@mstr_discrete.ir354xx(chips)!IR354XX_SM-IR35411,IC,H73688-0A!!!F2077!BOOST!!!!
S!P5V_STBY!EU1D1!35!@baseboard_fab2_lib.baseboard_fab2(sch_1):page208_i71@mstr_discrete.ir354xx(chips)!IR354XX_SM-IR35411,IC,H73688-0A!!!F2077!EN!!!!
S!TP_PVCCIN_CPU1_PH4_GL_0!EU1D1!6!@baseboard_fab2_lib.baseboard_fab2(sch_1):page208_i71@mstr_discrete.ir354xx(chips)!IR354XX_SM-IR35411,IC,H73688-0A!!!F2077!GL(0)!!!!
S!TP_PVCCIN_CPU1_PH4_GL_1!EU1D1!41!@baseboard_fab2_lib.baseboard_fab2(sch_1):page208_i71@mstr_discrete.ir354xx(chips)!IR354XX_SM-IR35411,IC,H73688-0A!!!F2077!GL(1)!!!!
S!ISENSE_PVCCIN_CPU1_PH4_IMON!EU1D1!38!@baseboard_fab2_lib.baseboard_fab2(sch_1):page208_i71@mstr_discrete.ir354xx(chips)!IR354XX_SM-IR35411,IC,H73688-0A!!!F2077!IOUT!!!!
S!GND!EU1D1!2!@baseboard_fab2_lib.baseboard_fab2(sch_1):page208_i71@mstr_discrete.ir354xx(chips)!IR354XX_SM-IR35411,IC,H73688-0A!!!F2077!LGND!!!!
S!NC_PVCCIN_CPU1_PH4_P31!EU1D1!31!@baseboard_fab2_lib.baseboard_fab2(sch_1):page208_i71@mstr_discrete.ir354xx(chips)!IR354XX_SM-IR35411,IC,H73688-0A!!!F2077!NC!!!!
S!VR_PVCCIN_CPU1_PH4_OCSET!EU1D1!37!@baseboard_fab2_lib.baseboard_fab2(sch_1):page208_i71@mstr_discrete.ir354xx(chips)!IR354XX_SM-IR35411,IC,H73688-0A!!!F2077!OCSET!!!!
S!GND!EU1D1!5!@baseboard_fab2_lib.baseboard_fab2(sch_1):page208_i71@mstr_discrete.ir354xx(chips)!IR354XX_SM-IR35411,IC,H73688-0A!!!F2077!PGND(0)!!!!
S!GND!EU1D1!7!@baseboard_fab2_lib.baseboard_fab2(sch_1):page208_i71@mstr_discrete.ir354xx(chips)!IR354XX_SM-IR35411,IC,H73688-0A!!!F2077!PGND(1)!!!!
S!GND!EU1D1!40!@baseboard_fab2_lib.baseboard_fab2(sch_1):page208_i71@mstr_discrete.ir354xx(chips)!IR354XX_SM-IR35411,IC,H73688-0A!!!F2077!PGND(2)!!!!
S!VR_PVCCIN_CPU1_PH4_PHASE!EU1D1!32!@baseboard_fab2_lib.baseboard_fab2(sch_1):page208_i71@mstr_discrete.ir354xx(chips)!IR354XX_SM-IR35411,IC,H73688-0A!!!F2077!PHASE!!!!
S!VR_PVCCIN_CPU1_PWM4!EU1D1!34!@baseboard_fab2_lib.baseboard_fab2(sch_1):page208_i71@mstr_discrete.ir354xx(chips)!IR354XX_SM-IR35411,IC,H73688-0A!!!F2077!PWM!!!!
S!VR_PVCCIN_CPU1_AIREF4!EU1D1!39!@baseboard_fab2_lib.baseboard_fab2(sch_1):page208_i71@mstr_discrete.ir354xx(chips)!IR354XX_SM-IR35411,IC,H73688-0A!!!F2077!REFIN!!!!
S!VR_PVCCIN_CPU1_PHASE4!EU1D1!10!@baseboard_fab2_lib.baseboard_fab2(sch_1):page208_i71@mstr_discrete.ir354xx(chips)!IR354XX_SM-IR35411,IC,H73688-0A!!!F2077!SW!!!!
S!A_TSENSE_PVCCIN_CPU1!EU1D1!36!@baseboard_fab2_lib.baseboard_fab2(sch_1):page208_i71@mstr_discrete.ir354xx(chips)!IR354XX_SM-IR35411,IC,H73688-0A!!!F2077!TOUT_FLT!!!!
S!VR_PVCCIN_CPU1_PH4_VCIN!EU1D1!3!@baseboard_fab2_lib.baseboard_fab2(sch_1):page208_i71@mstr_discrete.ir354xx(chips)!IR354XX_SM-IR35411,IC,H73688-0A!!!F2077!VCC!!!!
S!P5V_STBY!EU1D1!4!@baseboard_fab2_lib.baseboard_fab2(sch_1):page208_i71@mstr_discrete.ir354xx(chips)!IR354XX_SM-IR35411,IC,H73688-0A!!!F2077!VDRV!!!!
S!VR_FET_SW_P12V_STBY_PVCCIN_CPU1!EU1D1!25!@baseboard_fab2_lib.baseboard_fab2(sch_1):page208_i71@mstr_discrete.ir354xx(chips)!IR354XX_SM-IR35411,IC,H73688-0A!!!F2077!VIN(0)!!!!
S!VR_FET_SW_P12V_STBY_PVCCIN_CPU1!EU1D1!30!@baseboard_fab2_lib.baseboard_fab2(sch_1):page208_i71@mstr_discrete.ir354xx(chips)!IR354XX_SM-IR35411,IC,H73688-0A!!!F2077!VIN(1)!!!!
S!PVCCIN_CPU1!EU1D1!1!@baseboard_fab2_lib.baseboard_fab2(sch_1):page208_i71@mstr_discrete.ir354xx(chips)!IR354XX_SM-IR35411,IC,H73688-0A!!!F2077!VOS!!!!
S!VR_PVCCIN_CPU0_PH3_BOOT!EU4D3!33!@baseboard_fab2_lib.baseboard_fab2(sch_1):page203_i70@mstr_discrete.ir354xx(chips)!IR354XX_SM-IR35411,IC,H73688-0A!!!F2069!BOOST!!!!
S!P5V_STBY!EU4D3!35!@baseboard_fab2_lib.baseboard_fab2(sch_1):page203_i70@mstr_discrete.ir354xx(chips)!IR354XX_SM-IR35411,IC,H73688-0A!!!F2069!EN!!!!
S!TP_PVCCIN_CPU0_PH3_GL_0!EU4D3!6!@baseboard_fab2_lib.baseboard_fab2(sch_1):page203_i70@mstr_discrete.ir354xx(chips)!IR354XX_SM-IR35411,IC,H73688-0A!!!F2069!GL(0)!!!!
S!TP_PVCCIN_CPU0_PH3_GL_1!EU4D3!41!@baseboard_fab2_lib.baseboard_fab2(sch_1):page203_i70@mstr_discrete.ir354xx(chips)!IR354XX_SM-IR35411,IC,H73688-0A!!!F2069!GL(1)!!!!
S!ISENSE_PVCCIN_CPU0_PH3_IMON!EU4D3!38!@baseboard_fab2_lib.baseboard_fab2(sch_1):page203_i70@mstr_discrete.ir354xx(chips)!IR354XX_SM-IR35411,IC,H73688-0A!!!F2069!IOUT!!!!
S!GND!EU4D3!2!@baseboard_fab2_lib.baseboard_fab2(sch_1):page203_i70@mstr_discrete.ir354xx(chips)!IR354XX_SM-IR35411,IC,H73688-0A!!!F2069!LGND!!!!
S!NC_PVCCIN_CPU0_PH3_P31!EU4D3!31!@baseboard_fab2_lib.baseboard_fab2(sch_1):page203_i70@mstr_discrete.ir354xx(chips)!IR354XX_SM-IR35411,IC,H73688-0A!!!F2069!NC!!!!
S!VR_PVCCIN_CPU0_PH3_OCSET!EU4D3!37!@baseboard_fab2_lib.baseboard_fab2(sch_1):page203_i70@mstr_discrete.ir354xx(chips)!IR354XX_SM-IR35411,IC,H73688-0A!!!F2069!OCSET!!!!
S!GND!EU4D3!5!@baseboard_fab2_lib.baseboard_fab2(sch_1):page203_i70@mstr_discrete.ir354xx(chips)!IR354XX_SM-IR35411,IC,H73688-0A!!!F2069!PGND(0)!!!!
S!GND!EU4D3!7!@baseboard_fab2_lib.baseboard_fab2(sch_1):page203_i70@mstr_discrete.ir354xx(chips)!IR354XX_SM-IR35411,IC,H73688-0A!!!F2069!PGND(1)!!!!
S!GND!EU4D3!40!@baseboard_fab2_lib.baseboard_fab2(sch_1):page203_i70@mstr_discrete.ir354xx(chips)!IR354XX_SM-IR35411,IC,H73688-0A!!!F2069!PGND(2)!!!!
S!VR_PVCCIN_CPU0_PH3_PHASE!EU4D3!32!@baseboard_fab2_lib.baseboard_fab2(sch_1):page203_i70@mstr_discrete.ir354xx(chips)!IR354XX_SM-IR35411,IC,H73688-0A!!!F2069!PHASE!!!!
S!VR_PVCCIN_CPU0_PWM3!EU4D3!34!@baseboard_fab2_lib.baseboard_fab2(sch_1):page203_i70@mstr_discrete.ir354xx(chips)!IR354XX_SM-IR35411,IC,H73688-0A!!!F2069!PWM!!!!
S!VR_PVCCIN_CPU0_AIREF3!EU4D3!39!@baseboard_fab2_lib.baseboard_fab2(sch_1):page203_i70@mstr_discrete.ir354xx(chips)!IR354XX_SM-IR35411,IC,H73688-0A!!!F2069!REFIN!!!!
S!VR_PVCCIN_CPU0_PHASE3!EU4D3!10!@baseboard_fab2_lib.baseboard_fab2(sch_1):page203_i70@mstr_discrete.ir354xx(chips)!IR354XX_SM-IR35411,IC,H73688-0A!!!F2069!SW!!!!
S!A_TSENSE_PVCCIN_CPU0!EU4D3!36!@baseboard_fab2_lib.baseboard_fab2(sch_1):page203_i70@mstr_discrete.ir354xx(chips)!IR354XX_SM-IR35411,IC,H73688-0A!!!F2069!TOUT_FLT!!!!
S!VR_PVCCIN_CPU0_PH3_VCIN!EU4D3!3!@baseboard_fab2_lib.baseboard_fab2(sch_1):page203_i70@mstr_discrete.ir354xx(chips)!IR354XX_SM-IR35411,IC,H73688-0A!!!F2069!VCC!!!!
S!P5V_STBY!EU4D3!4!@baseboard_fab2_lib.baseboard_fab2(sch_1):page203_i70@mstr_discrete.ir354xx(chips)!IR354XX_SM-IR35411,IC,H73688-0A!!!F2069!VDRV!!!!
S!VR_FET_SW_P12V_STBY_PVCCIN_CPU0!EU4D3!25!@baseboard_fab2_lib.baseboard_fab2(sch_1):page203_i70@mstr_discrete.ir354xx(chips)!IR354XX_SM-IR35411,IC,H73688-0A!!!F2069!VIN(0)!!!!
S!VR_FET_SW_P12V_STBY_PVCCIN_CPU0!EU4D3!30!@baseboard_fab2_lib.baseboard_fab2(sch_1):page203_i70@mstr_discrete.ir354xx(chips)!IR354XX_SM-IR35411,IC,H73688-0A!!!F2069!VIN(1)!!!!
S!PVCCIN_CPU0!EU4D3!1!@baseboard_fab2_lib.baseboard_fab2(sch_1):page203_i70@mstr_discrete.ir354xx(chips)!IR354XX_SM-IR35411,IC,H73688-0A!!!F2069!VOS!!!!
S!VR_PVCCIN_CPU0_PH4_BOOT!EU4D1!33!@baseboard_fab2_lib.baseboard_fab2(sch_1):page203_i71@mstr_discrete.ir354xx(chips)!IR354XX_SM-IR35411,IC,H73688-0A!!!F2070!BOOST!!!!
S!P5V_STBY!EU4D1!35!@baseboard_fab2_lib.baseboard_fab2(sch_1):page203_i71@mstr_discrete.ir354xx(chips)!IR354XX_SM-IR35411,IC,H73688-0A!!!F2070!EN!!!!
S!TP_PVCCIN_CPU0_PH4_GL_0!EU4D1!6!@baseboard_fab2_lib.baseboard_fab2(sch_1):page203_i71@mstr_discrete.ir354xx(chips)!IR354XX_SM-IR35411,IC,H73688-0A!!!F2070!GL(0)!!!!
S!TP_PVCCIN_CPU0_PH4_GL_1!EU4D1!41!@baseboard_fab2_lib.baseboard_fab2(sch_1):page203_i71@mstr_discrete.ir354xx(chips)!IR354XX_SM-IR35411,IC,H73688-0A!!!F2070!GL(1)!!!!
S!ISENSE_PVCCIN_CPU0_PH4_IMON!EU4D1!38!@baseboard_fab2_lib.baseboard_fab2(sch_1):page203_i71@mstr_discrete.ir354xx(chips)!IR354XX_SM-IR35411,IC,H73688-0A!!!F2070!IOUT!!!!
S!GND!EU4D1!2!@baseboard_fab2_lib.baseboard_fab2(sch_1):page203_i71@mstr_discrete.ir354xx(chips)!IR354XX_SM-IR35411,IC,H73688-0A!!!F2070!LGND!!!!
S!NC_PVCCIN_CPU0_PH4_P31!EU4D1!31!@baseboard_fab2_lib.baseboard_fab2(sch_1):page203_i71@mstr_discrete.ir354xx(chips)!IR354XX_SM-IR35411,IC,H73688-0A!!!F2070!NC!!!!
S!VR_PVCCIN_CPU0_PH4_OCSET!EU4D1!37!@baseboard_fab2_lib.baseboard_fab2(sch_1):page203_i71@mstr_discrete.ir354xx(chips)!IR354XX_SM-IR35411,IC,H73688-0A!!!F2070!OCSET!!!!
S!GND!EU4D1!5!@baseboard_fab2_lib.baseboard_fab2(sch_1):page203_i71@mstr_discrete.ir354xx(chips)!IR354XX_SM-IR35411,IC,H73688-0A!!!F2070!PGND(0)!!!!
S!GND!EU4D1!7!@baseboard_fab2_lib.baseboard_fab2(sch_1):page203_i71@mstr_discrete.ir354xx(chips)!IR354XX_SM-IR35411,IC,H73688-0A!!!F2070!PGND(1)!!!!
S!GND!EU4D1!40!@baseboard_fab2_lib.baseboard_fab2(sch_1):page203_i71@mstr_discrete.ir354xx(chips)!IR354XX_SM-IR35411,IC,H73688-0A!!!F2070!PGND(2)!!!!
S!VR_PVCCIN_CPU0_PH4_PHASE!EU4D1!32!@baseboard_fab2_lib.baseboard_fab2(sch_1):page203_i71@mstr_discrete.ir354xx(chips)!IR354XX_SM-IR35411,IC,H73688-0A!!!F2070!PHASE!!!!
S!VR_PVCCIN_CPU0_PWM4!EU4D1!34!@baseboard_fab2_lib.baseboard_fab2(sch_1):page203_i71@mstr_discrete.ir354xx(chips)!IR354XX_SM-IR35411,IC,H73688-0A!!!F2070!PWM!!!!
S!VR_PVCCIN_CPU0_AIREF4!EU4D1!39!@baseboard_fab2_lib.baseboard_fab2(sch_1):page203_i71@mstr_discrete.ir354xx(chips)!IR354XX_SM-IR35411,IC,H73688-0A!!!F2070!REFIN!!!!
S!VR_PVCCIN_CPU0_PHASE4!EU4D1!10!@baseboard_fab2_lib.baseboard_fab2(sch_1):page203_i71@mstr_discrete.ir354xx(chips)!IR354XX_SM-IR35411,IC,H73688-0A!!!F2070!SW!!!!
S!A_TSENSE_PVCCIN_CPU0!EU4D1!36!@baseboard_fab2_lib.baseboard_fab2(sch_1):page203_i71@mstr_discrete.ir354xx(chips)!IR354XX_SM-IR35411,IC,H73688-0A!!!F2070!TOUT_FLT!!!!
S!VR_PVCCIN_CPU0_PH4_VCIN!EU4D1!3!@baseboard_fab2_lib.baseboard_fab2(sch_1):page203_i71@mstr_discrete.ir354xx(chips)!IR354XX_SM-IR35411,IC,H73688-0A!!!F2070!VCC!!!!
S!P5V_STBY!EU4D1!4!@baseboard_fab2_lib.baseboard_fab2(sch_1):page203_i71@mstr_discrete.ir354xx(chips)!IR354XX_SM-IR35411,IC,H73688-0A!!!F2070!VDRV!!!!
S!VR_FET_SW_P12V_STBY_PVCCIN_CPU0!EU4D1!25!@baseboard_fab2_lib.baseboard_fab2(sch_1):page203_i71@mstr_discrete.ir354xx(chips)!IR354XX_SM-IR35411,IC,H73688-0A!!!F2070!VIN(0)!!!!
S!VR_FET_SW_P12V_STBY_PVCCIN_CPU0!EU4D1!30!@baseboard_fab2_lib.baseboard_fab2(sch_1):page203_i71@mstr_discrete.ir354xx(chips)!IR354XX_SM-IR35411,IC,H73688-0A!!!F2070!VIN(1)!!!!
S!PVCCIN_CPU0!EU4D1!1!@baseboard_fab2_lib.baseboard_fab2(sch_1):page203_i71@mstr_discrete.ir354xx(chips)!IR354XX_SM-IR35411,IC,H73688-0A!!!F2070!VOS!!!!
S!VR_PVCCIN_CPU0_PH5_BOOT!EU4C2!33!@baseboard_fab2_lib.baseboard_fab2(sch_1):page204_i71@mstr_discrete.ir354xx(chips)!IR354XX_SM-IR35411,IC,H73688-0A!!!F2071!BOOST!!!!
S!P5V_STBY!EU4C2!35!@baseboard_fab2_lib.baseboard_fab2(sch_1):page204_i71@mstr_discrete.ir354xx(chips)!IR354XX_SM-IR35411,IC,H73688-0A!!!F2071!EN!!!!
S!TP_PVCCIN_CPU0_PH5_GL_0!EU4C2!6!@baseboard_fab2_lib.baseboard_fab2(sch_1):page204_i71@mstr_discrete.ir354xx(chips)!IR354XX_SM-IR35411,IC,H73688-0A!!!F2071!GL(0)!!!!
S!TP_PVCCIN_CPU0_PH5_GL_1!EU4C2!41!@baseboard_fab2_lib.baseboard_fab2(sch_1):page204_i71@mstr_discrete.ir354xx(chips)!IR354XX_SM-IR35411,IC,H73688-0A!!!F2071!GL(1)!!!!
S!ISENSE_PVCCIN_CPU0_PH5_IMON!EU4C2!38!@baseboard_fab2_lib.baseboard_fab2(sch_1):page204_i71@mstr_discrete.ir354xx(chips)!IR354XX_SM-IR35411,IC,H73688-0A!!!F2071!IOUT!!!!
S!GND!EU4C2!2!@baseboard_fab2_lib.baseboard_fab2(sch_1):page204_i71@mstr_discrete.ir354xx(chips)!IR354XX_SM-IR35411,IC,H73688-0A!!!F2071!LGND!!!!
S!NC_PVCCIN_CPU0_PH5_P31!EU4C2!31!@baseboard_fab2_lib.baseboard_fab2(sch_1):page204_i71@mstr_discrete.ir354xx(chips)!IR354XX_SM-IR35411,IC,H73688-0A!!!F2071!NC!!!!
S!VR_PVCCIN_CPU0_PH5_OCSET!EU4C2!37!@baseboard_fab2_lib.baseboard_fab2(sch_1):page204_i71@mstr_discrete.ir354xx(chips)!IR354XX_SM-IR35411,IC,H73688-0A!!!F2071!OCSET!!!!
S!GND!EU4C2!5!@baseboard_fab2_lib.baseboard_fab2(sch_1):page204_i71@mstr_discrete.ir354xx(chips)!IR354XX_SM-IR35411,IC,H73688-0A!!!F2071!PGND(0)!!!!
S!GND!EU4C2!7!@baseboard_fab2_lib.baseboard_fab2(sch_1):page204_i71@mstr_discrete.ir354xx(chips)!IR354XX_SM-IR35411,IC,H73688-0A!!!F2071!PGND(1)!!!!
S!GND!EU4C2!40!@baseboard_fab2_lib.baseboard_fab2(sch_1):page204_i71@mstr_discrete.ir354xx(chips)!IR354XX_SM-IR35411,IC,H73688-0A!!!F2071!PGND(2)!!!!
S!VR_PVCCIN_CPU0_PH5_PHASE!EU4C2!32!@baseboard_fab2_lib.baseboard_fab2(sch_1):page204_i71@mstr_discrete.ir354xx(chips)!IR354XX_SM-IR35411,IC,H73688-0A!!!F2071!PHASE!!!!
S!VR_PVCCIN_CPU0_PWM5!EU4C2!34!@baseboard_fab2_lib.baseboard_fab2(sch_1):page204_i71@mstr_discrete.ir354xx(chips)!IR354XX_SM-IR35411,IC,H73688-0A!!!F2071!PWM!!!!
S!VR_PVCCIN_CPU0_AIREF5!EU4C2!39!@baseboard_fab2_lib.baseboard_fab2(sch_1):page204_i71@mstr_discrete.ir354xx(chips)!IR354XX_SM-IR35411,IC,H73688-0A!!!F2071!REFIN!!!!
S!VR_PVCCIN_CPU0_PHASE5!EU4C2!10!@baseboard_fab2_lib.baseboard_fab2(sch_1):page204_i71@mstr_discrete.ir354xx(chips)!IR354XX_SM-IR35411,IC,H73688-0A!!!F2071!SW!!!!
S!A_TSENSE_PVCCIN_CPU0!EU4C2!36!@baseboard_fab2_lib.baseboard_fab2(sch_1):page204_i71@mstr_discrete.ir354xx(chips)!IR354XX_SM-IR35411,IC,H73688-0A!!!F2071!TOUT_FLT!!!!
S!VR_PVCCIN_CPU0_PH5_VCIN!EU4C2!3!@baseboard_fab2_lib.baseboard_fab2(sch_1):page204_i71@mstr_discrete.ir354xx(chips)!IR354XX_SM-IR35411,IC,H73688-0A!!!F2071!VCC!!!!
S!P5V_STBY!EU4C2!4!@baseboard_fab2_lib.baseboard_fab2(sch_1):page204_i71@mstr_discrete.ir354xx(chips)!IR354XX_SM-IR35411,IC,H73688-0A!!!F2071!VDRV!!!!
S!VR_FET_SW_P12V_STBY_PVCCIN_CPU0!EU4C2!25!@baseboard_fab2_lib.baseboard_fab2(sch_1):page204_i71@mstr_discrete.ir354xx(chips)!IR354XX_SM-IR35411,IC,H73688-0A!!!F2071!VIN(0)!!!!
S!VR_FET_SW_P12V_STBY_PVCCIN_CPU0!EU4C2!30!@baseboard_fab2_lib.baseboard_fab2(sch_1):page204_i71@mstr_discrete.ir354xx(chips)!IR354XX_SM-IR35411,IC,H73688-0A!!!F2071!VIN(1)!!!!
S!PVCCIN_CPU0!EU4C2!1!@baseboard_fab2_lib.baseboard_fab2(sch_1):page204_i71@mstr_discrete.ir354xx(chips)!IR354XX_SM-IR35411,IC,H73688-0A!!!F2071!VOS!!!!
S!VR_PVCCIN_CPU0_PH1_BOOT!EU4E1!33!@baseboard_fab2_lib.baseboard_fab2(sch_1):page202_i63@mstr_discrete.ir354xx(chips)!IR354XX_SM-IR35411,IC,H73688-0A!!!F2067!BOOST!!!!
S!P5V_STBY!EU4E1!35!@baseboard_fab2_lib.baseboard_fab2(sch_1):page202_i63@mstr_discrete.ir354xx(chips)!IR354XX_SM-IR35411,IC,H73688-0A!!!F2067!EN!!!!
S!TP_PVCCIN_CPU0_PH1_GL_0!EU4E1!6!@baseboard_fab2_lib.baseboard_fab2(sch_1):page202_i63@mstr_discrete.ir354xx(chips)!IR354XX_SM-IR35411,IC,H73688-0A!!!F2067!GL(0)!!!!
S!TP_PVCCIN_CPU0_PH1_GL_1!EU4E1!41!@baseboard_fab2_lib.baseboard_fab2(sch_1):page202_i63@mstr_discrete.ir354xx(chips)!IR354XX_SM-IR35411,IC,H73688-0A!!!F2067!GL(1)!!!!
S!ISENSE_PVCCIN_CPU0_PH1_IMON!EU4E1!38!@baseboard_fab2_lib.baseboard_fab2(sch_1):page202_i63@mstr_discrete.ir354xx(chips)!IR354XX_SM-IR35411,IC,H73688-0A!!!F2067!IOUT!!!!
S!GND!EU4E1!2!@baseboard_fab2_lib.baseboard_fab2(sch_1):page202_i63@mstr_discrete.ir354xx(chips)!IR354XX_SM-IR35411,IC,H73688-0A!!!F2067!LGND!!!!
S!NC_PVCCIN_CPU0_PH1_P31!EU4E1!31!@baseboard_fab2_lib.baseboard_fab2(sch_1):page202_i63@mstr_discrete.ir354xx(chips)!IR354XX_SM-IR35411,IC,H73688-0A!!!F2067!NC!!!!
S!VR_PVCCIN_CPU0_PH1_OCSET!EU4E1!37!@baseboard_fab2_lib.baseboard_fab2(sch_1):page202_i63@mstr_discrete.ir354xx(chips)!IR354XX_SM-IR35411,IC,H73688-0A!!!F2067!OCSET!!!!
S!GND!EU4E1!5!@baseboard_fab2_lib.baseboard_fab2(sch_1):page202_i63@mstr_discrete.ir354xx(chips)!IR354XX_SM-IR35411,IC,H73688-0A!!!F2067!PGND(0)!!!!
S!GND!EU4E1!7!@baseboard_fab2_lib.baseboard_fab2(sch_1):page202_i63@mstr_discrete.ir354xx(chips)!IR354XX_SM-IR35411,IC,H73688-0A!!!F2067!PGND(1)!!!!
S!GND!EU4E1!40!@baseboard_fab2_lib.baseboard_fab2(sch_1):page202_i63@mstr_discrete.ir354xx(chips)!IR354XX_SM-IR35411,IC,H73688-0A!!!F2067!PGND(2)!!!!
S!VR_PVCCIN_CPU0_PH1_PHASE!EU4E1!32!@baseboard_fab2_lib.baseboard_fab2(sch_1):page202_i63@mstr_discrete.ir354xx(chips)!IR354XX_SM-IR35411,IC,H73688-0A!!!F2067!PHASE!!!!
S!VR_PVCCIN_CPU0_PWM1!EU4E1!34!@baseboard_fab2_lib.baseboard_fab2(sch_1):page202_i63@mstr_discrete.ir354xx(chips)!IR354XX_SM-IR35411,IC,H73688-0A!!!F2067!PWM!!!!
S!VR_PVCCIN_CPU0_AIREF1!EU4E1!39!@baseboard_fab2_lib.baseboard_fab2(sch_1):page202_i63@mstr_discrete.ir354xx(chips)!IR354XX_SM-IR35411,IC,H73688-0A!!!F2067!REFIN!!!!
S!VR_PVCCIN_CPU0_PHASE1!EU4E1!10!@baseboard_fab2_lib.baseboard_fab2(sch_1):page202_i63@mstr_discrete.ir354xx(chips)!IR354XX_SM-IR35411,IC,H73688-0A!!!F2067!SW!!!!
S!A_TSENSE_PVCCIN_CPU0!EU4E1!36!@baseboard_fab2_lib.baseboard_fab2(sch_1):page202_i63@mstr_discrete.ir354xx(chips)!IR354XX_SM-IR35411,IC,H73688-0A!!!F2067!TOUT_FLT!!!!
S!VR_PVCCIN_CPU0_PH1_VCIN!EU4E1!3!@baseboard_fab2_lib.baseboard_fab2(sch_1):page202_i63@mstr_discrete.ir354xx(chips)!IR354XX_SM-IR35411,IC,H73688-0A!!!F2067!VCC!!!!
S!P5V_STBY!EU4E1!4!@baseboard_fab2_lib.baseboard_fab2(sch_1):page202_i63@mstr_discrete.ir354xx(chips)!IR354XX_SM-IR35411,IC,H73688-0A!!!F2067!VDRV!!!!
S!VR_FET_SW_P12V_STBY_PVCCIN_CPU0!EU4E1!25!@baseboard_fab2_lib.baseboard_fab2(sch_1):page202_i63@mstr_discrete.ir354xx(chips)!IR354XX_SM-IR35411,IC,H73688-0A!!!F2067!VIN(0)!!!!
S!VR_FET_SW_P12V_STBY_PVCCIN_CPU0!EU4E1!30!@baseboard_fab2_lib.baseboard_fab2(sch_1):page202_i63@mstr_discrete.ir354xx(chips)!IR354XX_SM-IR35411,IC,H73688-0A!!!F2067!VIN(1)!!!!
S!PVCCIN_CPU0!EU4E1!1!@baseboard_fab2_lib.baseboard_fab2(sch_1):page202_i63@mstr_discrete.ir354xx(chips)!IR354XX_SM-IR35411,IC,H73688-0A!!!F2067!VOS!!!!
S!VR_PVCCIN_CPU1_PH3_BOOT!EU1D3!33!@baseboard_fab2_lib.baseboard_fab2(sch_1):page208_i27@mstr_discrete.ir354xx(chips)!IR354XX_SM-IR35411,IC,H73688-0A!!!F2076!BOOST!!!!
S!P5V_STBY!EU1D3!35!@baseboard_fab2_lib.baseboard_fab2(sch_1):page208_i27@mstr_discrete.ir354xx(chips)!IR354XX_SM-IR35411,IC,H73688-0A!!!F2076!EN!!!!
S!TP_PVCCIN_CPU1_PH3_GL_0!EU1D3!6!@baseboard_fab2_lib.baseboard_fab2(sch_1):page208_i27@mstr_discrete.ir354xx(chips)!IR354XX_SM-IR35411,IC,H73688-0A!!!F2076!GL(0)!!!!
S!TP_PVCCIN_CPU1_PH3_GL_1!EU1D3!41!@baseboard_fab2_lib.baseboard_fab2(sch_1):page208_i27@mstr_discrete.ir354xx(chips)!IR354XX_SM-IR35411,IC,H73688-0A!!!F2076!GL(1)!!!!
S!ISENSE_PVCCIN_CPU1_PH3_IMON!EU1D3!38!@baseboard_fab2_lib.baseboard_fab2(sch_1):page208_i27@mstr_discrete.ir354xx(chips)!IR354XX_SM-IR35411,IC,H73688-0A!!!F2076!IOUT!!!!
S!GND!EU1D3!2!@baseboard_fab2_lib.baseboard_fab2(sch_1):page208_i27@mstr_discrete.ir354xx(chips)!IR354XX_SM-IR35411,IC,H73688-0A!!!F2076!LGND!!!!
S!NC_PVCCIN_CPU1_PH3_P31!EU1D3!31!@baseboard_fab2_lib.baseboard_fab2(sch_1):page208_i27@mstr_discrete.ir354xx(chips)!IR354XX_SM-IR35411,IC,H73688-0A!!!F2076!NC!!!!
S!VR_PVCCIN_CPU1_PH3_OCSET!EU1D3!37!@baseboard_fab2_lib.baseboard_fab2(sch_1):page208_i27@mstr_discrete.ir354xx(chips)!IR354XX_SM-IR35411,IC,H73688-0A!!!F2076!OCSET!!!!
S!GND!EU1D3!5!@baseboard_fab2_lib.baseboard_fab2(sch_1):page208_i27@mstr_discrete.ir354xx(chips)!IR354XX_SM-IR35411,IC,H73688-0A!!!F2076!PGND(0)!!!!
S!GND!EU1D3!7!@baseboard_fab2_lib.baseboard_fab2(sch_1):page208_i27@mstr_discrete.ir354xx(chips)!IR354XX_SM-IR35411,IC,H73688-0A!!!F2076!PGND(1)!!!!
S!GND!EU1D3!40!@baseboard_fab2_lib.baseboard_fab2(sch_1):page208_i27@mstr_discrete.ir354xx(chips)!IR354XX_SM-IR35411,IC,H73688-0A!!!F2076!PGND(2)!!!!
S!VR_PVCCIN_CPU1_PH3_PHASE!EU1D3!32!@baseboard_fab2_lib.baseboard_fab2(sch_1):page208_i27@mstr_discrete.ir354xx(chips)!IR354XX_SM-IR35411,IC,H73688-0A!!!F2076!PHASE!!!!
S!VR_PVCCIN_CPU1_PWM3!EU1D3!34!@baseboard_fab2_lib.baseboard_fab2(sch_1):page208_i27@mstr_discrete.ir354xx(chips)!IR354XX_SM-IR35411,IC,H73688-0A!!!F2076!PWM!!!!
S!VR_PVCCIN_CPU1_AIREF3!EU1D3!39!@baseboard_fab2_lib.baseboard_fab2(sch_1):page208_i27@mstr_discrete.ir354xx(chips)!IR354XX_SM-IR35411,IC,H73688-0A!!!F2076!REFIN!!!!
S!VR_PVCCIN_CPU1_PHASE3!EU1D3!10!@baseboard_fab2_lib.baseboard_fab2(sch_1):page208_i27@mstr_discrete.ir354xx(chips)!IR354XX_SM-IR35411,IC,H73688-0A!!!F2076!SW!!!!
S!A_TSENSE_PVCCIN_CPU1!EU1D3!36!@baseboard_fab2_lib.baseboard_fab2(sch_1):page208_i27@mstr_discrete.ir354xx(chips)!IR354XX_SM-IR35411,IC,H73688-0A!!!F2076!TOUT_FLT!!!!
S!VR_PVCCIN_CPU1_PH3_VCIN!EU1D3!3!@baseboard_fab2_lib.baseboard_fab2(sch_1):page208_i27@mstr_discrete.ir354xx(chips)!IR354XX_SM-IR35411,IC,H73688-0A!!!F2076!VCC!!!!
S!P5V_STBY!EU1D3!4!@baseboard_fab2_lib.baseboard_fab2(sch_1):page208_i27@mstr_discrete.ir354xx(chips)!IR354XX_SM-IR35411,IC,H73688-0A!!!F2076!VDRV!!!!
S!VR_FET_SW_P12V_STBY_PVCCIN_CPU1!EU1D3!25!@baseboard_fab2_lib.baseboard_fab2(sch_1):page208_i27@mstr_discrete.ir354xx(chips)!IR354XX_SM-IR35411,IC,H73688-0A!!!F2076!VIN(0)!!!!
S!VR_FET_SW_P12V_STBY_PVCCIN_CPU1!EU1D3!30!@baseboard_fab2_lib.baseboard_fab2(sch_1):page208_i27@mstr_discrete.ir354xx(chips)!IR354XX_SM-IR35411,IC,H73688-0A!!!F2076!VIN(1)!!!!
S!PVCCIN_CPU1!EU1D3!1!@baseboard_fab2_lib.baseboard_fab2(sch_1):page208_i27@mstr_discrete.ir354xx(chips)!IR354XX_SM-IR35411,IC,H73688-0A!!!F2076!VOS!!!!
S!VR_PVCCIN_CPU1_PH2_BOOT!EU1D4!33!@baseboard_fab2_lib.baseboard_fab2(sch_1):page207_i24@mstr_discrete.ir354xx(chips)!IR354XX_SM-IR35411,IC,H73688-0A!!!F2075!BOOST!!!!
S!P5V_STBY!EU1D4!35!@baseboard_fab2_lib.baseboard_fab2(sch_1):page207_i24@mstr_discrete.ir354xx(chips)!IR354XX_SM-IR35411,IC,H73688-0A!!!F2075!EN!!!!
S!TP_PVCCINC_CPU1_PH2_GL_0!EU1D4!6!@baseboard_fab2_lib.baseboard_fab2(sch_1):page207_i24@mstr_discrete.ir354xx(chips)!IR354XX_SM-IR35411,IC,H73688-0A!!!F2075!GL(0)!!!!
S!TP_PVCCINC_CPU1_PH2_GL_1!EU1D4!41!@baseboard_fab2_lib.baseboard_fab2(sch_1):page207_i24@mstr_discrete.ir354xx(chips)!IR354XX_SM-IR35411,IC,H73688-0A!!!F2075!GL(1)!!!!
S!ISENSE_PVCCIN_CPU1_PH2_IMON!EU1D4!38!@baseboard_fab2_lib.baseboard_fab2(sch_1):page207_i24@mstr_discrete.ir354xx(chips)!IR354XX_SM-IR35411,IC,H73688-0A!!!F2075!IOUT!!!!
S!GND!EU1D4!2!@baseboard_fab2_lib.baseboard_fab2(sch_1):page207_i24@mstr_discrete.ir354xx(chips)!IR354XX_SM-IR35411,IC,H73688-0A!!!F2075!LGND!!!!
S!NC_PVCCIN_CPU1_PH2_P31!EU1D4!31!@baseboard_fab2_lib.baseboard_fab2(sch_1):page207_i24@mstr_discrete.ir354xx(chips)!IR354XX_SM-IR35411,IC,H73688-0A!!!F2075!NC!!!!
S!VR_PVCCIN_CPU1_PH2_OCSET!EU1D4!37!@baseboard_fab2_lib.baseboard_fab2(sch_1):page207_i24@mstr_discrete.ir354xx(chips)!IR354XX_SM-IR35411,IC,H73688-0A!!!F2075!OCSET!!!!
S!GND!EU1D4!5!@baseboard_fab2_lib.baseboard_fab2(sch_1):page207_i24@mstr_discrete.ir354xx(chips)!IR354XX_SM-IR35411,IC,H73688-0A!!!F2075!PGND(0)!!!!
S!GND!EU1D4!7!@baseboard_fab2_lib.baseboard_fab2(sch_1):page207_i24@mstr_discrete.ir354xx(chips)!IR354XX_SM-IR35411,IC,H73688-0A!!!F2075!PGND(1)!!!!
S!GND!EU1D4!40!@baseboard_fab2_lib.baseboard_fab2(sch_1):page207_i24@mstr_discrete.ir354xx(chips)!IR354XX_SM-IR35411,IC,H73688-0A!!!F2075!PGND(2)!!!!
S!VR_PVCCIN_CPU1_PH2_PHASE!EU1D4!32!@baseboard_fab2_lib.baseboard_fab2(sch_1):page207_i24@mstr_discrete.ir354xx(chips)!IR354XX_SM-IR35411,IC,H73688-0A!!!F2075!PHASE!!!!
S!VR_PVCCIN_CPU1_PWM2!EU1D4!34!@baseboard_fab2_lib.baseboard_fab2(sch_1):page207_i24@mstr_discrete.ir354xx(chips)!IR354XX_SM-IR35411,IC,H73688-0A!!!F2075!PWM!!!!
S!VR_PVCCIN_CPU1_AIREF2!EU1D4!39!@baseboard_fab2_lib.baseboard_fab2(sch_1):page207_i24@mstr_discrete.ir354xx(chips)!IR354XX_SM-IR35411,IC,H73688-0A!!!F2075!REFIN!!!!
S!VR_PVCCIN_CPU1_PHASE2!EU1D4!10!@baseboard_fab2_lib.baseboard_fab2(sch_1):page207_i24@mstr_discrete.ir354xx(chips)!IR354XX_SM-IR35411,IC,H73688-0A!!!F2075!SW!!!!
S!A_TSENSE_PVCCIN_CPU1!EU1D4!36!@baseboard_fab2_lib.baseboard_fab2(sch_1):page207_i24@mstr_discrete.ir354xx(chips)!IR354XX_SM-IR35411,IC,H73688-0A!!!F2075!TOUT_FLT!!!!
S!VR_PVCCIN_CPU1_PH2_VCIN!EU1D4!3!@baseboard_fab2_lib.baseboard_fab2(sch_1):page207_i24@mstr_discrete.ir354xx(chips)!IR354XX_SM-IR35411,IC,H73688-0A!!!F2075!VCC!!!!
S!P5V_STBY!EU1D4!4!@baseboard_fab2_lib.baseboard_fab2(sch_1):page207_i24@mstr_discrete.ir354xx(chips)!IR354XX_SM-IR35411,IC,H73688-0A!!!F2075!VDRV!!!!
S!VR_FET_SW_P12V_STBY_PVCCIN_CPU1!EU1D4!25!@baseboard_fab2_lib.baseboard_fab2(sch_1):page207_i24@mstr_discrete.ir354xx(chips)!IR354XX_SM-IR35411,IC,H73688-0A!!!F2075!VIN(0)!!!!
S!VR_FET_SW_P12V_STBY_PVCCIN_CPU1!EU1D4!30!@baseboard_fab2_lib.baseboard_fab2(sch_1):page207_i24@mstr_discrete.ir354xx(chips)!IR354XX_SM-IR35411,IC,H73688-0A!!!F2075!VIN(1)!!!!
S!PVCCIN_CPU1!EU1D4!1!@baseboard_fab2_lib.baseboard_fab2(sch_1):page207_i24@mstr_discrete.ir354xx(chips)!IR354XX_SM-IR35411,IC,H73688-0A!!!F2075!VOS!!!!
S!VR_PVCCIN_CPU1_PH1_BOOT!EU1E2!33!@baseboard_fab2_lib.baseboard_fab2(sch_1):page207_i20@mstr_discrete.ir354xx(chips)!IR354XX_SM-IR35411,IC,H73688-0A!!!F2074!BOOST!!!!
S!P5V_STBY!EU1E2!35!@baseboard_fab2_lib.baseboard_fab2(sch_1):page207_i20@mstr_discrete.ir354xx(chips)!IR354XX_SM-IR35411,IC,H73688-0A!!!F2074!EN!!!!
S!TP_PVCCINC_CPU1_PH1_GL_0!EU1E2!6!@baseboard_fab2_lib.baseboard_fab2(sch_1):page207_i20@mstr_discrete.ir354xx(chips)!IR354XX_SM-IR35411,IC,H73688-0A!!!F2074!GL(0)!!!!
S!TP_PVCCINC_CPU1_PH1_GL_1!EU1E2!41!@baseboard_fab2_lib.baseboard_fab2(sch_1):page207_i20@mstr_discrete.ir354xx(chips)!IR354XX_SM-IR35411,IC,H73688-0A!!!F2074!GL(1)!!!!
S!ISENSE_PVCCIN_CPU1_PH1_IMON!EU1E2!38!@baseboard_fab2_lib.baseboard_fab2(sch_1):page207_i20@mstr_discrete.ir354xx(chips)!IR354XX_SM-IR35411,IC,H73688-0A!!!F2074!IOUT!!!!
S!GND!EU1E2!2!@baseboard_fab2_lib.baseboard_fab2(sch_1):page207_i20@mstr_discrete.ir354xx(chips)!IR354XX_SM-IR35411,IC,H73688-0A!!!F2074!LGND!!!!
S!NC_PVCCIN_CPU1_PH1_P31!EU1E2!31!@baseboard_fab2_lib.baseboard_fab2(sch_1):page207_i20@mstr_discrete.ir354xx(chips)!IR354XX_SM-IR35411,IC,H73688-0A!!!F2074!NC!!!!
S!VR_PVCCIN_CPU1_PH1_OCSET!EU1E2!37!@baseboard_fab2_lib.baseboard_fab2(sch_1):page207_i20@mstr_discrete.ir354xx(chips)!IR354XX_SM-IR35411,IC,H73688-0A!!!F2074!OCSET!!!!
S!GND!EU1E2!5!@baseboard_fab2_lib.baseboard_fab2(sch_1):page207_i20@mstr_discrete.ir354xx(chips)!IR354XX_SM-IR35411,IC,H73688-0A!!!F2074!PGND(0)!!!!
S!GND!EU1E2!7!@baseboard_fab2_lib.baseboard_fab2(sch_1):page207_i20@mstr_discrete.ir354xx(chips)!IR354XX_SM-IR35411,IC,H73688-0A!!!F2074!PGND(1)!!!!
S!GND!EU1E2!40!@baseboard_fab2_lib.baseboard_fab2(sch_1):page207_i20@mstr_discrete.ir354xx(chips)!IR354XX_SM-IR35411,IC,H73688-0A!!!F2074!PGND(2)!!!!
S!VR_PVCCIN_CPU1_PH1_PHASE!EU1E2!32!@baseboard_fab2_lib.baseboard_fab2(sch_1):page207_i20@mstr_discrete.ir354xx(chips)!IR354XX_SM-IR35411,IC,H73688-0A!!!F2074!PHASE!!!!
S!VR_PVCCIN_CPU1_PWM1!EU1E2!34!@baseboard_fab2_lib.baseboard_fab2(sch_1):page207_i20@mstr_discrete.ir354xx(chips)!IR354XX_SM-IR35411,IC,H73688-0A!!!F2074!PWM!!!!
S!VR_PVCCIN_CPU1_AIREF1!EU1E2!39!@baseboard_fab2_lib.baseboard_fab2(sch_1):page207_i20@mstr_discrete.ir354xx(chips)!IR354XX_SM-IR35411,IC,H73688-0A!!!F2074!REFIN!!!!
S!VR_PVCCIN_CPU1_PHASE1!EU1E2!10!@baseboard_fab2_lib.baseboard_fab2(sch_1):page207_i20@mstr_discrete.ir354xx(chips)!IR354XX_SM-IR35411,IC,H73688-0A!!!F2074!SW!!!!
S!A_TSENSE_PVCCIN_CPU1!EU1E2!36!@baseboard_fab2_lib.baseboard_fab2(sch_1):page207_i20@mstr_discrete.ir354xx(chips)!IR354XX_SM-IR35411,IC,H73688-0A!!!F2074!TOUT_FLT!!!!
S!VR_PVCCIN_CPU1_PH1_VCIN!EU1E2!3!@baseboard_fab2_lib.baseboard_fab2(sch_1):page207_i20@mstr_discrete.ir354xx(chips)!IR354XX_SM-IR35411,IC,H73688-0A!!!F2074!VCC!!!!
S!P5V_STBY!EU1E2!4!@baseboard_fab2_lib.baseboard_fab2(sch_1):page207_i20@mstr_discrete.ir354xx(chips)!IR354XX_SM-IR35411,IC,H73688-0A!!!F2074!VDRV!!!!
S!VR_FET_SW_P12V_STBY_PVCCIN_CPU1!EU1E2!25!@baseboard_fab2_lib.baseboard_fab2(sch_1):page207_i20@mstr_discrete.ir354xx(chips)!IR354XX_SM-IR35411,IC,H73688-0A!!!F2074!VIN(0)!!!!
S!VR_FET_SW_P12V_STBY_PVCCIN_CPU1!EU1E2!30!@baseboard_fab2_lib.baseboard_fab2(sch_1):page207_i20@mstr_discrete.ir354xx(chips)!IR354XX_SM-IR35411,IC,H73688-0A!!!F2074!VIN(1)!!!!
S!PVCCIN_CPU1!EU1E2!1!@baseboard_fab2_lib.baseboard_fab2(sch_1):page207_i20@mstr_discrete.ir354xx(chips)!IR354XX_SM-IR35411,IC,H73688-0A!!!F2074!VOS!!!!
S!FM_CPU1_STL_BRD_OSC_EN!Y3F1!1!@baseboard_fab2_lib.baseboard_fab2(sch_1):page104_i72@mstr_discrete.osc_c(chips)!OSC_C_6P10-156.25MHZ,OSC,G6383A!!!F1989!ENABLE_DISABLE!!!!
S!GND!Y3F1!3!@baseboard_fab2_lib.baseboard_fab2(sch_1):page104_i72@mstr_discrete.osc_c(chips)!OSC_C_6P10-156.25MHZ,OSC,G6383A!!!F1989!GND!!!!
S!NC_CLK_156M_CPU1_OSC!Y3F1!2!@baseboard_fab2_lib.baseboard_fab2(sch_1):page104_i72@mstr_discrete.osc_c(chips)!OSC_C_6P10-156.25MHZ,OSC,G6383A!!!F1989!NC_GND!!!!
S!CLK_156M_OSC_BRD_CPU1_DP!Y3F1!4!@baseboard_fab2_lib.baseboard_fab2(sch_1):page104_i72@mstr_discrete.osc_c(chips)!OSC_C_6P10-156.25MHZ,OSC,G6383A!!!F1989!\out\!!!!
S!CLK_156M_OSC_BRD_CPU1_DN!Y3F1!5!@baseboard_fab2_lib.baseboard_fab2(sch_1):page104_i72@mstr_discrete.osc_c(chips)!OSC_C_6P10-156.25MHZ,OSC,G6383A!!!F1989!OUT_N!!!!
S!P3V3!Y3F1!6!@baseboard_fab2_lib.baseboard_fab2(sch_1):page104_i72@mstr_discrete.osc_c(chips)!OSC_C_6P10-156.25MHZ,OSC,G6383A!!!F1989!VCC!!!!
S!FM_CPU0_STL_BRD_OSC_EN!Y6F1!1!@baseboard_fab2_lib.baseboard_fab2(sch_1):page104_i71@mstr_discrete.osc_c(chips)!OSC_C_6P10-156.25MHZ,OSC,G6383A!!!F1988!ENABLE_DISABLE!!!!
S!GND!Y6F1!3!@baseboard_fab2_lib.baseboard_fab2(sch_1):page104_i71@mstr_discrete.osc_c(chips)!OSC_C_6P10-156.25MHZ,OSC,G6383A!!!F1988!GND!!!!
S!NC_CLK_156M_CPU0_OSC!Y6F1!2!@baseboard_fab2_lib.baseboard_fab2(sch_1):page104_i71@mstr_discrete.osc_c(chips)!OSC_C_6P10-156.25MHZ,OSC,G6383A!!!F1988!NC_GND!!!!
S!CLK_156M_OSC_BRD_CPU0_DP!Y6F1!4!@baseboard_fab2_lib.baseboard_fab2(sch_1):page104_i71@mstr_discrete.osc_c(chips)!OSC_C_6P10-156.25MHZ,OSC,G6383A!!!F1988!\out\!!!!
S!CLK_156M_OSC_BRD_CPU0_DN!Y6F1!5!@baseboard_fab2_lib.baseboard_fab2(sch_1):page104_i71@mstr_discrete.osc_c(chips)!OSC_C_6P10-156.25MHZ,OSC,G6383A!!!F1988!OUT_N!!!!
S!P3V3!Y6F1!6!@baseboard_fab2_lib.baseboard_fab2(sch_1):page104_i71@mstr_discrete.osc_c(chips)!OSC_C_6P10-156.25MHZ,OSC,G6383A!!!F1988!VCC!!!!
S!GND!U8E1!15!!TTL08_QFN15-74LVC08A,IC,D90404B!!!!!!!!
S!GND!U8E1!7!!TTL08_QFN15-74LVC08A,IC,D90404B!!!!!!!!
S!P3V3_STBY!U8E1!14!!TTL08_QFN15-74LVC08A,IC,D90404B!!!!!!!!
S!FM_FAST_PROCHOT_AND_OUT_0_N!U8E1!12!@baseboard_fab2_lib.baseboard_fab2(sch_1):page170_i12@mstr_ttl.ttl08(chips)!TTL08_QFN15-74LVC08A,IC,D90404B!1!!F45!A(0)!!!!
S!FM_FAST_PROCHOT_AND_OUT_1_N!U8E1!13!@baseboard_fab2_lib.baseboard_fab2(sch_1):page170_i12@mstr_ttl.ttl08(chips)!TTL08_QFN15-74LVC08A,IC,D90404B!1!!F45!B(0)!!!!
S!FM_FAST_PROCHOT_THROTTLE_IN_N!U8E1!11!@baseboard_fab2_lib.baseboard_fab2(sch_1):page170_i12@mstr_ttl.ttl08(chips)!TTL08_QFN15-74LVC08A,IC,D90404B!1!!F45!Y(0)!!!!
S!FM_PS_EN!U8E1!9!@baseboard_fab2_lib.baseboard_fab2(sch_1):page181_i243@mstr_ttl.ttl08(chips)!TTL08_QFN15-74LVC08A,IC,D90404B!1!!F44!A(0)!!!!
S!PWRGD_P12V_HSC_DLY!U8E1!10!@baseboard_fab2_lib.baseboard_fab2(sch_1):page181_i243@mstr_ttl.ttl08(chips)!TTL08_QFN15-74LVC08A,IC,D90404B!1!!F44!B(0)!!!!
S!FM_CTNR_PS_ON_R!U8E1!8!@baseboard_fab2_lib.baseboard_fab2(sch_1):page181_i243@mstr_ttl.ttl08(chips)!TTL08_QFN15-74LVC08A,IC,D90404B!1!!F44!Y(0)!!!!
S!IRQ_UV_DETECT_N!U8E1!4!@baseboard_fab2_lib.baseboard_fab2(sch_1):page170_i11@mstr_ttl.ttl08(chips)!TTL08_QFN15-74LVC08A,IC,D90404B!1!!F43!A(0)!!!!
S!FM_HSC_TIMER_EXP_N!U8E1!5!@baseboard_fab2_lib.baseboard_fab2(sch_1):page170_i11@mstr_ttl.ttl08(chips)!TTL08_QFN15-74LVC08A,IC,D90404B!1!!F43!B(0)!!!!
S!FM_FAST_PROCHOT_AND_OUT_1_N!U8E1!6!@baseboard_fab2_lib.baseboard_fab2(sch_1):page170_i11@mstr_ttl.ttl08(chips)!TTL08_QFN15-74LVC08A,IC,D90404B!1!!F43!Y(0)!!!!
S!IRQ_FORCE_NM_THROTTLE_N!U8E1!1!@baseboard_fab2_lib.baseboard_fab2(sch_1):page170_i10@mstr_ttl.ttl08(chips)!TTL08_QFN15-74LVC08A,IC,D90404B!1!!F42!A(0)!!!!
S!FM_OC_DETECT_N!U8E1!2!@baseboard_fab2_lib.baseboard_fab2(sch_1):page170_i10@mstr_ttl.ttl08(chips)!TTL08_QFN15-74LVC08A,IC,D90404B!1!!F42!B(0)!!!!
S!FM_FAST_PROCHOT_AND_OUT_0_N!U8E1!3!@baseboard_fab2_lib.baseboard_fab2(sch_1):page170_i10@mstr_ttl.ttl08(chips)!TTL08_QFN15-74LVC08A,IC,D90404B!1!!F42!Y(0)!!!!
S!GND!U1E2!3!!TTL1G08_SOTLF-NC7SZ08,IC,D1032B!!!!!!!!
S!P3V3_STBY!U1E2!5!!TTL1G08_SOTLF-NC7SZ08,IC,D1032B!!!!!!!!
S!FM_CTNR_PS_ON!U1E2!1!@baseboard_fab2_lib.baseboard_fab2(sch_1):page161_i121@mstr_ttl.ttl1g08(chips)!TTL1G08_SOTLF-NC7SZ08,IC,D1032B!1!!F32!A(0)!!!!
S!FM_DISABLE_FAN_N!U1E2!2!@baseboard_fab2_lib.baseboard_fab2(sch_1):page161_i121@mstr_ttl.ttl1g08(chips)!TTL1G08_SOTLF-NC7SZ08,IC,D1032B!1!!F32!B(0)!!!!
S!FM_ENABLE_FAN_POWER!U1E2!4!@baseboard_fab2_lib.baseboard_fab2(sch_1):page161_i121@mstr_ttl.ttl1g08(chips)!TTL1G08_SOTLF-NC7SZ08,IC,D1032B!1!!F32!Y(0)!!!!
S!GND!U7E2!3!!TTL1G08_SOTLF-NC7SZ08,IC,D1032B!!!!!!!!
S!P3V3_STBY!U7E2!5!!TTL1G08_SOTLF-NC7SZ08,IC,D1032B!!!!!!!!
S!FM_PVCCIN_CPU0_PWR_IN_ALERT_N!U7E2!1!@baseboard_fab2_lib.baseboard_fab2(sch_1):page95_i117@mstr_ttl.ttl1g08(chips)!TTL1G08_SOTLF-NC7SZ08,IC,D1032B!1!!F31!A(0)!!!!
S!IRQ_PVCCIN_CPU0_VRHOT_LVC3_N!U7E2!2!@baseboard_fab2_lib.baseboard_fab2(sch_1):page95_i117@mstr_ttl.ttl1g08(chips)!TTL1G08_SOTLF-NC7SZ08,IC,D1032B!1!!F31!B(0)!!!!
S!IRQ_CPU0_PROCHOT_G_N!U7E2!4!@baseboard_fab2_lib.baseboard_fab2(sch_1):page95_i117@mstr_ttl.ttl1g08(chips)!TTL1G08_SOTLF-NC7SZ08,IC,D1032B!1!!F31!Y(0)!!!!
S!GND!U7E3!3!!TTL1G08_SOTLF-NC7SZ08,IC,D1032B!!!!!!!!
S!P3V3_STBY!U7E3!5!!TTL1G08_SOTLF-NC7SZ08,IC,D1032B!!!!!!!!
S!FM_PVCCIN_CPU1_PWR_IN_ALERT_N!U7E3!1!@baseboard_fab2_lib.baseboard_fab2(sch_1):page95_i118@mstr_ttl.ttl1g08(chips)!TTL1G08_SOTLF-NC7SZ08,IC,D1032B!1!!F30!A(0)!!!!
S!IRQ_PVCCIN_CPU1_VRHOT_LVC3_N!U7E3!2!@baseboard_fab2_lib.baseboard_fab2(sch_1):page95_i118@mstr_ttl.ttl1g08(chips)!TTL1G08_SOTLF-NC7SZ08,IC,D1032B!1!!F30!B(0)!!!!
S!IRQ_CPU1_PROCHOT_G_N!U7E3!4!@baseboard_fab2_lib.baseboard_fab2(sch_1):page95_i118@mstr_ttl.ttl1g08(chips)!TTL1G08_SOTLF-NC7SZ08,IC,D1032B!1!!F30!Y(0)!!!!
S!GND!U1M1!3!!TTL1G08_SOTLF-NC7SZ08,IC,D1032C!!!!!!!!
S!P3V3!U1M1!5!!TTL1G08_SOTLF-NC7SZ08,IC,D1032C!!!!!!!!
S!LED_SATA_ACT_R_N!U1M1!1!@baseboard_fab2_lib.baseboard_fab2(sch_1):page177_i70@mstr_ttl.ttl1g08(chips)!TTL1G08_SOTLF-NC7SZ08,IC,D1032C!1!!F29!A(0)!!!!
S!LED_SAS_ACT_R_N!U1M1!2!@baseboard_fab2_lib.baseboard_fab2(sch_1):page177_i70@mstr_ttl.ttl1g08(chips)!TTL1G08_SOTLF-NC7SZ08,IC,D1032C!1!!F29!B(0)!!!!
S!FP_LED_HDD_ACTIVITY_AND_N!U1M1!4!@baseboard_fab2_lib.baseboard_fab2(sch_1):page177_i70@mstr_ttl.ttl1g08(chips)!TTL1G08_SOTLF-NC7SZ08,IC,D1032C!1!!F29!Y(0)!!!!
S!GND!U1D1!3!!TTL1G126_A_SOT-74HC1G126,IC,A7B!!!!!!!!
S!P3V3_STBY!U1D1!5!!TTL1G126_A_SOT-74HC1G126,IC,A7B!!!!!!!!
S!IRQ_OC_DETECT_N!U1D1!2!@baseboard_fab2_lib.baseboard_fab2(sch_1):page200_i103@mstr_ttl.ttl1g126_a(chips)!TTL1G126_A_SOT-74HC1G126,IC,A7B!!!F28!A!!!!
S!FM_OC_DETECT_EN!U1D1!1!@baseboard_fab2_lib.baseboard_fab2(sch_1):page200_i103@mstr_ttl.ttl1g126_a(chips)!TTL1G126_A_SOT-74HC1G126,IC,A7B!!!F28!OE!!!!
S!FM_OC_DETECT_N!U1D1!4!@baseboard_fab2_lib.baseboard_fab2(sch_1):page200_i103@mstr_ttl.ttl1g126_a(chips)!TTL1G126_A_SOT-74HC1G126,IC,A7B!!!F28!Y!!!!
S!GND!U1R2!3!!TTL1G126_A_SOT-74HC1G126,IC,A7B!!!!!!!!
S!P3V3_STBY!U1R2!5!!TTL1G126_A_SOT-74HC1G126,IC,A7B!!!!!!!!
S!FM_FAST_PROCHOT_THROTTLE_DLY_N!U1R2!2!@baseboard_fab2_lib.baseboard_fab2(sch_1):page170_i20@mstr_ttl.ttl1g126_a(chips)!TTL1G126_A_SOT-74HC1G126,IC,A7B!!!F27!A!!!!
S!FM_FAST_PROCHOT_EN!U1R2!1!@baseboard_fab2_lib.baseboard_fab2(sch_1):page170_i20@mstr_ttl.ttl1g126_a(chips)!TTL1G126_A_SOT-74HC1G126,IC,A7B!!!F27!OE!!!!
S!FM_FAST_PROCHOT_THROTTLE_DLY_BU!U1R2!4!@baseboard_fab2_lib.baseboard_fab2(sch_1):page170_i20@mstr_ttl.ttl1g126_a(chips)!TTL1G126_A_SOT-74HC1G126,IC,A7B!!!F27!Y!!!!
S!GND!U8D5!3!!TTL1G126_A_SOT-74HC1G126,IC,A7B!!!!!!!!
S!P3V3_STBY!U8D5!5!!TTL1G126_A_SOT-74HC1G126,IC,A7B!!!!!!!!
S!IRQ_SML1_PMBUS_ALERT_N!U8D5!2!@baseboard_fab2_lib.baseboard_fab2(sch_1):page170_i38@mstr_ttl.ttl1g126_a(chips)!TTL1G126_A_SOT-74HC1G126,IC,A7B!!!F26!A!!!!
S!FM_PMBUS_ALERT_BUF_EN!U8D5!1!@baseboard_fab2_lib.baseboard_fab2(sch_1):page170_i38@mstr_ttl.ttl1g126_a(chips)!TTL1G126_A_SOT-74HC1G126,IC,A7B!!!F26!OE!!!!
S!IRQ_SML1_PMBUS_ALERT_BUF_N!U8D5!4!@baseboard_fab2_lib.baseboard_fab2(sch_1):page170_i38@mstr_ttl.ttl1g126_a(chips)!TTL1G126_A_SOT-74HC1G126,IC,A7B!!!F26!Y!!!!
S!GND!U8E3!3!!TTL1G126_A_SOT-74HC1G126,IC,A7B!!!!!!!!
S!P3V3_STBY!U8E3!5!!TTL1G126_A_SOT-74HC1G126,IC,A7B!!!!!!!!
S!FM_BIOS_TOP_SWAP!U8E3!2!@baseboard_fab2_lib.baseboard_fab2(sch_1):page136_i130@mstr_ttl.ttl1g126_a(chips)!TTL1G126_A_SOT-74HC1G126,IC,A7B!!!F25!A!!!!
S!RST_PLTRST_TOP_SWAP!U8E3!1!@baseboard_fab2_lib.baseboard_fab2(sch_1):page136_i130@mstr_ttl.ttl1g126_a(chips)!TTL1G126_A_SOT-74HC1G126,IC,A7B!!!F25!OE!!!!
S!FM_BIOS_TOP_SWAP_SPKR_R!U8E3!4!@baseboard_fab2_lib.baseboard_fab2(sch_1):page136_i130@mstr_ttl.ttl1g126_a(chips)!TTL1G126_A_SOT-74HC1G126,IC,A7B!!!F25!Y!!!!
S!GND!U8E4!3!!TTL1G126_A_SOT-74HC1G126,IC,A7B!!!!!!!!
S!P3V3_STBY!U8E4!5!!TTL1G126_A_SOT-74HC1G126,IC,A7B!!!!!!!!
S!FM_ALL_WAKE_N!U8E4!2!@baseboard_fab2_lib.baseboard_fab2(sch_1):page142_i1@mstr_ttl.ttl1g126_a(chips)!TTL1G126_A_SOT-74HC1G126,IC,A7B!!!F24!A!!!!
S!PU_TRI_STATE_EN!U8E4!1!@baseboard_fab2_lib.baseboard_fab2(sch_1):page142_i1@mstr_ttl.ttl1g126_a(chips)!TTL1G126_A_SOT-74HC1G126,IC,A7B!!!F24!OE!!!!
S!IRQ_LVC3_WAKE_R_N!U8E4!4!@baseboard_fab2_lib.baseboard_fab2(sch_1):page142_i1@mstr_ttl.ttl1g126_a(chips)!TTL1G126_A_SOT-74HC1G126,IC,A7B!!!F24!Y!!!!
S!P3V3_STBY!R7D13!1!@baseboard_fab2_lib.baseboard_fab2(sch_1):page125_i60@mstr_discrete.res(chips)!RES_0402-8.2K,1%,1/16W,EMPTY,GA!!!F292!A!!!!
S!RMII_BMC_PCH_SPRNGVLLE_RXER!R7D13!2!@baseboard_fab2_lib.baseboard_fab2(sch_1):page125_i60@mstr_discrete.res(chips)!RES_0402-8.2K,1%,1/16W,EMPTY,GA!!!F292!B!!!!
S!GND_SIGNAL1!TC1!1!@baseboard_fab2_lib.baseboard_fab2(sch_1):page110_i54@mstr_misc.tp3_pprobeb(chips)!TP3_PPROBEB_SM-EMPTY,NA!!!F60!IO1!!!!
S!L5_Z85_SL!TC1!2!@baseboard_fab2_lib.baseboard_fab2(sch_1):page110_i54@mstr_misc.tp3_pprobeb(chips)!TP3_PPROBEB_SM-EMPTY,NA!!!F60!IO2!!!!
S!L5_Z85_SL!TC1!3!@baseboard_fab2_lib.baseboard_fab2(sch_1):page110_i54@mstr_misc.tp3_pprobeb(chips)!TP3_PPROBEB_SM-EMPTY,NA!!!F60!IO3!!!!
S!GND_SIGNAL1!TC3!1!@baseboard_fab2_lib.baseboard_fab2(sch_1):page110_i58@mstr_misc.tp3_pprobeb(chips)!TP3_PPROBEB_SM-EMPTY,NA!!!F59!IO1!!!!
S!L10_Z85_SL!TC3!2!@baseboard_fab2_lib.baseboard_fab2(sch_1):page110_i58@mstr_misc.tp3_pprobeb(chips)!TP3_PPROBEB_SM-EMPTY,NA!!!F59!IO2!!!!
S!L10_Z85_SL!TC3!3!@baseboard_fab2_lib.baseboard_fab2(sch_1):page110_i58@mstr_misc.tp3_pprobeb(chips)!TP3_PPROBEB_SM-EMPTY,NA!!!F59!IO3!!!!
S!GND_SIGNAL1!TC4!1!@baseboard_fab2_lib.baseboard_fab2(sch_1):page110_i62@mstr_misc.tp3_pprobeb(chips)!TP3_PPROBEB_SM-EMPTY,NA!!!F58!IO1!!!!
S!L1_Z85_THRU!TC4!2!@baseboard_fab2_lib.baseboard_fab2(sch_1):page110_i62@mstr_misc.tp3_pprobeb(chips)!TP3_PPROBEB_SM-EMPTY,NA!!!F58!IO2!!!!
S!L1_Z85_THRU!TC4!3!@baseboard_fab2_lib.baseboard_fab2(sch_1):page110_i62@mstr_misc.tp3_pprobeb(chips)!TP3_PPROBEB_SM-EMPTY,NA!!!F58!IO3!!!!
S!GND_SIGNAL1!TC7!1!@baseboard_fab2_lib.baseboard_fab2(sch_1):page110_i16@mstr_misc.tp3_pprobeb(chips)!TP3_PPROBEB_SM-EMPTY,NA!!!F57!IO1!!!!
S!L1_Z85_MS!TC7!2!@baseboard_fab2_lib.baseboard_fab2(sch_1):page110_i16@mstr_misc.tp3_pprobeb(chips)!TP3_PPROBEB_SM-EMPTY,NA!!!F57!IO2!!!!
S!L1_Z85_MS!TC7!3!@baseboard_fab2_lib.baseboard_fab2(sch_1):page110_i16@mstr_misc.tp3_pprobeb(chips)!TP3_PPROBEB_SM-EMPTY,NA!!!F57!IO3!!!!
S!GND_SIGNAL1!TC8!1!@baseboard_fab2_lib.baseboard_fab2(sch_1):page110_i18@mstr_misc.tp3_pprobeb(chips)!TP3_PPROBEB_SM-EMPTY,NA!!!F56!IO1!!!!
S!L3_Z85_SL!TC8!2!@baseboard_fab2_lib.baseboard_fab2(sch_1):page110_i18@mstr_misc.tp3_pprobeb(chips)!TP3_PPROBEB_SM-EMPTY,NA!!!F56!IO2!!!!
S!L3_Z85_SL!TC8!3!@baseboard_fab2_lib.baseboard_fab2(sch_1):page110_i18@mstr_misc.tp3_pprobeb(chips)!TP3_PPROBEB_SM-EMPTY,NA!!!F56!IO3!!!!
S!GND_SIGNAL1!TC10!1!@baseboard_fab2_lib.baseboard_fab2(sch_1):page110_i22@mstr_misc.tp3_pprobeb(chips)!TP3_PPROBEB_SM-EMPTY,NA!!!F55!IO1!!!!
S!L12_Z85_SL!TC10!2!@baseboard_fab2_lib.baseboard_fab2(sch_1):page110_i22@mstr_misc.tp3_pprobeb(chips)!TP3_PPROBEB_SM-EMPTY,NA!!!F55!IO2!!!!
S!L12_Z85_SL!TC10!3!@baseboard_fab2_lib.baseboard_fab2(sch_1):page110_i22@mstr_misc.tp3_pprobeb(chips)!TP3_PPROBEB_SM-EMPTY,NA!!!F55!IO3!!!!
S!GND_SIGNAL1!TC11!1!@baseboard_fab2_lib.baseboard_fab2(sch_1):page110_i24@mstr_misc.tp3_pprobeb(chips)!TP3_PPROBEB_SM-EMPTY,NA!!!F54!IO1!!!!
S!L14_Z85_MS!TC11!2!@baseboard_fab2_lib.baseboard_fab2(sch_1):page110_i24@mstr_misc.tp3_pprobeb(chips)!TP3_PPROBEB_SM-EMPTY,NA!!!F54!IO2!!!!
S!L14_Z85_MS!TC11!3!@baseboard_fab2_lib.baseboard_fab2(sch_1):page110_i24@mstr_misc.tp3_pprobeb(chips)!TP3_PPROBEB_SM-EMPTY,NA!!!F54!IO3!!!!
S!GND_SIGNAL2!TC19!1!@baseboard_fab2_lib.baseboard_fab2(sch_1):page110_i53@mstr_misc.tp3_pprobeb(chips)!TP3_PPROBEB_SM-EMPTY,NA!!!F53!IO1!!!!
S!L1_Z100_MS!TC19!2!@baseboard_fab2_lib.baseboard_fab2(sch_1):page110_i53@mstr_misc.tp3_pprobeb(chips)!TP3_PPROBEB_SM-EMPTY,NA!!!F53!IO2!!!!
S!L1_Z100_MS!TC19!3!@baseboard_fab2_lib.baseboard_fab2(sch_1):page110_i53@mstr_misc.tp3_pprobeb(chips)!TP3_PPROBEB_SM-EMPTY,NA!!!F53!IO3!!!!
S!GND_SIGNAL2!TC20!1!@baseboard_fab2_lib.baseboard_fab2(sch_1):page110_i66@mstr_misc.tp3_pprobeb(chips)!TP3_PPROBEB_SM-EMPTY,NA!!!F52!IO1!!!!
S!L14_Z100_MS!TC20!2!@baseboard_fab2_lib.baseboard_fab2(sch_1):page110_i66@mstr_misc.tp3_pprobeb(chips)!TP3_PPROBEB_SM-EMPTY,NA!!!F52!IO2!!!!
S!L14_Z100_MS!TC20!3!@baseboard_fab2_lib.baseboard_fab2(sch_1):page110_i66@mstr_misc.tp3_pprobeb(chips)!TP3_PPROBEB_SM-EMPTY,NA!!!F52!IO3!!!!
S!P0V9_LAN!R1R15!1!@baseboard_fab2_lib.baseboard_fab2(sch_1):page139_i237@mstr_discrete.res(chips)!RES_0603-0,5.0%,1/10W,CHIP,G22A!!!F281!A!!!!
S!P0V9_LAN_I210!R1R15!2!@baseboard_fab2_lib.baseboard_fab2(sch_1):page139_i237@mstr_discrete.res(chips)!RES_0603-0,5.0%,1/10W,CHIP,G22A!!!F281!B!!!!
S!P1V5_LAN!R1T32!1!@baseboard_fab2_lib.baseboard_fab2(sch_1):page139_i238@mstr_discrete.res(chips)!RES_0603-0,5.0%,1/10W,CHIP,G22A!!!F280!A!!!!
S!P1V5_LAN_I210!R1T32!2!@baseboard_fab2_lib.baseboard_fab2(sch_1):page139_i238@mstr_discrete.res(chips)!RES_0603-0,5.0%,1/10W,CHIP,G22A!!!F280!B!!!!
S!P3V3_STBY!R1T34!1!@baseboard_fab2_lib.baseboard_fab2(sch_1):page139_i239@mstr_discrete.res(chips)!RES_0603-0,5.0%,1/10W,CHIP,G22A!!!F279!A!!!!
S!P3V3_STBY_P1V5_LAN_I210!R1T34!2!@baseboard_fab2_lib.baseboard_fab2(sch_1):page139_i239@mstr_discrete.res(chips)!RES_0603-0,5.0%,1/10W,CHIP,G22A!!!F279!B!!!!
S!P1V5_LAN!R1T33!1!@baseboard_fab2_lib.baseboard_fab2(sch_1):page139_i240@mstr_discrete.res(chips)!RES_0603-0,5.0%,1/10W,EMPTY,G2A!!!F278!A!!!!
S!P3V3_STBY_P1V5_LAN_I210!R1T33!2!@baseboard_fab2_lib.baseboard_fab2(sch_1):page139_i240@mstr_discrete.res(chips)!RES_0603-0,5.0%,1/10W,EMPTY,G2A!!!F278!B!!!!
S!LED_LAN_0_R_N!JA9G1!L1!@baseboard_fab2_lib.baseboard_fab2(sch_1):page141_i109@mstr_conn.conn17_h71061002(chips)!CONN17_H71061002_PIP1-CONN,H71A!!!F2252!L1!!!!
S!P3V3_STBY!JA9G1!L2!@baseboard_fab2_lib.baseboard_fab2(sch_1):page141_i109@mstr_conn.conn17_h71061002(chips)!CONN17_H71061002_PIP1-CONN,H71A!!!F2252!L2!!!!
S!LED_LAN_2_R_N!JA9G1!L3!@baseboard_fab2_lib.baseboard_fab2(sch_1):page141_i109@mstr_conn.conn17_h71061002(chips)!CONN17_H71061002_PIP1-CONN,H71A!!!F2252!L3!!!!
S!NIC_LED_ACT_ANODE_R!JA9G1!L4!@baseboard_fab2_lib.baseboard_fab2(sch_1):page141_i109@mstr_conn.conn17_h71061002(chips)!CONN17_H71061002_PIP1-CONN,H71A!!!F2252!L4!!!!
S!LED_LAN_1_R_N!JA9G1!L5!@baseboard_fab2_lib.baseboard_fab2(sch_1):page141_i109@mstr_conn.conn17_h71061002(chips)!CONN17_H71061002_PIP1-CONN,H71A!!!F2252!L5!!!!
S!GND_NIC!JA9G1!MH1!@baseboard_fab2_lib.baseboard_fab2(sch_1):page141_i109@mstr_conn.conn17_h71061002(chips)!CONN17_H71061002_PIP1-CONN,H71A!!!F2252!MH1!!!!
S!GND_NIC!JA9G1!MH2!@baseboard_fab2_lib.baseboard_fab2(sch_1):page141_i109@mstr_conn.conn17_h71061002(chips)!CONN17_H71061002_PIP1-CONN,H71A!!!F2252!MH2!!!!
S!GND_LAN_TRCT1234_C!JA9G1!R12!@baseboard_fab2_lib.baseboard_fab2(sch_1):page141_i109@mstr_conn.conn17_h71061002(chips)!CONN17_H71061002_PIP1-CONN,H71A!!!F2252!TRCT1!!!!
S!GND_LAN_TRCT1234_C!JA9G1!R6!@baseboard_fab2_lib.baseboard_fab2(sch_1):page141_i109@mstr_conn.conn17_h71061002(chips)!CONN17_H71061002_PIP1-CONN,H71A!!!F2252!TRCT2!!!!
S!GND_LAN_TRCT1234_C!JA9G1!R1!@baseboard_fab2_lib.baseboard_fab2(sch_1):page141_i109@mstr_conn.conn17_h71061002(chips)!CONN17_H71061002_PIP1-CONN,H71A!!!F2252!TRCT3!!!!
S!GND_LAN_TRCT1234_C!JA9G1!R7!@baseboard_fab2_lib.baseboard_fab2(sch_1):page141_i109@mstr_conn.conn17_h71061002(chips)!CONN17_H71061002_PIP1-CONN,H71A!!!F2252!TRCT4!!!!
S!NIC_MDI_SPRV_RJ45_0_R_DN!JA9G1!R10!@baseboard_fab2_lib.baseboard_fab2(sch_1):page141_i109@mstr_conn.conn17_h71061002(chips)!CONN17_H71061002_PIP1-CONN,H71A!!!F2252!TRD1N!!!!
S!NIC_MDI_SPRV_RJ45_0_R_DP!JA9G1!R11!@baseboard_fab2_lib.baseboard_fab2(sch_1):page141_i109@mstr_conn.conn17_h71061002(chips)!CONN17_H71061002_PIP1-CONN,H71A!!!F2252!TRD1P!!!!
S!NIC_MDI_SPRV_RJ45_1_R_DN!JA9G1!R5!@baseboard_fab2_lib.baseboard_fab2(sch_1):page141_i109@mstr_conn.conn17_h71061002(chips)!CONN17_H71061002_PIP1-CONN,H71A!!!F2252!TRD2N!!!!
S!NIC_MDI_SPRV_RJ45_1_R_DP!JA9G1!R4!@baseboard_fab2_lib.baseboard_fab2(sch_1):page141_i109@mstr_conn.conn17_h71061002(chips)!CONN17_H71061002_PIP1-CONN,H71A!!!F2252!TRD2P!!!!
S!NIC_MDI_SPRV_RJ45_2_R_DN!JA9G1!R2!@baseboard_fab2_lib.baseboard_fab2(sch_1):page141_i109@mstr_conn.conn17_h71061002(chips)!CONN17_H71061002_PIP1-CONN,H71A!!!F2252!TRD3N!!!!
S!NIC_MDI_SPRV_RJ45_2_R_DP!JA9G1!R3!@baseboard_fab2_lib.baseboard_fab2(sch_1):page141_i109@mstr_conn.conn17_h71061002(chips)!CONN17_H71061002_PIP1-CONN,H71A!!!F2252!TRD3P!!!!
S!NIC_MDI_SPRV_RJ45_3_R_DN!JA9G1!R9!@baseboard_fab2_lib.baseboard_fab2(sch_1):page141_i109@mstr_conn.conn17_h71061002(chips)!CONN17_H71061002_PIP1-CONN,H71A!!!F2252!TRD4N!!!!
S!NIC_MDI_SPRV_RJ45_3_R_DP!JA9G1!R8!@baseboard_fab2_lib.baseboard_fab2(sch_1):page141_i109@mstr_conn.conn17_h71061002(chips)!CONN17_H71061002_PIP1-CONN,H71A!!!F2252!TRD4P!!!!
S!GND!U1L3!1!!ADM809_SMLF-IC,D23047-001-GND=A!!!!!!!!
S!PWRGD_P3V3_R1!U1L3!2!@baseboard_fab2_lib.baseboard_fab2(sch_1):page196_i80@mstr_analog.adm809(chips)!ADM809_SMLF-IC,D23047-001-GND=A!!!F4194!RESET_N!!!!
S!P3V3!U1L3!3!@baseboard_fab2_lib.baseboard_fab2(sch_1):page196_i80@mstr_analog.adm809(chips)!ADM809_SMLF-IC,D23047-001-GND=A!!!F4194!VCC!!!!
S!GND!U8E2!1!!ADM809_SMLF-IC,D23047-001-GND=A!!!!!!!!
S!PWRGD_P12V_HSC_DLY_R!U8E2!2!@baseboard_fab2_lib.baseboard_fab2(sch_1):page196_i89@mstr_analog.adm809(chips)!ADM809_SMLF-IC,D23047-001-GND=A!!!F4193!RESET_N!!!!
S!PWRGD_P12V_HSC!U8E2!3!@baseboard_fab2_lib.baseboard_fab2(sch_1):page196_i89@mstr_analog.adm809(chips)!ADM809_SMLF-IC,D23047-001-GND=A!!!F4193!VCC!!!!
S!GND!U1B2!4!!PCA9517_SM-IC,G77073-001-GND=GA!!!!!!!!
S!TP_SMB_PEHPCPU1_EN!U1B2!5!@baseboard_fab2_lib.baseboard_fab2(sch_1):page163_i1@mstr_digital.pca9517(chips)!PCA9517_SM-IC,G77073-001-GND=GA!!!F1986!EN!!!!
S!SMB_CPU1_PE_HP_GTL_R_SCL!U1B2!2!@baseboard_fab2_lib.baseboard_fab2(sch_1):page163_i1@mstr_digital.pca9517(chips)!PCA9517_SM-IC,G77073-001-GND=GA!!!F1986!SCLA!!!!
S!SMB_PEHPCPU1_STBY_LVC3_R_SCL!U1B2!7!@baseboard_fab2_lib.baseboard_fab2(sch_1):page163_i1@mstr_digital.pca9517(chips)!PCA9517_SM-IC,G77073-001-GND=GA!!!F1986!SCLB!!!!
S!SMB_CPU1_PE_HP_GTL_R_SDA!U1B2!3!@baseboard_fab2_lib.baseboard_fab2(sch_1):page163_i1@mstr_digital.pca9517(chips)!PCA9517_SM-IC,G77073-001-GND=GA!!!F1986!SDAA!!!!
S!SMB_PEHPCPU1_STBY_LVC3_R_SDA!U1B2!6!@baseboard_fab2_lib.baseboard_fab2(sch_1):page163_i1@mstr_digital.pca9517(chips)!PCA9517_SM-IC,G77073-001-GND=GA!!!F1986!SDAB!!!!
S!PVCCIO_CPU1!U1B2!1!@baseboard_fab2_lib.baseboard_fab2(sch_1):page163_i1@mstr_digital.pca9517(chips)!PCA9517_SM-IC,G77073-001-GND=GA!!!F1986!VCCA!!!!
S!P3V3_STBY!U1B2!8!@baseboard_fab2_lib.baseboard_fab2(sch_1):page163_i1@mstr_digital.pca9517(chips)!PCA9517_SM-IC,G77073-001-GND=GA!!!F1986!VCCB!!!!
S!GND!U3B1!4!!PCA9617_SSOP-IC,G81764-001-GNDA!!!!!!!!
S!TP_SMB_DDR_KLM_EN!U3B1!5!@baseboard_fab2_lib.baseboard_fab2(sch_1):page99_i75@mstr_digital.pca9617(chips)!PCA9617_SSOP-IC,G81764-001-GNDA!!!F1985!EN!!!!
S!SMB_DDR_KLM_SCL_G!U3B1!2!@baseboard_fab2_lib.baseboard_fab2(sch_1):page99_i75@mstr_digital.pca9617(chips)!PCA9617_SSOP-IC,G81764-001-GNDA!!!F1985!SCLA!!!!
S!SMB_DDR_KLM_VPP_SCL_R!U3B1!7!@baseboard_fab2_lib.baseboard_fab2(sch_1):page99_i75@mstr_digital.pca9617(chips)!PCA9617_SSOP-IC,G81764-001-GNDA!!!F1985!SCLB!!!!
S!SMB_DDR_KLM_SDA_G!U3B1!3!@baseboard_fab2_lib.baseboard_fab2(sch_1):page99_i75@mstr_digital.pca9617(chips)!PCA9617_SSOP-IC,G81764-001-GNDA!!!F1985!SDAA!!!!
S!SMB_DDR_KLM_VPP_SDA_R!U3B1!6!@baseboard_fab2_lib.baseboard_fab2(sch_1):page99_i75@mstr_digital.pca9617(chips)!PCA9617_SSOP-IC,G81764-001-GNDA!!!F1985!SDAB!!!!
S!PVCCIO_CPU1!U3B1!1!@baseboard_fab2_lib.baseboard_fab2(sch_1):page99_i75@mstr_digital.pca9617(chips)!PCA9617_SSOP-IC,G81764-001-GNDA!!!F1985!VCCA!!!!
S!PVPP_KLM!U3B1!8!@baseboard_fab2_lib.baseboard_fab2(sch_1):page99_i75@mstr_digital.pca9617(chips)!PCA9617_SSOP-IC,G81764-001-GNDA!!!F1985!VCCB!!!!
S!GND!U4G1!4!!PCA9617_SSOP-IC,G81764-001-GNDA!!!!!!!!
S!TP_SMB_DDR_GHJ_EN!U4G1!5!@baseboard_fab2_lib.baseboard_fab2(sch_1):page99_i63@mstr_digital.pca9617(chips)!PCA9617_SSOP-IC,G81764-001-GNDA!!!F1984!EN!!!!
S!SMB_DDR_GHJ_SCL_G!U4G1!2!@baseboard_fab2_lib.baseboard_fab2(sch_1):page99_i63@mstr_digital.pca9617(chips)!PCA9617_SSOP-IC,G81764-001-GNDA!!!F1984!SCLA!!!!
S!SMB_DDR_GHJ_VPP_SCL_R!U4G1!7!@baseboard_fab2_lib.baseboard_fab2(sch_1):page99_i63@mstr_digital.pca9617(chips)!PCA9617_SSOP-IC,G81764-001-GNDA!!!F1984!SCLB!!!!
S!SMB_DDR_GHJ_SDA_G!U4G1!3!@baseboard_fab2_lib.baseboard_fab2(sch_1):page99_i63@mstr_digital.pca9617(chips)!PCA9617_SSOP-IC,G81764-001-GNDA!!!F1984!SDAA!!!!
S!SMB_DDR_GHJ_VPP_SDA_R!U4G1!6!@baseboard_fab2_lib.baseboard_fab2(sch_1):page99_i63@mstr_digital.pca9617(chips)!PCA9617_SSOP-IC,G81764-001-GNDA!!!F1984!SDAB!!!!
S!PVCCIO_CPU1!U4G1!1!@baseboard_fab2_lib.baseboard_fab2(sch_1):page99_i63@mstr_digital.pca9617(chips)!PCA9617_SSOP-IC,G81764-001-GNDA!!!F1984!VCCA!!!!
S!PVPP_GHJ!U4G1!8!@baseboard_fab2_lib.baseboard_fab2(sch_1):page99_i63@mstr_digital.pca9617(chips)!PCA9617_SSOP-IC,G81764-001-GNDA!!!F1984!VCCB!!!!
S!GND!U6F1!4!!PCA9617_SSOP-IC,G81764-001-GNDA!!!!!!!!
S!TP_SMB_DDR_ABC_EN!U6F1!5!@baseboard_fab2_lib.baseboard_fab2(sch_1):page99_i15@mstr_digital.pca9617(chips)!PCA9617_SSOP-IC,G81764-001-GNDA!!!F1983!EN!!!!
S!SMB_DDR_ABC_SCL_G!U6F1!2!@baseboard_fab2_lib.baseboard_fab2(sch_1):page99_i15@mstr_digital.pca9617(chips)!PCA9617_SSOP-IC,G81764-001-GNDA!!!F1983!SCLA!!!!
S!SMB_DDR_ABC_VPP_SCL_R!U6F1!7!@baseboard_fab2_lib.baseboard_fab2(sch_1):page99_i15@mstr_digital.pca9617(chips)!PCA9617_SSOP-IC,G81764-001-GNDA!!!F1983!SCLB!!!!
S!SMB_DDR_ABC_SDA_G!U6F1!3!@baseboard_fab2_lib.baseboard_fab2(sch_1):page99_i15@mstr_digital.pca9617(chips)!PCA9617_SSOP-IC,G81764-001-GNDA!!!F1983!SDAA!!!!
S!SMB_DDR_ABC_VPP_SDA_R!U6F1!6!@baseboard_fab2_lib.baseboard_fab2(sch_1):page99_i15@mstr_digital.pca9617(chips)!PCA9617_SSOP-IC,G81764-001-GNDA!!!F1983!SDAB!!!!
S!PVCCIO_CPU0!U6F1!1!@baseboard_fab2_lib.baseboard_fab2(sch_1):page99_i15@mstr_digital.pca9617(chips)!PCA9617_SSOP-IC,G81764-001-GNDA!!!F1983!VCCA!!!!
S!PVPP_ABC!U6F1!8!@baseboard_fab2_lib.baseboard_fab2(sch_1):page99_i15@mstr_digital.pca9617(chips)!PCA9617_SSOP-IC,G81764-001-GNDA!!!F1983!VCCB!!!!
S!GND!U7E1!4!!PCA9617_SSOP-IC,G81764-001-GNDA!!!!!!!!
S!TP_SMB_DDR_DEF_EN!U7E1!5!@baseboard_fab2_lib.baseboard_fab2(sch_1):page99_i61@mstr_digital.pca9617(chips)!PCA9617_SSOP-IC,G81764-001-GNDA!!!F1982!EN!!!!
S!SMB_DDR_DEF_SCL_G!U7E1!2!@baseboard_fab2_lib.baseboard_fab2(sch_1):page99_i61@mstr_digital.pca9617(chips)!PCA9617_SSOP-IC,G81764-001-GNDA!!!F1982!SCLA!!!!
S!SMB_DDR_DEF_VPP_SCL_R!U7E1!7!@baseboard_fab2_lib.baseboard_fab2(sch_1):page99_i61@mstr_digital.pca9617(chips)!PCA9617_SSOP-IC,G81764-001-GNDA!!!F1982!SCLB!!!!
S!SMB_DDR_DEF_SDA_G!U7E1!3!@baseboard_fab2_lib.baseboard_fab2(sch_1):page99_i61@mstr_digital.pca9617(chips)!PCA9617_SSOP-IC,G81764-001-GNDA!!!F1982!SDAA!!!!
S!SMB_DDR_DEF_VPP_SDA_R!U7E1!6!@baseboard_fab2_lib.baseboard_fab2(sch_1):page99_i61@mstr_digital.pca9617(chips)!PCA9617_SSOP-IC,G81764-001-GNDA!!!F1982!SDAB!!!!
S!PVCCIO_CPU0!U7E1!1!@baseboard_fab2_lib.baseboard_fab2(sch_1):page99_i61@mstr_digital.pca9617(chips)!PCA9617_SSOP-IC,G81764-001-GNDA!!!F1982!VCCA!!!!
S!PVPP_DEF!U7E1!8!@baseboard_fab2_lib.baseboard_fab2(sch_1):page99_i61@mstr_digital.pca9617(chips)!PCA9617_SSOP-IC,G81764-001-GNDA!!!F1982!VCCB!!!!
S!GND!U2T1!15!@baseboard_fab2_lib.baseboard_fab2(sch_1):page154_i75@mstr_digital.pi3b3257a(chips)!PI3B3257A_TSSOPLF-IC,E16801-001!!!F1981!EN!!!!
S!GND!U2T1!8!@baseboard_fab2_lib.baseboard_fab2(sch_1):page154_i75@mstr_digital.pi3b3257a(chips)!PI3B3257A_TSSOPLF-IC,E16801-001!!!F1981!GND!!!!
S!SPI_PCH_IO2_R1!U2T1!2!@baseboard_fab2_lib.baseboard_fab2(sch_1):page154_i75@mstr_digital.pi3b3257a(chips)!PI3B3257A_TSSOPLF-IC,E16801-001!!!F1981!IA0!!!!
S!TP_SPI_SWITCH1_3!U2T1!3!@baseboard_fab2_lib.baseboard_fab2(sch_1):page154_i75@mstr_digital.pi3b3257a(chips)!PI3B3257A_TSSOPLF-IC,E16801-001!!!F1981!IA1!!!!
S!SPI_PCH_IO3_R1!U2T1!5!@baseboard_fab2_lib.baseboard_fab2(sch_1):page154_i75@mstr_digital.pi3b3257a(chips)!PI3B3257A_TSSOPLF-IC,E16801-001!!!F1981!IB0!!!!
S!TP_SPI_SWITCH1_6!U2T1!6!@baseboard_fab2_lib.baseboard_fab2(sch_1):page154_i75@mstr_digital.pi3b3257a(chips)!PI3B3257A_TSSOPLF-IC,E16801-001!!!F1981!IB1!!!!
S!TP_SPI_SWITCH1_11!U2T1!11!@baseboard_fab2_lib.baseboard_fab2(sch_1):page154_i75@mstr_digital.pi3b3257a(chips)!PI3B3257A_TSSOPLF-IC,E16801-001!!!F1981!IC0!!!!
S!TP_SPI_SWITCH1_10!U2T1!10!@baseboard_fab2_lib.baseboard_fab2(sch_1):page154_i75@mstr_digital.pi3b3257a(chips)!PI3B3257A_TSSOPLF-IC,E16801-001!!!F1981!IC1!!!!
S!TP_SPI_SWITCH1_14!U2T1!14!@baseboard_fab2_lib.baseboard_fab2(sch_1):page154_i75@mstr_digital.pi3b3257a(chips)!PI3B3257A_TSSOPLF-IC,E16801-001!!!F1981!ID0!!!!
S!TP_SPI_SWITCH1_13!U2T1!13!@baseboard_fab2_lib.baseboard_fab2(sch_1):page154_i75@mstr_digital.pi3b3257a(chips)!PI3B3257A_TSSOPLF-IC,E16801-001!!!F1981!ID1!!!!
S!FM_BIOS_SPI_BMC_CTRL!U2T1!1!@baseboard_fab2_lib.baseboard_fab2(sch_1):page154_i75@mstr_digital.pi3b3257a(chips)!PI3B3257A_TSSOPLF-IC,E16801-001!!!F1981!S!!!!
S!P3V3_STBY!U2T1!16!@baseboard_fab2_lib.baseboard_fab2(sch_1):page154_i75@mstr_digital.pi3b3257a(chips)!PI3B3257A_TSSOPLF-IC,E16801-001!!!F1981!VCC!!!!
S!SPI_BIOS_SOCKET_IO2!U2T1!4!@baseboard_fab2_lib.baseboard_fab2(sch_1):page154_i75@mstr_digital.pi3b3257a(chips)!PI3B3257A_TSSOPLF-IC,E16801-001!!!F1981!YA!!!!
S!SPI_BIOS_SOCKET_IO3!U2T1!7!@baseboard_fab2_lib.baseboard_fab2(sch_1):page154_i75@mstr_digital.pi3b3257a(chips)!PI3B3257A_TSSOPLF-IC,E16801-001!!!F1981!YB!!!!
S!TP_SPI_SWITCH1_9!U2T1!9!@baseboard_fab2_lib.baseboard_fab2(sch_1):page154_i75@mstr_digital.pi3b3257a(chips)!PI3B3257A_TSSOPLF-IC,E16801-001!!!F1981!YC!!!!
S!TP_SPI_SWITCH1_12!U2T1!12!@baseboard_fab2_lib.baseboard_fab2(sch_1):page154_i75@mstr_digital.pi3b3257a(chips)!PI3B3257A_TSSOPLF-IC,E16801-001!!!F1981!YD!!!!
S!GND!U8F1!15!@baseboard_fab2_lib.baseboard_fab2(sch_1):page154_i74@mstr_digital.pi3b3257a(chips)!PI3B3257A_TSSOPLF-IC,E16801-001!!!F1980!EN!!!!
S!GND!U8F1!8!@baseboard_fab2_lib.baseboard_fab2(sch_1):page154_i74@mstr_digital.pi3b3257a(chips)!PI3B3257A_TSSOPLF-IC,E16801-001!!!F1980!GND!!!!
S!SPI_PCH_CLK!U8F1!2!@baseboard_fab2_lib.baseboard_fab2(sch_1):page154_i74@mstr_digital.pi3b3257a(chips)!PI3B3257A_TSSOPLF-IC,E16801-001!!!F1980!IA0!!!!
S!SPI_BMC_CLK!U8F1!3!@baseboard_fab2_lib.baseboard_fab2(sch_1):page154_i74@mstr_digital.pi3b3257a(chips)!PI3B3257A_TSSOPLF-IC,E16801-001!!!F1980!IA1!!!!
S!SPI_PCH_MOSI!U8F1!5!@baseboard_fab2_lib.baseboard_fab2(sch_1):page154_i74@mstr_digital.pi3b3257a(chips)!PI3B3257A_TSSOPLF-IC,E16801-001!!!F1980!IB0!!!!
S!SPI_BMC_DO!U8F1!6!@baseboard_fab2_lib.baseboard_fab2(sch_1):page154_i74@mstr_digital.pi3b3257a(chips)!PI3B3257A_TSSOPLF-IC,E16801-001!!!F1980!IB1!!!!
S!SPI_PCH_CS0_N!U8F1!11!@baseboard_fab2_lib.baseboard_fab2(sch_1):page154_i74@mstr_digital.pi3b3257a(chips)!PI3B3257A_TSSOPLF-IC,E16801-001!!!F1980!IC0!!!!
S!SPI_BMC_CS0_N!U8F1!10!@baseboard_fab2_lib.baseboard_fab2(sch_1):page154_i74@mstr_digital.pi3b3257a(chips)!PI3B3257A_TSSOPLF-IC,E16801-001!!!F1980!IC1!!!!
S!SPI_PCH_MISO_R!U8F1!14!@baseboard_fab2_lib.baseboard_fab2(sch_1):page154_i74@mstr_digital.pi3b3257a(chips)!PI3B3257A_TSSOPLF-IC,E16801-001!!!F1980!ID0!!!!
S!SPI_BMC_DI!U8F1!13!@baseboard_fab2_lib.baseboard_fab2(sch_1):page154_i74@mstr_digital.pi3b3257a(chips)!PI3B3257A_TSSOPLF-IC,E16801-001!!!F1980!ID1!!!!
S!FM_BIOS_SPI_BMC_CTRL!U8F1!1!@baseboard_fab2_lib.baseboard_fab2(sch_1):page154_i74@mstr_digital.pi3b3257a(chips)!PI3B3257A_TSSOPLF-IC,E16801-001!!!F1980!S!!!!
S!P3V3_STBY!U8F1!16!@baseboard_fab2_lib.baseboard_fab2(sch_1):page154_i74@mstr_digital.pi3b3257a(chips)!PI3B3257A_TSSOPLF-IC,E16801-001!!!F1980!VCC!!!!
S!SPI_SWITCH_CLK!U8F1!4!@baseboard_fab2_lib.baseboard_fab2(sch_1):page154_i74@mstr_digital.pi3b3257a(chips)!PI3B3257A_TSSOPLF-IC,E16801-001!!!F1980!YA!!!!
S!SPI_SWITCH_MOSI!U8F1!7!@baseboard_fab2_lib.baseboard_fab2(sch_1):page154_i74@mstr_digital.pi3b3257a(chips)!PI3B3257A_TSSOPLF-IC,E16801-001!!!F1980!YB!!!!
S!SPI_SWITCH_CS0_N!U8F1!9!@baseboard_fab2_lib.baseboard_fab2(sch_1):page154_i74@mstr_digital.pi3b3257a(chips)!PI3B3257A_TSSOPLF-IC,E16801-001!!!F1980!YC!!!!
S!SPI_SWITCH_MISO!U8F1!12!@baseboard_fab2_lib.baseboard_fab2(sch_1):page154_i74@mstr_digital.pi3b3257a(chips)!PI3B3257A_TSSOPLF-IC,E16801-001!!!F1980!YD!!!!
S!FM_DIMM_EVENT_FET!R4U4!1!@baseboard_fab2_lib.baseboard_fab2(sch_1):page94_i104@mstr_discrete.res(chips)!RES_0402-33.0K,5%,1/16W,CHIP,GA!!!F758!A!!!!
S!GND!R4U4!2!@baseboard_fab2_lib.baseboard_fab2(sch_1):page94_i104@mstr_discrete.res(chips)!RES_0402-33.0K,5%,1/16W,CHIP,GA!!!F758!B!!!!
S!GND!J1F1!A2!@baseboard_fab2_lib.baseboard_fab2(sch_1):page181_i111@mstr_conn.conn76_h22707001(chips)!CONN76_H22707001_THMT1-CONN,H2A!!!F2238!GNDA2!!!!
S!FAN_TACH3_R!J1F1!A4!@baseboard_fab2_lib.baseboard_fab2(sch_1):page181_i111@mstr_conn.conn76_h22707001(chips)!CONN76_H22707001_THMT1-CONN,H2A!!!F2238!GNDA4!!!!
S!IRQ_SML1_PMBUS_ALERT_R_N!J1F1!A6!@baseboard_fab2_lib.baseboard_fab2(sch_1):page181_i111@mstr_conn.conn76_h22707001(chips)!CONN76_H22707001_THMT1-CONN,H2A!!!F2238!GNDA6!!!!
S!GND!J1F1!A8!@baseboard_fab2_lib.baseboard_fab2(sch_1):page181_i111@mstr_conn.conn76_h22707001(chips)!CONN76_H22707001_THMT1-CONN,H2A!!!F2238!GNDA8!!!!
S!GND!J1F1!C1!@baseboard_fab2_lib.baseboard_fab2(sch_1):page181_i111@mstr_conn.conn76_h22707001(chips)!CONN76_H22707001_THMT1-CONN,H2A!!!F2238!GNDC1!!!!
S!GND!J1F1!C3!@baseboard_fab2_lib.baseboard_fab2(sch_1):page181_i111@mstr_conn.conn76_h22707001(chips)!CONN76_H22707001_THMT1-CONN,H2A!!!F2238!GNDC3!!!!
S!GND!J1F1!C5!@baseboard_fab2_lib.baseboard_fab2(sch_1):page181_i111@mstr_conn.conn76_h22707001(chips)!CONN76_H22707001_THMT1-CONN,H2A!!!F2238!GNDC5!!!!
S!GND!J1F1!C7!@baseboard_fab2_lib.baseboard_fab2(sch_1):page181_i111@mstr_conn.conn76_h22707001(chips)!CONN76_H22707001_THMT1-CONN,H2A!!!F2238!GNDC7!!!!
S!GND!J1F1!D2!@baseboard_fab2_lib.baseboard_fab2(sch_1):page181_i111@mstr_conn.conn76_h22707001(chips)!CONN76_H22707001_THMT1-CONN,H2A!!!F2238!GNDD2!!!!
S!FAN_TACH0_R!J1F1!D4!@baseboard_fab2_lib.baseboard_fab2(sch_1):page181_i111@mstr_conn.conn76_h22707001(chips)!CONN76_H22707001_THMT1-CONN,H2A!!!F2238!GNDD4!!!!
S!GND!J1F1!D6!@baseboard_fab2_lib.baseboard_fab2(sch_1):page181_i111@mstr_conn.conn76_h22707001(chips)!CONN76_H22707001_THMT1-CONN,H2A!!!F2238!GNDD6!!!!
S!GND!J1F1!D8!@baseboard_fab2_lib.baseboard_fab2(sch_1):page181_i111@mstr_conn.conn76_h22707001(chips)!CONN76_H22707001_THMT1-CONN,H2A!!!F2238!GNDD8!!!!
S!GND!J1F1!F1!@baseboard_fab2_lib.baseboard_fab2(sch_1):page181_i111@mstr_conn.conn76_h22707001(chips)!CONN76_H22707001_THMT1-CONN,H2A!!!F2238!GNDF1!!!!
S!GND!J1F1!F3!@baseboard_fab2_lib.baseboard_fab2(sch_1):page181_i111@mstr_conn.conn76_h22707001(chips)!CONN76_H22707001_THMT1-CONN,H2A!!!F2238!GNDF3!!!!
S!FM_MB_SLOT_ID0!J1F1!F5!@baseboard_fab2_lib.baseboard_fab2(sch_1):page181_i111@mstr_conn.conn76_h22707001(chips)!CONN76_H22707001_THMT1-CONN,H2A!!!F2238!GNDF5!!!!
S!GND!J1F1!F7!@baseboard_fab2_lib.baseboard_fab2(sch_1):page181_i111@mstr_conn.conn76_h22707001(chips)!CONN76_H22707001_THMT1-CONN,H2A!!!F2238!GNDF7!!!!
S!GND!J1F1!G2!@baseboard_fab2_lib.baseboard_fab2(sch_1):page181_i111@mstr_conn.conn76_h22707001(chips)!CONN76_H22707001_THMT1-CONN,H2A!!!F2238!GNDG2!!!!
S!GND!J1F1!G4!@baseboard_fab2_lib.baseboard_fab2(sch_1):page181_i111@mstr_conn.conn76_h22707001(chips)!CONN76_H22707001_THMT1-CONN,H2A!!!F2238!GNDG4!!!!
S!GND!J1F1!G6!@baseboard_fab2_lib.baseboard_fab2(sch_1):page181_i111@mstr_conn.conn76_h22707001(chips)!CONN76_H22707001_THMT1-CONN,H2A!!!F2238!GNDG6!!!!
S!GND!J1F1!G8!@baseboard_fab2_lib.baseboard_fab2(sch_1):page181_i111@mstr_conn.conn76_h22707001(chips)!CONN76_H22707001_THMT1-CONN,H2A!!!F2238!GNDG8!!!!
S!GND!J1F1!I1!@baseboard_fab2_lib.baseboard_fab2(sch_1):page181_i111@mstr_conn.conn76_h22707001(chips)!CONN76_H22707001_THMT1-CONN,H2A!!!F2238!GNDI1!!!!
S!FM_ENABLE_FAN_POWER!J1F1!I3!@baseboard_fab2_lib.baseboard_fab2(sch_1):page181_i111@mstr_conn.conn76_h22707001(chips)!CONN76_H22707001_THMT1-CONN,H2A!!!F2238!GNDI3!!!!
S!RST_PCIE_MIDPLANE_N!J1F1!I5!@baseboard_fab2_lib.baseboard_fab2(sch_1):page181_i111@mstr_conn.conn76_h22707001(chips)!CONN76_H22707001_THMT1-CONN,H2A!!!F2238!GNDI5!!!!
S!GND!J1F1!I7!@baseboard_fab2_lib.baseboard_fab2(sch_1):page181_i111@mstr_conn.conn76_h22707001(chips)!CONN76_H22707001_THMT1-CONN,H2A!!!F2238!GNDI7!!!!
S!GND!J1F1!J2!@baseboard_fab2_lib.baseboard_fab2(sch_1):page181_i111@mstr_conn.conn76_h22707001(chips)!CONN76_H22707001_THMT1-CONN,H2A!!!F2238!GNDJ2!!!!
S!GND!J1F1!J4!@baseboard_fab2_lib.baseboard_fab2(sch_1):page181_i111@mstr_conn.conn76_h22707001(chips)!CONN76_H22707001_THMT1-CONN,H2A!!!F2238!GNDJ4!!!!
S!GND!J1F1!J6!@baseboard_fab2_lib.baseboard_fab2(sch_1):page181_i111@mstr_conn.conn76_h22707001(chips)!CONN76_H22707001_THMT1-CONN,H2A!!!F2238!GNDJ6!!!!
S!GND!J1F1!J8!@baseboard_fab2_lib.baseboard_fab2(sch_1):page181_i111@mstr_conn.conn76_h22707001(chips)!CONN76_H22707001_THMT1-CONN,H2A!!!F2238!GNDJ8!!!!
S!P3E_CPU1_PE3_MP_RXN<0>!J1F1!A1!@baseboard_fab2_lib.baseboard_fab2(sch_1):page181_i111@mstr_conn.conn76_h22707001(chips)!CONN76_H22707001_THMT1-CONN,H2A!!!F2238!IOA1!!!!
S!P3E_CPU1_PE3_MP_RXP<6>!J1F1!A3!@baseboard_fab2_lib.baseboard_fab2(sch_1):page181_i111@mstr_conn.conn76_h22707001(chips)!CONN76_H22707001_THMT1-CONN,H2A!!!F2238!IOA3!!!!
S!NIC_MDI_MNG_TX_DP!J1F1!A5!@baseboard_fab2_lib.baseboard_fab2(sch_1):page181_i111@mstr_conn.conn76_h22707001(chips)!CONN76_H22707001_THMT1-CONN,H2A!!!F2238!IOA5!!!!
S!P3E_CPU1_PE3_MP_C_TXN<3>!J1F1!A7!@baseboard_fab2_lib.baseboard_fab2(sch_1):page181_i111@mstr_conn.conn76_h22707001(chips)!CONN76_H22707001_THMT1-CONN,H2A!!!F2238!IOA7!!!!
S!P3E_CPU1_PE3_MP_RXP<0>!J1F1!B1!@baseboard_fab2_lib.baseboard_fab2(sch_1):page181_i111@mstr_conn.conn76_h22707001(chips)!CONN76_H22707001_THMT1-CONN,H2A!!!F2238!IOB1!!!!
S!P3E_CPU1_PE3_MP_RXN<3>!J1F1!B2!@baseboard_fab2_lib.baseboard_fab2(sch_1):page181_i111@mstr_conn.conn76_h22707001(chips)!CONN76_H22707001_THMT1-CONN,H2A!!!F2238!IOB2!!!!
S!P3E_CPU1_PE3_MP_RXN<6>!J1F1!B3!@baseboard_fab2_lib.baseboard_fab2(sch_1):page181_i111@mstr_conn.conn76_h22707001(chips)!CONN76_H22707001_THMT1-CONN,H2A!!!F2238!IOB3!!!!
S!FAN_TACH2_R!J1F1!B4!@baseboard_fab2_lib.baseboard_fab2(sch_1):page181_i111@mstr_conn.conn76_h22707001(chips)!CONN76_H22707001_THMT1-CONN,H2A!!!F2238!IOB4!!!!
S!NIC_MDI_MNG_TX_DN!J1F1!B5!@baseboard_fab2_lib.baseboard_fab2(sch_1):page181_i111@mstr_conn.conn76_h22707001(chips)!CONN76_H22707001_THMT1-CONN,H2A!!!F2238!IOB5!!!!
S!SMB_BMC_PMBUS_STBY_LVC3_SDA!J1F1!B6!@baseboard_fab2_lib.baseboard_fab2(sch_1):page181_i111@mstr_conn.conn76_h22707001(chips)!CONN76_H22707001_THMT1-CONN,H2A!!!F2238!IOB6!!!!
S!P3E_CPU1_PE3_MP_C_TXP<3>!J1F1!B7!@baseboard_fab2_lib.baseboard_fab2(sch_1):page181_i111@mstr_conn.conn76_h22707001(chips)!CONN76_H22707001_THMT1-CONN,H2A!!!F2238!IOB7!!!!
S!P3E_CPU1_PE3_MP_C_TXN<0>!J1F1!B8!@baseboard_fab2_lib.baseboard_fab2(sch_1):page181_i111@mstr_conn.conn76_h22707001(chips)!CONN76_H22707001_THMT1-CONN,H2A!!!F2238!IOB8!!!!
S!P3E_CPU1_PE3_MP_RXP<3>!J1F1!C2!@baseboard_fab2_lib.baseboard_fab2(sch_1):page181_i111@mstr_conn.conn76_h22707001(chips)!CONN76_H22707001_THMT1-CONN,H2A!!!F2238!IOC2!!!!
S!FAN_TACH1_R!J1F1!C4!@baseboard_fab2_lib.baseboard_fab2(sch_1):page181_i111@mstr_conn.conn76_h22707001(chips)!CONN76_H22707001_THMT1-CONN,H2A!!!F2238!IOC4!!!!
S!SMB_BMC_PMBUS_STBY_LVC3_SCL!J1F1!C6!@baseboard_fab2_lib.baseboard_fab2(sch_1):page181_i111@mstr_conn.conn76_h22707001(chips)!CONN76_H22707001_THMT1-CONN,H2A!!!F2238!IOC6!!!!
S!P3E_CPU1_PE3_MP_C_TXP<0>!J1F1!C8!@baseboard_fab2_lib.baseboard_fab2(sch_1):page181_i111@mstr_conn.conn76_h22707001(chips)!CONN76_H22707001_THMT1-CONN,H2A!!!F2238!IOC8!!!!
S!P3E_CPU1_PE3_MP_RXN<1>!J1F1!D1!@baseboard_fab2_lib.baseboard_fab2(sch_1):page181_i111@mstr_conn.conn76_h22707001(chips)!CONN76_H22707001_THMT1-CONN,H2A!!!F2238!IOD1!!!!
S!P3E_CPU1_PE3_MP_RXN<7>!J1F1!D3!@baseboard_fab2_lib.baseboard_fab2(sch_1):page181_i111@mstr_conn.conn76_h22707001(chips)!CONN76_H22707001_THMT1-CONN,H2A!!!F2238!IOD3!!!!
S!NIC_MDI_MNG_RX_DP!J1F1!D5!@baseboard_fab2_lib.baseboard_fab2(sch_1):page181_i111@mstr_conn.conn76_h22707001(chips)!CONN76_H22707001_THMT1-CONN,H2A!!!F2238!IOD5!!!!
S!P3E_CPU1_PE3_MP_C_TXN<4>!J1F1!D7!@baseboard_fab2_lib.baseboard_fab2(sch_1):page181_i111@mstr_conn.conn76_h22707001(chips)!CONN76_H22707001_THMT1-CONN,H2A!!!F2238!IOD7!!!!
S!P3E_CPU1_PE3_MP_RXP<1>!J1F1!E1!@baseboard_fab2_lib.baseboard_fab2(sch_1):page181_i111@mstr_conn.conn76_h22707001(chips)!CONN76_H22707001_THMT1-CONN,H2A!!!F2238!IOE1!!!!
S!P3E_CPU1_PE3_MP_RXN<4>!J1F1!E2!@baseboard_fab2_lib.baseboard_fab2(sch_1):page181_i111@mstr_conn.conn76_h22707001(chips)!CONN76_H22707001_THMT1-CONN,H2A!!!F2238!IOE2!!!!
S!P3E_CPU1_PE3_MP_RXP<7>!J1F1!E3!@baseboard_fab2_lib.baseboard_fab2(sch_1):page181_i111@mstr_conn.conn76_h22707001(chips)!CONN76_H22707001_THMT1-CONN,H2A!!!F2238!IOE3!!!!
S!FM_MATED_IN_N!J1F1!E4!@baseboard_fab2_lib.baseboard_fab2(sch_1):page181_i111@mstr_conn.conn76_h22707001(chips)!CONN76_H22707001_THMT1-CONN,H2A!!!F2238!IOE4!!!!
S!NIC_MDI_MNG_RX_DN!J1F1!E5!@baseboard_fab2_lib.baseboard_fab2(sch_1):page181_i111@mstr_conn.conn76_h22707001(chips)!CONN76_H22707001_THMT1-CONN,H2A!!!F2238!IOE5!!!!
S!P3E_CPU1_PE3_MP_C_TXN<6>!J1F1!E6!@baseboard_fab2_lib.baseboard_fab2(sch_1):page181_i111@mstr_conn.conn76_h22707001(chips)!CONN76_H22707001_THMT1-CONN,H2A!!!F2238!IOE6!!!!
S!P3E_CPU1_PE3_MP_C_TXP<4>!J1F1!E7!@baseboard_fab2_lib.baseboard_fab2(sch_1):page181_i111@mstr_conn.conn76_h22707001(chips)!CONN76_H22707001_THMT1-CONN,H2A!!!F2238!IOE7!!!!
S!P3E_CPU1_PE3_MP_C_TXN<1>!J1F1!E8!@baseboard_fab2_lib.baseboard_fab2(sch_1):page181_i111@mstr_conn.conn76_h22707001(chips)!CONN76_H22707001_THMT1-CONN,H2A!!!F2238!IOE8!!!!
S!P3E_CPU1_PE3_MP_RXP<4>!J1F1!F2!@baseboard_fab2_lib.baseboard_fab2(sch_1):page181_i111@mstr_conn.conn76_h22707001(chips)!CONN76_H22707001_THMT1-CONN,H2A!!!F2238!IOF2!!!!
S!FAN_PWM_OUT_SYS0_R1!J1F1!F4!@baseboard_fab2_lib.baseboard_fab2(sch_1):page181_i111@mstr_conn.conn76_h22707001(chips)!CONN76_H22707001_THMT1-CONN,H2A!!!F2238!IOF4!!!!
S!P3E_CPU1_PE3_MP_C_TXP<6>!J1F1!F6!@baseboard_fab2_lib.baseboard_fab2(sch_1):page181_i111@mstr_conn.conn76_h22707001(chips)!CONN76_H22707001_THMT1-CONN,H2A!!!F2238!IOF6!!!!
S!P3E_CPU1_PE3_MP_C_TXP<1>!J1F1!F8!@baseboard_fab2_lib.baseboard_fab2(sch_1):page181_i111@mstr_conn.conn76_h22707001(chips)!CONN76_H22707001_THMT1-CONN,H2A!!!F2238!IOF8!!!!
S!P3E_CPU1_PE3_MP_RXP<2>!J1F1!G1!@baseboard_fab2_lib.baseboard_fab2(sch_1):page181_i111@mstr_conn.conn76_h22707001(chips)!CONN76_H22707001_THMT1-CONN,H2A!!!F2238!IOG1!!!!
S!SPA_MID_DBG_TX!J1F1!G3!@baseboard_fab2_lib.baseboard_fab2(sch_1):page181_i111@mstr_conn.conn76_h22707001(chips)!CONN76_H22707001_THMT1-CONN,H2A!!!F2238!IOG3!!!!
S!FM_MB_SLOT_ID1!J1F1!G5!@baseboard_fab2_lib.baseboard_fab2(sch_1):page181_i111@mstr_conn.conn76_h22707001(chips)!CONN76_H22707001_THMT1-CONN,H2A!!!F2238!IOG5!!!!
S!P3E_CPU1_PE3_MP_C_TXP<5>!J1F1!G7!@baseboard_fab2_lib.baseboard_fab2(sch_1):page181_i111@mstr_conn.conn76_h22707001(chips)!CONN76_H22707001_THMT1-CONN,H2A!!!F2238!IOG7!!!!
S!P3E_CPU1_PE3_MP_RXN<2>!J1F1!H1!@baseboard_fab2_lib.baseboard_fab2(sch_1):page181_i111@mstr_conn.conn76_h22707001(chips)!CONN76_H22707001_THMT1-CONN,H2A!!!F2238!IOH1!!!!
S!P3E_CPU1_PE3_MP_RXP<5>!J1F1!H2!@baseboard_fab2_lib.baseboard_fab2(sch_1):page181_i111@mstr_conn.conn76_h22707001(chips)!CONN76_H22707001_THMT1-CONN,H2A!!!F2238!IOH2!!!!
S!SPA_MID_DBG_RX!J1F1!H3!@baseboard_fab2_lib.baseboard_fab2(sch_1):page181_i111@mstr_conn.conn76_h22707001(chips)!CONN76_H22707001_THMT1-CONN,H2A!!!F2238!IOH3!!!!
S!CLK_100M_AIRMAX8_PE1_DP!J1F1!H4!@baseboard_fab2_lib.baseboard_fab2(sch_1):page181_i111@mstr_conn.conn76_h22707001(chips)!CONN76_H22707001_THMT1-CONN,H2A!!!F2238!IOH4!!!!
S!FM_MB_SLOT_ID2!J1F1!H5!@baseboard_fab2_lib.baseboard_fab2(sch_1):page181_i111@mstr_conn.conn76_h22707001(chips)!CONN76_H22707001_THMT1-CONN,H2A!!!F2238!IOH5!!!!
S!P3E_CPU1_PE3_MP_C_TXP<7>!J1F1!H6!@baseboard_fab2_lib.baseboard_fab2(sch_1):page181_i111@mstr_conn.conn76_h22707001(chips)!CONN76_H22707001_THMT1-CONN,H2A!!!F2238!IOH6!!!!
S!P3E_CPU1_PE3_MP_C_TXN<5>!J1F1!H7!@baseboard_fab2_lib.baseboard_fab2(sch_1):page181_i111@mstr_conn.conn76_h22707001(chips)!CONN76_H22707001_THMT1-CONN,H2A!!!F2238!IOH7!!!!
S!P3E_CPU1_PE3_MP_C_TXN<2>!J1F1!H8!@baseboard_fab2_lib.baseboard_fab2(sch_1):page181_i111@mstr_conn.conn76_h22707001(chips)!CONN76_H22707001_THMT1-CONN,H2A!!!F2238!IOH8!!!!
S!P3E_CPU1_PE3_MP_RXN<5>!J1F1!I2!@baseboard_fab2_lib.baseboard_fab2(sch_1):page181_i111@mstr_conn.conn76_h22707001(chips)!CONN76_H22707001_THMT1-CONN,H2A!!!F2238!IOI2!!!!
S!CLK_100M_AIRMAX8_PE1_DN!J1F1!I4!@baseboard_fab2_lib.baseboard_fab2(sch_1):page181_i111@mstr_conn.conn76_h22707001(chips)!CONN76_H22707001_THMT1-CONN,H2A!!!F2238!IOI4!!!!
S!P3E_CPU1_PE3_MP_C_TXN<7>!J1F1!I6!@baseboard_fab2_lib.baseboard_fab2(sch_1):page181_i111@mstr_conn.conn76_h22707001(chips)!CONN76_H22707001_THMT1-CONN,H2A!!!F2238!IOI6!!!!
S!P3E_CPU1_PE3_MP_C_TXP<2>!J1F1!I8!@baseboard_fab2_lib.baseboard_fab2(sch_1):page181_i111@mstr_conn.conn76_h22707001(chips)!CONN76_H22707001_THMT1-CONN,H2A!!!F2238!IOI8!!!!
S!GND!J1C1!A2!@baseboard_fab2_lib.baseboard_fab2(sch_1):page182_i18@mstr_conn.conn76_h22707001(chips)!CONN76_H22707001_THMT1-CONN,H2A!!!F2239!GNDA2!!!!
S!GND!J1C1!A4!@baseboard_fab2_lib.baseboard_fab2(sch_1):page182_i18@mstr_conn.conn76_h22707001(chips)!CONN76_H22707001_THMT1-CONN,H2A!!!F2239!GNDA4!!!!
S!GND!J1C1!A6!@baseboard_fab2_lib.baseboard_fab2(sch_1):page182_i18@mstr_conn.conn76_h22707001(chips)!CONN76_H22707001_THMT1-CONN,H2A!!!F2239!GNDA6!!!!
S!GND!J1C1!A8!@baseboard_fab2_lib.baseboard_fab2(sch_1):page182_i18@mstr_conn.conn76_h22707001(chips)!CONN76_H22707001_THMT1-CONN,H2A!!!F2239!GNDA8!!!!
S!GND!J1C1!C1!@baseboard_fab2_lib.baseboard_fab2(sch_1):page182_i18@mstr_conn.conn76_h22707001(chips)!CONN76_H22707001_THMT1-CONN,H2A!!!F2239!GNDC1!!!!
S!GND!J1C1!C3!@baseboard_fab2_lib.baseboard_fab2(sch_1):page182_i18@mstr_conn.conn76_h22707001(chips)!CONN76_H22707001_THMT1-CONN,H2A!!!F2239!GNDC3!!!!
S!GND!J1C1!C5!@baseboard_fab2_lib.baseboard_fab2(sch_1):page182_i18@mstr_conn.conn76_h22707001(chips)!CONN76_H22707001_THMT1-CONN,H2A!!!F2239!GNDC5!!!!
S!GND!J1C1!C7!@baseboard_fab2_lib.baseboard_fab2(sch_1):page182_i18@mstr_conn.conn76_h22707001(chips)!CONN76_H22707001_THMT1-CONN,H2A!!!F2239!GNDC7!!!!
S!GND!J1C1!D2!@baseboard_fab2_lib.baseboard_fab2(sch_1):page182_i18@mstr_conn.conn76_h22707001(chips)!CONN76_H22707001_THMT1-CONN,H2A!!!F2239!GNDD2!!!!
S!GND!J1C1!D4!@baseboard_fab2_lib.baseboard_fab2(sch_1):page182_i18@mstr_conn.conn76_h22707001(chips)!CONN76_H22707001_THMT1-CONN,H2A!!!F2239!GNDD4!!!!
S!GND!J1C1!D6!@baseboard_fab2_lib.baseboard_fab2(sch_1):page182_i18@mstr_conn.conn76_h22707001(chips)!CONN76_H22707001_THMT1-CONN,H2A!!!F2239!GNDD6!!!!
S!GND!J1C1!D8!@baseboard_fab2_lib.baseboard_fab2(sch_1):page182_i18@mstr_conn.conn76_h22707001(chips)!CONN76_H22707001_THMT1-CONN,H2A!!!F2239!GNDD8!!!!
S!GND!J1C1!F1!@baseboard_fab2_lib.baseboard_fab2(sch_1):page182_i18@mstr_conn.conn76_h22707001(chips)!CONN76_H22707001_THMT1-CONN,H2A!!!F2239!GNDF1!!!!
S!GND!J1C1!F3!@baseboard_fab2_lib.baseboard_fab2(sch_1):page182_i18@mstr_conn.conn76_h22707001(chips)!CONN76_H22707001_THMT1-CONN,H2A!!!F2239!GNDF3!!!!
S!GND!J1C1!F5!@baseboard_fab2_lib.baseboard_fab2(sch_1):page182_i18@mstr_conn.conn76_h22707001(chips)!CONN76_H22707001_THMT1-CONN,H2A!!!F2239!GNDF5!!!!
S!GND!J1C1!F7!@baseboard_fab2_lib.baseboard_fab2(sch_1):page182_i18@mstr_conn.conn76_h22707001(chips)!CONN76_H22707001_THMT1-CONN,H2A!!!F2239!GNDF7!!!!
S!GND!J1C1!G2!@baseboard_fab2_lib.baseboard_fab2(sch_1):page182_i18@mstr_conn.conn76_h22707001(chips)!CONN76_H22707001_THMT1-CONN,H2A!!!F2239!GNDG2!!!!
S!GND!J1C1!G4!@baseboard_fab2_lib.baseboard_fab2(sch_1):page182_i18@mstr_conn.conn76_h22707001(chips)!CONN76_H22707001_THMT1-CONN,H2A!!!F2239!GNDG4!!!!
S!GND!J1C1!G6!@baseboard_fab2_lib.baseboard_fab2(sch_1):page182_i18@mstr_conn.conn76_h22707001(chips)!CONN76_H22707001_THMT1-CONN,H2A!!!F2239!GNDG6!!!!
S!GND!J1C1!G8!@baseboard_fab2_lib.baseboard_fab2(sch_1):page182_i18@mstr_conn.conn76_h22707001(chips)!CONN76_H22707001_THMT1-CONN,H2A!!!F2239!GNDG8!!!!
S!GND!J1C1!I1!@baseboard_fab2_lib.baseboard_fab2(sch_1):page182_i18@mstr_conn.conn76_h22707001(chips)!CONN76_H22707001_THMT1-CONN,H2A!!!F2239!GNDI1!!!!
S!GND!J1C1!I3!@baseboard_fab2_lib.baseboard_fab2(sch_1):page182_i18@mstr_conn.conn76_h22707001(chips)!CONN76_H22707001_THMT1-CONN,H2A!!!F2239!GNDI3!!!!
S!GND!J1C1!I5!@baseboard_fab2_lib.baseboard_fab2(sch_1):page182_i18@mstr_conn.conn76_h22707001(chips)!CONN76_H22707001_THMT1-CONN,H2A!!!F2239!GNDI5!!!!
S!GND!J1C1!I7!@baseboard_fab2_lib.baseboard_fab2(sch_1):page182_i18@mstr_conn.conn76_h22707001(chips)!CONN76_H22707001_THMT1-CONN,H2A!!!F2239!GNDI7!!!!
S!GND!J1C1!J2!@baseboard_fab2_lib.baseboard_fab2(sch_1):page182_i18@mstr_conn.conn76_h22707001(chips)!CONN76_H22707001_THMT1-CONN,H2A!!!F2239!GNDJ2!!!!
S!GND!J1C1!J4!@baseboard_fab2_lib.baseboard_fab2(sch_1):page182_i18@mstr_conn.conn76_h22707001(chips)!CONN76_H22707001_THMT1-CONN,H2A!!!F2239!GNDJ4!!!!
S!GND!J1C1!J6!@baseboard_fab2_lib.baseboard_fab2(sch_1):page182_i18@mstr_conn.conn76_h22707001(chips)!CONN76_H22707001_THMT1-CONN,H2A!!!F2239!GNDJ6!!!!
S!GND!J1C1!J8!@baseboard_fab2_lib.baseboard_fab2(sch_1):page182_i18@mstr_conn.conn76_h22707001(chips)!CONN76_H22707001_THMT1-CONN,H2A!!!F2239!GNDJ8!!!!
S!P3E_CPU1_PE3_MP_RXN<8>!J1C1!A1!@baseboard_fab2_lib.baseboard_fab2(sch_1):page182_i18@mstr_conn.conn76_h22707001(chips)!CONN76_H22707001_THMT1-CONN,H2A!!!F2239!IOA1!!!!
S!P3E_CPU1_PE3_MP_RXP<14>!J1C1!A3!@baseboard_fab2_lib.baseboard_fab2(sch_1):page182_i18@mstr_conn.conn76_h22707001(chips)!CONN76_H22707001_THMT1-CONN,H2A!!!F2239!IOA3!!!!
S!TP_IOA5!J1C1!A5!@baseboard_fab2_lib.baseboard_fab2(sch_1):page182_i18@mstr_conn.conn76_h22707001(chips)!CONN76_H22707001_THMT1-CONN,H2A!!!F2239!IOA5!!!!
S!P3E_CPU1_PE3_MP_C_TXN<11>!J1C1!A7!@baseboard_fab2_lib.baseboard_fab2(sch_1):page182_i18@mstr_conn.conn76_h22707001(chips)!CONN76_H22707001_THMT1-CONN,H2A!!!F2239!IOA7!!!!
S!P3E_CPU1_PE3_MP_RXP<8>!J1C1!B1!@baseboard_fab2_lib.baseboard_fab2(sch_1):page182_i18@mstr_conn.conn76_h22707001(chips)!CONN76_H22707001_THMT1-CONN,H2A!!!F2239!IOB1!!!!
S!P3E_CPU1_PE3_MP_RXN<11>!J1C1!B2!@baseboard_fab2_lib.baseboard_fab2(sch_1):page182_i18@mstr_conn.conn76_h22707001(chips)!CONN76_H22707001_THMT1-CONN,H2A!!!F2239!IOB2!!!!
S!P3E_CPU1_PE3_MP_RXN<14>!J1C1!B3!@baseboard_fab2_lib.baseboard_fab2(sch_1):page182_i18@mstr_conn.conn76_h22707001(chips)!CONN76_H22707001_THMT1-CONN,H2A!!!F2239!IOB3!!!!
S!TP_FM_WAKE_N!J1C1!B4!@baseboard_fab2_lib.baseboard_fab2(sch_1):page182_i18@mstr_conn.conn76_h22707001(chips)!CONN76_H22707001_THMT1-CONN,H2A!!!F2239!IOB4!!!!
S!IRQ_BOARD_BMC_ALERT_N!J1C1!B5!@baseboard_fab2_lib.baseboard_fab2(sch_1):page182_i18@mstr_conn.conn76_h22707001(chips)!CONN76_H22707001_THMT1-CONN,H2A!!!F2239!IOB5!!!!
S!SMB_PEHPCPU1_STBY_LVC3_SDA!J1C1!B6!@baseboard_fab2_lib.baseboard_fab2(sch_1):page182_i18@mstr_conn.conn76_h22707001(chips)!CONN76_H22707001_THMT1-CONN,H2A!!!F2239!IOB6!!!!
S!P3E_CPU1_PE3_MP_C_TXP<11>!J1C1!B7!@baseboard_fab2_lib.baseboard_fab2(sch_1):page182_i18@mstr_conn.conn76_h22707001(chips)!CONN76_H22707001_THMT1-CONN,H2A!!!F2239!IOB7!!!!
S!P3E_CPU1_PE3_MP_C_TXN<8>!J1C1!B8!@baseboard_fab2_lib.baseboard_fab2(sch_1):page182_i18@mstr_conn.conn76_h22707001(chips)!CONN76_H22707001_THMT1-CONN,H2A!!!F2239!IOB8!!!!
S!P3E_CPU1_PE3_MP_RXP<11>!J1C1!C2!@baseboard_fab2_lib.baseboard_fab2(sch_1):page182_i18@mstr_conn.conn76_h22707001(chips)!CONN76_H22707001_THMT1-CONN,H2A!!!F2239!IOC2!!!!
S!FM_BB_BMC_MP_GPIO!J1C1!C4!@baseboard_fab2_lib.baseboard_fab2(sch_1):page182_i18@mstr_conn.conn76_h22707001(chips)!CONN76_H22707001_THMT1-CONN,H2A!!!F2239!IOC4!!!!
S!SMB_PEHPCPU1_STBY_LVC3_SCL!J1C1!C6!@baseboard_fab2_lib.baseboard_fab2(sch_1):page182_i18@mstr_conn.conn76_h22707001(chips)!CONN76_H22707001_THMT1-CONN,H2A!!!F2239!IOC6!!!!
S!P3E_CPU1_PE3_MP_C_TXP<8>!J1C1!C8!@baseboard_fab2_lib.baseboard_fab2(sch_1):page182_i18@mstr_conn.conn76_h22707001(chips)!CONN76_H22707001_THMT1-CONN,H2A!!!F2239!IOC8!!!!
S!P3E_CPU1_PE3_MP_RXN<9>!J1C1!D1!@baseboard_fab2_lib.baseboard_fab2(sch_1):page182_i18@mstr_conn.conn76_h22707001(chips)!CONN76_H22707001_THMT1-CONN,H2A!!!F2239!IOD1!!!!
S!P3E_CPU1_PE3_MP_RXN<15>!J1C1!D3!@baseboard_fab2_lib.baseboard_fab2(sch_1):page182_i18@mstr_conn.conn76_h22707001(chips)!CONN76_H22707001_THMT1-CONN,H2A!!!F2239!IOD3!!!!
S!SMB_LAN_STBY_LVC3_SDA!J1C1!D5!@baseboard_fab2_lib.baseboard_fab2(sch_1):page182_i18@mstr_conn.conn76_h22707001(chips)!CONN76_H22707001_THMT1-CONN,H2A!!!F2239!IOD5!!!!
S!P3E_CPU1_PE3_MP_C_TXN<12>!J1C1!D7!@baseboard_fab2_lib.baseboard_fab2(sch_1):page182_i18@mstr_conn.conn76_h22707001(chips)!CONN76_H22707001_THMT1-CONN,H2A!!!F2239!IOD7!!!!
S!P3E_CPU1_PE3_MP_RXP<9>!J1C1!E1!@baseboard_fab2_lib.baseboard_fab2(sch_1):page182_i18@mstr_conn.conn76_h22707001(chips)!CONN76_H22707001_THMT1-CONN,H2A!!!F2239!IOE1!!!!
S!P3E_CPU1_PE3_MP_RXN<12>!J1C1!E2!@baseboard_fab2_lib.baseboard_fab2(sch_1):page182_i18@mstr_conn.conn76_h22707001(chips)!CONN76_H22707001_THMT1-CONN,H2A!!!F2239!IOE2!!!!
S!P3E_CPU1_PE3_MP_RXP<15>!J1C1!E3!@baseboard_fab2_lib.baseboard_fab2(sch_1):page182_i18@mstr_conn.conn76_h22707001(chips)!CONN76_H22707001_THMT1-CONN,H2A!!!F2239!IOE3!!!!
S!TP_IOE4!J1C1!E4!@baseboard_fab2_lib.baseboard_fab2(sch_1):page182_i18@mstr_conn.conn76_h22707001(chips)!CONN76_H22707001_THMT1-CONN,H2A!!!F2239!IOE4!!!!
S!SMB_LAN_STBY_LVC3_SCL!J1C1!E5!@baseboard_fab2_lib.baseboard_fab2(sch_1):page182_i18@mstr_conn.conn76_h22707001(chips)!CONN76_H22707001_THMT1-CONN,H2A!!!F2239!IOE5!!!!
S!P3E_CPU1_PE3_MP_C_TXN<14>!J1C1!E6!@baseboard_fab2_lib.baseboard_fab2(sch_1):page182_i18@mstr_conn.conn76_h22707001(chips)!CONN76_H22707001_THMT1-CONN,H2A!!!F2239!IOE6!!!!
S!P3E_CPU1_PE3_MP_C_TXP<12>!J1C1!E7!@baseboard_fab2_lib.baseboard_fab2(sch_1):page182_i18@mstr_conn.conn76_h22707001(chips)!CONN76_H22707001_THMT1-CONN,H2A!!!F2239!IOE7!!!!
S!P3E_CPU1_PE3_MP_C_TXN<9>!J1C1!E8!@baseboard_fab2_lib.baseboard_fab2(sch_1):page182_i18@mstr_conn.conn76_h22707001(chips)!CONN76_H22707001_THMT1-CONN,H2A!!!F2239!IOE8!!!!
S!P3E_CPU1_PE3_MP_RXP<12>!J1C1!F2!@baseboard_fab2_lib.baseboard_fab2(sch_1):page182_i18@mstr_conn.conn76_h22707001(chips)!CONN76_H22707001_THMT1-CONN,H2A!!!F2239!IOF2!!!!
S!TP_IOF4!J1C1!F4!@baseboard_fab2_lib.baseboard_fab2(sch_1):page182_i18@mstr_conn.conn76_h22707001(chips)!CONN76_H22707001_THMT1-CONN,H2A!!!F2239!IOF4!!!!
S!P3E_CPU1_PE3_MP_C_TXP<14>!J1C1!F6!@baseboard_fab2_lib.baseboard_fab2(sch_1):page182_i18@mstr_conn.conn76_h22707001(chips)!CONN76_H22707001_THMT1-CONN,H2A!!!F2239!IOF6!!!!
S!P3E_CPU1_PE3_MP_C_TXP<9>!J1C1!F8!@baseboard_fab2_lib.baseboard_fab2(sch_1):page182_i18@mstr_conn.conn76_h22707001(chips)!CONN76_H22707001_THMT1-CONN,H2A!!!F2239!IOF8!!!!
S!P3E_CPU1_PE3_MP_RXP<10>!J1C1!G1!@baseboard_fab2_lib.baseboard_fab2(sch_1):page182_i18@mstr_conn.conn76_h22707001(chips)!CONN76_H22707001_THMT1-CONN,H2A!!!F2239!IOG1!!!!
S!TP_IOG3!J1C1!G3!@baseboard_fab2_lib.baseboard_fab2(sch_1):page182_i18@mstr_conn.conn76_h22707001(chips)!CONN76_H22707001_THMT1-CONN,H2A!!!F2239!IOG3!!!!
S!FM_XRC_PRESENT_N!J1C1!G5!@baseboard_fab2_lib.baseboard_fab2(sch_1):page182_i18@mstr_conn.conn76_h22707001(chips)!CONN76_H22707001_THMT1-CONN,H2A!!!F2239!IOG5!!!!
S!P3E_CPU1_PE3_MP_C_TXN<13>!J1C1!G7!@baseboard_fab2_lib.baseboard_fab2(sch_1):page182_i18@mstr_conn.conn76_h22707001(chips)!CONN76_H22707001_THMT1-CONN,H2A!!!F2239!IOG7!!!!
S!P3E_CPU1_PE3_MP_RXN<10>!J1C1!H1!@baseboard_fab2_lib.baseboard_fab2(sch_1):page182_i18@mstr_conn.conn76_h22707001(chips)!CONN76_H22707001_THMT1-CONN,H2A!!!F2239!IOH1!!!!
S!P3E_CPU1_PE3_MP_RXP<13>!J1C1!H2!@baseboard_fab2_lib.baseboard_fab2(sch_1):page182_i18@mstr_conn.conn76_h22707001(chips)!CONN76_H22707001_THMT1-CONN,H2A!!!F2239!IOH2!!!!
S!TP_IOH3!J1C1!H3!@baseboard_fab2_lib.baseboard_fab2(sch_1):page182_i18@mstr_conn.conn76_h22707001(chips)!CONN76_H22707001_THMT1-CONN,H2A!!!F2239!IOH3!!!!
S!TP_IOH4!J1C1!H4!@baseboard_fab2_lib.baseboard_fab2(sch_1):page182_i18@mstr_conn.conn76_h22707001(chips)!CONN76_H22707001_THMT1-CONN,H2A!!!F2239!IOH4!!!!
S!FM_XRC_READY_N!J1C1!H5!@baseboard_fab2_lib.baseboard_fab2(sch_1):page182_i18@mstr_conn.conn76_h22707001(chips)!CONN76_H22707001_THMT1-CONN,H2A!!!F2239!IOH5!!!!
S!P3E_CPU1_PE3_MP_C_TXN<15>!J1C1!H6!@baseboard_fab2_lib.baseboard_fab2(sch_1):page182_i18@mstr_conn.conn76_h22707001(chips)!CONN76_H22707001_THMT1-CONN,H2A!!!F2239!IOH6!!!!
S!P3E_CPU1_PE3_MP_C_TXP<13>!J1C1!H7!@baseboard_fab2_lib.baseboard_fab2(sch_1):page182_i18@mstr_conn.conn76_h22707001(chips)!CONN76_H22707001_THMT1-CONN,H2A!!!F2239!IOH7!!!!
S!P3E_CPU1_PE3_MP_C_TXP<10>!J1C1!H8!@baseboard_fab2_lib.baseboard_fab2(sch_1):page182_i18@mstr_conn.conn76_h22707001(chips)!CONN76_H22707001_THMT1-CONN,H2A!!!F2239!IOH8!!!!
S!P3E_CPU1_PE3_MP_RXN<13>!J1C1!I2!@baseboard_fab2_lib.baseboard_fab2(sch_1):page182_i18@mstr_conn.conn76_h22707001(chips)!CONN76_H22707001_THMT1-CONN,H2A!!!F2239!IOI2!!!!
S!TP_IOI4!J1C1!I4!@baseboard_fab2_lib.baseboard_fab2(sch_1):page182_i18@mstr_conn.conn76_h22707001(chips)!CONN76_H22707001_THMT1-CONN,H2A!!!F2239!IOI4!!!!
S!P3E_CPU1_PE3_MP_C_TXP<15>!J1C1!I6!@baseboard_fab2_lib.baseboard_fab2(sch_1):page182_i18@mstr_conn.conn76_h22707001(chips)!CONN76_H22707001_THMT1-CONN,H2A!!!F2239!IOI6!!!!
S!P3E_CPU1_PE3_MP_C_TXN<10>!J1C1!I8!@baseboard_fab2_lib.baseboard_fab2(sch_1):page182_i18@mstr_conn.conn76_h22707001(chips)!CONN76_H22707001_THMT1-CONN,H2A!!!F2239!IOI8!!!!
S!P3V3_STBY!R2L25!1!@baseboard_fab2_lib.baseboard_fab2(sch_1):page235_i235@mstr_discrete.res(chips)!RES_0402-100.0K,1%,1/16W,EMPTYA!!!F1113!A!!!!
S!VID_PCH_CORE_PVNN_AUX_VID_1!R2L25!2!@baseboard_fab2_lib.baseboard_fab2(sch_1):page235_i235@mstr_discrete.res(chips)!RES_0402-100.0K,1%,1/16W,EMPTYA!!!F1113!B!!!!
S!P3V3_STBY!R2L26!1!@baseboard_fab2_lib.baseboard_fab2(sch_1):page235_i236@mstr_discrete.res(chips)!RES_0402-100.0K,1%,1/16W,EMPTYA!!!F1112!A!!!!
S!VID_PCH_CORE_PVNN_AUX_VID_0!R2L26!2!@baseboard_fab2_lib.baseboard_fab2(sch_1):page235_i236@mstr_discrete.res(chips)!RES_0402-100.0K,1%,1/16W,EMPTYA!!!F1112!B!!!!
S!P3V3_STBY!R3P21!1!@baseboard_fab2_lib.baseboard_fab2(sch_1):page211_i88@mstr_discrete.res(chips)!RES_0402-100.0K,1%,1/16W,EMPTYA!!!F1120!A!!!!
S!VR_PVCCIO_CPU0_EN!R3P21!2!@baseboard_fab2_lib.baseboard_fab2(sch_1):page211_i88@mstr_discrete.res(chips)!RES_0402-100.0K,1%,1/16W,EMPTYA!!!F1120!B!!!!
S!P3V3_STBY!R6P40!1!@baseboard_fab2_lib.baseboard_fab2(sch_1):page213_i91@mstr_discrete.res(chips)!RES_0402-100.0K,1%,1/16W,EMPTYA!!!F1119!A!!!!
S!VR_PVCCIO_CPU1_EN!R6P40!2!@baseboard_fab2_lib.baseboard_fab2(sch_1):page213_i91@mstr_discrete.res(chips)!RES_0402-100.0K,1%,1/16W,EMPTYA!!!F1119!B!!!!
S!P3V3_STBY!R7F20!1!@baseboard_fab2_lib.baseboard_fab2(sch_1):page215_i315@mstr_discrete.res(chips)!RES_0402-100.0K,1%,1/16W,EMPTYA!!!F1118!A!!!!
S!VR_PVDDQ_ABC_VREN!R7F20!2!@baseboard_fab2_lib.baseboard_fab2(sch_1):page215_i315@mstr_discrete.res(chips)!RES_0402-100.0K,1%,1/16W,EMPTYA!!!F1118!B!!!!
S!P3V3_STBY!R3M5!1!@baseboard_fab2_lib.baseboard_fab2(sch_1):page218_i35@mstr_discrete.res(chips)!RES_0402-100.0K,1%,1/16W,EMPTYA!!!F1121!A!!!!
S!VR_PVDDQ_DEF_VREN!R3M5!2!@baseboard_fab2_lib.baseboard_fab2(sch_1):page218_i35@mstr_discrete.res(chips)!RES_0402-100.0K,1%,1/16W,EMPTYA!!!F1121!B!!!!
S!P3V3_STBY!R9U8!1!@baseboard_fab2_lib.baseboard_fab2(sch_1):page223_i85@mstr_discrete.res(chips)!RES_0402-100.0K,1%,1/16W,EMPTYA!!!F1114!A!!!!
S!VR_PVDDQ_GHJ_VREN!R9U8!2!@baseboard_fab2_lib.baseboard_fab2(sch_1):page223_i85@mstr_discrete.res(chips)!RES_0402-100.0K,1%,1/16W,EMPTYA!!!F1114!B!!!!
S!P3V3_STBY!R9M5!1!@baseboard_fab2_lib.baseboard_fab2(sch_1):page226_i85@mstr_discrete.res(chips)!RES_0402-100.0K,1%,1/16W,EMPTYA!!!F1115!A!!!!
S!VR_PVDDQ_KLM_VREN!R9M5!2!@baseboard_fab2_lib.baseboard_fab2(sch_1):page226_i85@mstr_discrete.res(chips)!RES_0402-100.0K,1%,1/16W,EMPTYA!!!F1115!B!!!!
S!P3V3_STBY!R8A7!1!@baseboard_fab2_lib.baseboard_fab2(sch_1):page235_i222@mstr_discrete.res(chips)!RES_0402-100.0K,1%,1/16W,EMPTYA!!!F1117!A!!!!
S!VR_PVNN_PCH_VREN!R8A7!2!@baseboard_fab2_lib.baseboard_fab2(sch_1):page235_i222@mstr_discrete.res(chips)!RES_0402-100.0K,1%,1/16W,EMPTYA!!!F1117!B!!!!
S!P3V3_STBY!R8E40!1!@baseboard_fab2_lib.baseboard_fab2(sch_1):page240_i177@mstr_discrete.res(chips)!RES_0402-100.0K,1%,1/16W,EMPTYA!!!F1116!A!!!!
S!VR_P3V3_STBY_EN!R8E40!2!@baseboard_fab2_lib.baseboard_fab2(sch_1):page240_i177@mstr_discrete.res(chips)!RES_0402-100.0K,1%,1/16W,EMPTYA!!!F1116!B!!!!
S!P3V3_STBY!R2N17!1!@baseboard_fab2_lib.baseboard_fab2(sch_1):page164_i29@mstr_discrete.res(chips)!RES_0402-2.7K,1%,1/16W,EMPTY,GA!!!F982!A!!!!
S!FM_BOARD_SKU_ID4!R2N17!2!@baseboard_fab2_lib.baseboard_fab2(sch_1):page164_i29@mstr_discrete.res(chips)!RES_0402-2.7K,1%,1/16W,EMPTY,GA!!!F982!B!!!!
S!P3V3_STBY!R1U21!1!@baseboard_fab2_lib.baseboard_fab2(sch_1):page164_i24@mstr_discrete.res(chips)!RES_0402-2.7K,1%,1/16W,EMPTY,GA!!!F984!A!!!!
S!FM_BOARD_SKU_ID3!R1U21!2!@baseboard_fab2_lib.baseboard_fab2(sch_1):page164_i24@mstr_discrete.res(chips)!RES_0402-2.7K,1%,1/16W,EMPTY,GA!!!F984!B!!!!
S!P3V3_STBY!R1U22!1!@baseboard_fab2_lib.baseboard_fab2(sch_1):page164_i27@mstr_discrete.res(chips)!RES_0402-2.7K,1%,1/16W,EMPTY,GA!!!F983!A!!!!
S!FM_BOARD_SKU_ID1!R1U22!2!@baseboard_fab2_lib.baseboard_fab2(sch_1):page164_i27@mstr_discrete.res(chips)!RES_0402-2.7K,1%,1/16W,EMPTY,GA!!!F983!B!!!!
S!P3V3_STBY!R1T5!1!@baseboard_fab2_lib.baseboard_fab2(sch_1):page164_i11@mstr_discrete.res(chips)!RES_0402-2.7K,1%,1/16W,EMPTY,GA!!!F986!A!!!!
S!FM_BOARD_REV_ID2!R1T5!2!@baseboard_fab2_lib.baseboard_fab2(sch_1):page164_i11@mstr_discrete.res(chips)!RES_0402-2.7K,1%,1/16W,EMPTY,GA!!!F986!B!!!!
S!P3V3_STBY!R1T6!1!@baseboard_fab2_lib.baseboard_fab2(sch_1):page164_i13@mstr_discrete.res(chips)!RES_0402-2.7K,1%,1/16W,EMPTY,GA!!!F985!A!!!!
S!FM_BOARD_REV_ID1!R1T6!2!@baseboard_fab2_lib.baseboard_fab2(sch_1):page164_i13@mstr_discrete.res(chips)!RES_0402-2.7K,1%,1/16W,EMPTY,GA!!!F985!B!!!!
S!XDP_PCH_CPU_TCK0!R9A2!1!@baseboard_fab2_lib.baseboard_fab2(sch_1):page111_i83@mstr_discrete.res(chips)!RES_0402-33.2,1%,1/16W,EMPTY,GA!!!F666!A!!!!
S!XDP_CPU_GTL_TCK_R2!R9A2!2!@baseboard_fab2_lib.baseboard_fab2(sch_1):page111_i83@mstr_discrete.res(chips)!RES_0402-33.2,1%,1/16W,EMPTY,GA!!!F666!B!!!!
S!XTAL_24MHZ_PI7C9X1172_IN!C9F20!1!@baseboard_fab2_lib.baseboard_fab2(sch_1):page183_i20@mstr_discrete.cap(chips)!CAP_0402LF-12.0PF,50V,5%,COG,AA!!!F3159!A!!!!
S!GND!C9F20!2!@baseboard_fab2_lib.baseboard_fab2(sch_1):page183_i20@mstr_discrete.cap(chips)!CAP_0402LF-12.0PF,50V,5%,COG,AA!!!F3159!B!!!!
S!XTAL_24MHZ_PI7C9X1172_OUT!C9F21!1!@baseboard_fab2_lib.baseboard_fab2(sch_1):page183_i21@mstr_discrete.cap(chips)!CAP_0402LF-12.0PF,50V,5%,COG,AA!!!F3158!A!!!!
S!GND!C9F21!2!@baseboard_fab2_lib.baseboard_fab2(sch_1):page183_i21@mstr_discrete.cap(chips)!CAP_0402LF-12.0PF,50V,5%,COG,AA!!!F3158!B!!!!
S!A_HSC_HIGH_EN!J1B3!1!@baseboard_fab2_lib.baseboard_fab2(sch_1):page199_i123@mstr_conn.conn3_c95678002(chips)!CONN3_C95678002_PIP-CONN,C9567A!!!F2250!IO1!!!!
S!A_HSC_OCP_SEL!J1B3!2!@baseboard_fab2_lib.baseboard_fab2(sch_1):page199_i123@mstr_conn.conn3_c95678002(chips)!CONN3_C95678002_PIP-CONN,C9567A!!!F2250!IO2!!!!
S!A_HSC_LOW_EN!J1B3!3!@baseboard_fab2_lib.baseboard_fab2(sch_1):page199_i123@mstr_conn.conn3_c95678002(chips)!CONN3_C95678002_PIP-CONN,C9567A!!!F2250!IO3!!!!
S!SMB_SMLINK0_STBY_LVC3_SDA!J9B2!1!@baseboard_fab2_lib.baseboard_fab2(sch_1):page156_i281@mstr_conn.conn3_c95678002(chips)!CONN3_C95678002_PIP-CONN,C9567A!!!F2247!IO1!!!!
S!GND!J9B2!2!@baseboard_fab2_lib.baseboard_fab2(sch_1):page156_i281@mstr_conn.conn3_c95678002(chips)!CONN3_C95678002_PIP-CONN,C9567A!!!F2247!IO2!!!!
S!SMB_SMLINK0_STBY_LVC3_SCL!J9B2!3!@baseboard_fab2_lib.baseboard_fab2(sch_1):page156_i281@mstr_conn.conn3_c95678002(chips)!CONN3_C95678002_PIP-CONN,C9567A!!!F2247!IO3!!!!
S!SMB_HOST_STBY_LVC3_SDA!J8C1!1!@baseboard_fab2_lib.baseboard_fab2(sch_1):page156_i285@mstr_conn.conn3_c95678002(chips)!CONN3_C95678002_PIP-CONN,C9567A!!!F2249!IO1!!!!
S!GND!J8C1!2!@baseboard_fab2_lib.baseboard_fab2(sch_1):page156_i285@mstr_conn.conn3_c95678002(chips)!CONN3_C95678002_PIP-CONN,C9567A!!!F2249!IO2!!!!
S!SMB_HOST_STBY_LVC3_SCL!J8C1!3!@baseboard_fab2_lib.baseboard_fab2(sch_1):page156_i285@mstr_conn.conn3_c95678002(chips)!CONN3_C95678002_PIP-CONN,C9567A!!!F2249!IO3!!!!
S!SMB_VR_STBY_LVC3_SDA!J8D4!1!@baseboard_fab2_lib.baseboard_fab2(sch_1):page201_i122@mstr_conn.conn3_c95678002(chips)!CONN3_C95678002_PIP-CONN,C9567A!!!F2248!IO1!!!!
S!GND!J8D4!2!@baseboard_fab2_lib.baseboard_fab2(sch_1):page201_i122@mstr_conn.conn3_c95678002(chips)!CONN3_C95678002_PIP-CONN,C9567A!!!F2248!IO2!!!!
S!SMB_VR_STBY_LVC3_SCL!J8D4!3!@baseboard_fab2_lib.baseboard_fab2(sch_1):page201_i122@mstr_conn.conn3_c95678002(chips)!CONN3_C95678002_PIP-CONN,C9567A!!!F2248!IO3!!!!
S!SPI_NIC_CS_N!U9E1!1!@baseboard_fab2_lib.baseboard_fab2(sch_1):page140_i1@mstr_memory.m25pe16(chips)!M25PE16_SM-IC,H77797-001!!!F2029!S_N!!!!
S!PU_NV_HOLD_N!U9E1!7!@baseboard_fab2_lib.baseboard_fab2(sch_1):page140_i1@mstr_memory.m25pe16(chips)!M25PE16_SM-IC,H77797-001!!!F2029!RESET_N!!!!
S!SPI_NIC_SCLK!U9E1!6!@baseboard_fab2_lib.baseboard_fab2(sch_1):page140_i1@mstr_memory.m25pe16(chips)!M25PE16_SM-IC,H77797-001!!!F2029!C!!!!
S!SPI_NIC_MOSI!U9E1!5!@baseboard_fab2_lib.baseboard_fab2(sch_1):page140_i1@mstr_memory.m25pe16(chips)!M25PE16_SM-IC,H77797-001!!!F2029!DQ0!!!!
S!SPI_NIC_MISO_R!U9E1!2!@baseboard_fab2_lib.baseboard_fab2(sch_1):page140_i1@mstr_memory.m25pe16(chips)!M25PE16_SM-IC,H77797-001!!!F2029!DQ1!!!!
S!P3V3_STBY!U9E1!8!@baseboard_fab2_lib.baseboard_fab2(sch_1):page140_i1@mstr_memory.m25pe16(chips)!M25PE16_SM-IC,H77797-001!!!F2029!VCC!!!!
S!GND!U9E1!4!@baseboard_fab2_lib.baseboard_fab2(sch_1):page140_i1@mstr_memory.m25pe16(chips)!M25PE16_SM-IC,H77797-001!!!F2029!VSS!!!!
S!PU_NV_WP_N!U9E1!3!@baseboard_fab2_lib.baseboard_fab2(sch_1):page140_i1@mstr_memory.m25pe16(chips)!M25PE16_SM-IC,H77797-001!!!F2029!W_N!!!!
S!IRQ_DIMM_SAVE_R_N!Q8D1!5!@baseboard_fab2_lib.baseboard_fab2(sch_1):page89_i35@mstr_discrete.npn_dual(chips)!NPN_DUAL_SSOPLF-MBT3904,XSTR,CA!1!!F1996!B(0)!!!!
S!IRQ_DIMM_SAVE_LVT3!Q8D1!3!@baseboard_fab2_lib.baseboard_fab2(sch_1):page89_i35@mstr_discrete.npn_dual(chips)!NPN_DUAL_SSOPLF-MBT3904,XSTR,CA!1!!F1996!C(0)!!!!
S!GND!Q8D1!4!@baseboard_fab2_lib.baseboard_fab2(sch_1):page89_i35@mstr_discrete.npn_dual(chips)!NPN_DUAL_SSOPLF-MBT3904,XSTR,CA!1!!F1996!E(0)!!!!
S!IRQ_DIMM_SAVE_LVT3!Q8D1!2!@baseboard_fab2_lib.baseboard_fab2(sch_1):page89_i36@mstr_discrete.npn_dual(chips)!NPN_DUAL_SSOPLF-MBT3904,XSTR,CA!1!!F1995!B(0)!!!!
S!IRQ_DIMM_SAVE_LVT3_N!Q8D1!6!@baseboard_fab2_lib.baseboard_fab2(sch_1):page89_i36@mstr_discrete.npn_dual(chips)!NPN_DUAL_SSOPLF-MBT3904,XSTR,CA!1!!F1995!C(0)!!!!
S!GND!Q8D1!1!@baseboard_fab2_lib.baseboard_fab2(sch_1):page89_i36@mstr_discrete.npn_dual(chips)!NPN_DUAL_SSOPLF-MBT3904,XSTR,CA!1!!F1995!E(0)!!!!
S!CLK_100M_CPU0_BCLK0_DN!U5D1!AU24!@baseboard_fab2_lib.baseboard_fab2(sch_1):page21_i259@chpset_lib.skx_ext_b(chips)!SKX_EXT_B_BGA1-IC,TBD!!!F101!BCLK0_DN!!!!
S!CLK_100M_CPU0_BCLK0_DP!U5D1!AW24!@baseboard_fab2_lib.baseboard_fab2(sch_1):page21_i259@chpset_lib.skx_ext_b(chips)!SKX_EXT_B_BGA1-IC,TBD!!!F101!BCLK0_DP!!!!
S!CLK_100M_CPU0_BCLK1_DN!U5D1!CR26!@baseboard_fab2_lib.baseboard_fab2(sch_1):page21_i259@chpset_lib.skx_ext_b(chips)!SKX_EXT_B_BGA1-IC,TBD!!!F101!BCLK1_DN!!!!
S!CLK_100M_CPU0_BCLK1_DP!U5D1!CP27!@baseboard_fab2_lib.baseboard_fab2(sch_1):page21_i259@chpset_lib.skx_ext_b(chips)!SKX_EXT_B_BGA1-IC,TBD!!!F101!BCLK1_DP!!!!
S!CLK_100M_CPU0_BCLK2_DN!U5D1!CT25!@baseboard_fab2_lib.baseboard_fab2(sch_1):page21_i259@chpset_lib.skx_ext_b(chips)!SKX_EXT_B_BGA1-IC,TBD!!!F101!BCLK2_DN!!!!
S!CLK_100M_CPU0_BCLK2_DP!U5D1!CU26!@baseboard_fab2_lib.baseboard_fab2(sch_1):page21_i259@chpset_lib.skx_ext_b(chips)!SKX_EXT_B_BGA1-IC,TBD!!!F101!BCLK2_DP!!!!
S!H_CPU0_BMCINIT!U5D1!BD23!@baseboard_fab2_lib.baseboard_fab2(sch_1):page21_i259@chpset_lib.skx_ext_b(chips)!SKX_EXT_B_BGA1-IC,TBD!!!F101!BMCINIT!!!!
S!H_CPU0_CATERR_G_N!U5D1!AL14!@baseboard_fab2_lib.baseboard_fab2(sch_1):page21_i259@chpset_lib.skx_ext_b(chips)!SKX_EXT_B_BGA1-IC,TBD!!!F101!CATERR_N!!!!
S!PWRGD_CPU0_DRAMPWROK_ABC_G!U5D1!AN30!@baseboard_fab2_lib.baseboard_fab2(sch_1):page21_i259@chpset_lib.skx_ext_b(chips)!SKX_EXT_B_BGA1-IC,TBD!!!F101!DDR012_DRAM_PWR_OK!!!!
S!H_CPU0_MEMABC_MEMHOT_G_N!U5D1!AH13!@baseboard_fab2_lib.baseboard_fab2(sch_1):page21_i259@chpset_lib.skx_ext_b(chips)!SKX_EXT_B_BGA1-IC,TBD!!!F101!MEM_HOT_C012_N!!!!
S!A_CPU0_ABC_RCOMP0!U5D1!Y43!@baseboard_fab2_lib.baseboard_fab2(sch_1):page21_i259@chpset_lib.skx_ext_b(chips)!SKX_EXT_B_BGA1-IC,TBD!!!F101!DDR012_RCOMP(0)!!!!
S!A_CPU0_ABC_RCOMP1!U5D1!AB43!@baseboard_fab2_lib.baseboard_fab2(sch_1):page21_i259@chpset_lib.skx_ext_b(chips)!SKX_EXT_B_BGA1-IC,TBD!!!F101!DDR012_RCOMP(1)!!!!
S!A_CPU0_ABC_RCOMP2!U5D1!AC42!@baseboard_fab2_lib.baseboard_fab2(sch_1):page21_i259@chpset_lib.skx_ext_b(chips)!SKX_EXT_B_BGA1-IC,TBD!!!F101!DDR012_RCOMP(2)!!!!
S!M_ABC_RST_N!U5D1!U64!@baseboard_fab2_lib.baseboard_fab2(sch_1):page21_i259@chpset_lib.skx_ext_b(chips)!SKX_EXT_B_BGA1-IC,TBD!!!F101!DDR012_RESET_N!!!!
S!M_A_CPU_VREF!U5D1!AJ64!@baseboard_fab2_lib.baseboard_fab2(sch_1):page21_i259@chpset_lib.skx_ext_b(chips)!SKX_EXT_B_BGA1-IC,TBD!!!F101!DDR0_CAVREF!!!!
S!M_B_CPU_VREF!U5D1!AK63!@baseboard_fab2_lib.baseboard_fab2(sch_1):page21_i259@chpset_lib.skx_ext_b(chips)!SKX_EXT_B_BGA1-IC,TBD!!!F101!DDR1_CAVREF!!!!
S!M_C_CPU_VREF!U5D1!AH63!@baseboard_fab2_lib.baseboard_fab2(sch_1):page21_i259@chpset_lib.skx_ext_b(chips)!SKX_EXT_B_BGA1-IC,TBD!!!F101!DDR2_CAVREF!!!!
S!PWRGD_CPU0_DRAMPWROK_DEF_G!U5D1!CR28!@baseboard_fab2_lib.baseboard_fab2(sch_1):page21_i259@chpset_lib.skx_ext_b(chips)!SKX_EXT_B_BGA1-IC,TBD!!!F101!DDR345_DRAM_PWR_OK!!!!
S!H_CPU0_MEMDEF_MEMHOT_G_N!U5D1!AF13!@baseboard_fab2_lib.baseboard_fab2(sch_1):page21_i259@chpset_lib.skx_ext_b(chips)!SKX_EXT_B_BGA1-IC,TBD!!!F101!MEM_HOT_C345_N!!!!
S!A_CPU0_DEF_RCOMP0!U5D1!DC48!@baseboard_fab2_lib.baseboard_fab2(sch_1):page21_i259@chpset_lib.skx_ext_b(chips)!SKX_EXT_B_BGA1-IC,TBD!!!F101!DDR345_RCOMP(0)!!!!
S!A_CPU0_DEF_RCOMP1!U5D1!DD47!@baseboard_fab2_lib.baseboard_fab2(sch_1):page21_i259@chpset_lib.skx_ext_b(chips)!SKX_EXT_B_BGA1-IC,TBD!!!F101!DDR345_RCOMP(1)!!!!
S!A_CPU0_DEF_RCOMP2!U5D1!DD49!@baseboard_fab2_lib.baseboard_fab2(sch_1):page21_i259@chpset_lib.skx_ext_b(chips)!SKX_EXT_B_BGA1-IC,TBD!!!F101!DDR345_RCOMP(2)!!!!
S!M_DEF_RST_N!U5D1!DV63!@baseboard_fab2_lib.baseboard_fab2(sch_1):page21_i259@chpset_lib.skx_ext_b(chips)!SKX_EXT_B_BGA1-IC,TBD!!!F101!DDR345_RESET_N!!!!
S!M_D_CPU_VREF!U5D1!CP61!@baseboard_fab2_lib.baseboard_fab2(sch_1):page21_i259@chpset_lib.skx_ext_b(chips)!SKX_EXT_B_BGA1-IC,TBD!!!F101!DDR3_CAVREF!!!!
S!M_E_CPU_VREF!U5D1!CT61!@baseboard_fab2_lib.baseboard_fab2(sch_1):page21_i259@chpset_lib.skx_ext_b(chips)!SKX_EXT_B_BGA1-IC,TBD!!!F101!DDR4_CAVREF!!!!
S!M_F_CPU_VREF!U5D1!CV61!@baseboard_fab2_lib.baseboard_fab2(sch_1):page21_i259@chpset_lib.skx_ext_b(chips)!SKX_EXT_B_BGA1-IC,TBD!!!F101!DDR5_CAVREF!!!!
S!SMB_DDR_ABC_SCL_G_R!U5D1!AJ18!@baseboard_fab2_lib.baseboard_fab2(sch_1):page21_i259@chpset_lib.skx_ext_b(chips)!SKX_EXT_B_BGA1-IC,TBD!!!F101!DDR012_SPDSCL!!!!
S!SMB_DDR_DEF_SCL_G_R!U5D1!AE18!@baseboard_fab2_lib.baseboard_fab2(sch_1):page21_i259@chpset_lib.skx_ext_b(chips)!SKX_EXT_B_BGA1-IC,TBD!!!F101!DDR345_SPDSCL!!!!
S!SMB_DDR_ABC_SDA_G_R!U5D1!AF17!@baseboard_fab2_lib.baseboard_fab2(sch_1):page21_i259@chpset_lib.skx_ext_b(chips)!SKX_EXT_B_BGA1-IC,TBD!!!F101!DDR012_SPDSDA!!!!
S!SMB_DDR_DEF_SDA_G_R!U5D1!AD17!@baseboard_fab2_lib.baseboard_fab2(sch_1):page21_i259@chpset_lib.skx_ext_b(chips)!SKX_EXT_B_BGA1-IC,TBD!!!F101!DDR345_SPDSDA!!!!
S!PU_CPU0_EAR_N!U5D1!AJ14!@baseboard_fab2_lib.baseboard_fab2(sch_1):page21_i259@chpset_lib.skx_ext_b(chips)!SKX_EXT_B_BGA1-IC,TBD!!!F101!EAR_N!!!!
S!H_CPU0_ERR0_G_N!U5D1!AJ12!@baseboard_fab2_lib.baseboard_fab2(sch_1):page21_i259@chpset_lib.skx_ext_b(chips)!SKX_EXT_B_BGA1-IC,TBD!!!F101!ERROR_N(0)!!!!
S!H_CPU0_ERR1_G_N!U5D1!AK11!@baseboard_fab2_lib.baseboard_fab2(sch_1):page21_i259@chpset_lib.skx_ext_b(chips)!SKX_EXT_B_BGA1-IC,TBD!!!F101!ERROR_N(1)!!!!
S!H_CPU0_ERR2_G_N!U5D1!AL12!@baseboard_fab2_lib.baseboard_fab2(sch_1):page21_i259@chpset_lib.skx_ext_b(chips)!SKX_EXT_B_BGA1-IC,TBD!!!F101!ERROR_N(2)!!!!
S!A_CPU0_UPI01_RBIAS!U5D1!AT29!@baseboard_fab2_lib.baseboard_fab2(sch_1):page21_i259@chpset_lib.skx_ext_b(chips)!SKX_EXT_B_BGA1-IC,TBD!!!F101!UPI01_RBIAS(0)!!!!
S!A_CPU0_UPI01_RBIAS!U5D1!AP29!@baseboard_fab2_lib.baseboard_fab2(sch_1):page21_i259@chpset_lib.skx_ext_b(chips)!SKX_EXT_B_BGA1-IC,TBD!!!F101!UPI01_RBIAS(1)!!!!
S!A_CPU0_UPI2_RBIAS!U5D1!CL28!@baseboard_fab2_lib.baseboard_fab2(sch_1):page21_i259@chpset_lib.skx_ext_b(chips)!SKX_EXT_B_BGA1-IC,TBD!!!F101!UPI2_RBIAS(0)!!!!
S!A_CPU0_UPI2_RBIAS!U5D1!CK29!@baseboard_fab2_lib.baseboard_fab2(sch_1):page21_i259@chpset_lib.skx_ext_b(chips)!SKX_EXT_B_BGA1-IC,TBD!!!F101!UPI2_RBIAS(1)!!!!
S!PU_CPU0_LEGACY_SKT!U5D1!AE20!@baseboard_fab2_lib.baseboard_fab2(sch_1):page21_i259@chpset_lib.skx_ext_b(chips)!SKX_EXT_B_BGA1-IC,TBD!!!F101!LEGACY_SKT!!!!
S!XDP_CPU_MBP0_N!U5D1!AJ10!@baseboard_fab2_lib.baseboard_fab2(sch_1):page21_i259@chpset_lib.skx_ext_b(chips)!SKX_EXT_B_BGA1-IC,TBD!!!F101!BPM_N(0)!!!!
S!XDP_CPU_MBP1_N!U5D1!AH11!@baseboard_fab2_lib.baseboard_fab2(sch_1):page21_i259@chpset_lib.skx_ext_b(chips)!SKX_EXT_B_BGA1-IC,TBD!!!F101!BPM_N(1)!!!!
S!TP_XDP_CPU0_OBSDATA_A0_MBP2_N!U5D1!AG10!@baseboard_fab2_lib.baseboard_fab2(sch_1):page21_i259@chpset_lib.skx_ext_b(chips)!SKX_EXT_B_BGA1-IC,TBD!!!F101!BPM_N(2)!!!!
S!TP_XDP_CPU0_OBSDATA_A1_MBP3_N!U5D1!AF11!@baseboard_fab2_lib.baseboard_fab2(sch_1):page21_i259@chpset_lib.skx_ext_b(chips)!SKX_EXT_B_BGA1-IC,TBD!!!F101!BPM_N(3)!!!!
S!TP_XDP_CPU0_OBSDATA_A2_MBP4_N!U5D1!AA12!@baseboard_fab2_lib.baseboard_fab2(sch_1):page21_i259@chpset_lib.skx_ext_b(chips)!SKX_EXT_B_BGA1-IC,TBD!!!F101!BPM_N(4)!!!!
S!TP_XDP_CPU0_OBSDATA_A3_MBP5_N!U5D1!Y11!@baseboard_fab2_lib.baseboard_fab2(sch_1):page21_i259@chpset_lib.skx_ext_b(chips)!SKX_EXT_B_BGA1-IC,TBD!!!F101!BPM_N(5)!!!!
S!XDP_CPU_OBSFN_B0_MBP6_N!U5D1!AE12!@baseboard_fab2_lib.baseboard_fab2(sch_1):page21_i259@chpset_lib.skx_ext_b(chips)!SKX_EXT_B_BGA1-IC,TBD!!!F101!BPM_N(6)!!!!
S!XDP_CPU_OBSFN_B1_MBP7_N!U5D1!AC12!@baseboard_fab2_lib.baseboard_fab2(sch_1):page21_i259@chpset_lib.skx_ext_b(chips)!SKX_EXT_B_BGA1-IC,TBD!!!F101!BPM_N(7)!!!!
S!PD_CPU0_BIST_ENABLE!U5D1!BA20!@baseboard_fab2_lib.baseboard_fab2(sch_1):page21_i259@chpset_lib.skx_ext_b(chips)!SKX_EXT_B_BGA1-IC,TBD!!!F101!BIST_ENABLE!!!!
S!PU_CPU0_FRMAGENT!U5D1!AV17!@baseboard_fab2_lib.baseboard_fab2(sch_1):page21_i259@chpset_lib.skx_ext_b(chips)!SKX_EXT_B_BGA1-IC,TBD!!!F101!FRMAGENT!!!!
S!PU_CPU0_SAFE_MODE_BOOT!U5D1!AR18!@baseboard_fab2_lib.baseboard_fab2(sch_1):page21_i259@chpset_lib.skx_ext_b(chips)!SKX_EXT_B_BGA1-IC,TBD!!!F101!SAFE_MODE_BOOT!!!!
S!PU_CPU0_SOCKET_ID_0!U5D1!AU22!@baseboard_fab2_lib.baseboard_fab2(sch_1):page21_i259@chpset_lib.skx_ext_b(chips)!SKX_EXT_B_BGA1-IC,TBD!!!F101!SOCKET_ID(0)!!!!
S!PU_CPU0_SOCKET_ID_1!U5D1!AU16!@baseboard_fab2_lib.baseboard_fab2(sch_1):page21_i259@chpset_lib.skx_ext_b(chips)!SKX_EXT_B_BGA1-IC,TBD!!!F101!SOCKET_ID(1)!!!!
S!PU_CPU0_TXT_AGENT!U5D1!AW18!@baseboard_fab2_lib.baseboard_fab2(sch_1):page21_i259@chpset_lib.skx_ext_b(chips)!SKX_EXT_B_BGA1-IC,TBD!!!F101!TXT_AGENT!!!!
S!PD_CPU0_TXT_PLTEN!U5D1!AV15!@baseboard_fab2_lib.baseboard_fab2(sch_1):page21_i259@chpset_lib.skx_ext_b(chips)!SKX_EXT_B_BGA1-IC,TBD!!!F101!TXT_PLTEN!!!!
S!A_CPU0_MCP01_RBIAS!U5D1!CT31!@baseboard_fab2_lib.baseboard_fab2(sch_1):page21_i259@chpset_lib.skx_ext_b(chips)!SKX_EXT_B_BGA1-IC,TBD!!!F101!MCP01_RBIAS(1)!!!!
S!A_CPU0_PE3_RBIAS!U5D1!CR30!@baseboard_fab2_lib.baseboard_fab2(sch_1):page21_i259@chpset_lib.skx_ext_b(chips)!SKX_EXT_B_BGA1-IC,TBD!!!F101!PE3_RBIAS(1)!!!!
S!H_CPU0_MSMI_G_N!U5D1!AN20!@baseboard_fab2_lib.baseboard_fab2(sch_1):page21_i259@chpset_lib.skx_ext_b(chips)!SKX_EXT_B_BGA1-IC,TBD!!!F101!MSMI_N!!!!
S!TP_NMI_CPU0!U5D1!AP11!@baseboard_fab2_lib.baseboard_fab2(sch_1):page21_i259@chpset_lib.skx_ext_b(chips)!SKX_EXT_B_BGA1-IC,TBD!!!F101!NMI!!!!
S!TP_CPU0_RSVD_TEST_4!U5D1!AN12!@baseboard_fab2_lib.baseboard_fab2(sch_1):page22_i204@chpset_lib.skx_ext_b(chips)!SKX_EXT_B_BGA1-IC,TBD!!!F100!TEST_4!!!!
S!TP_CPU0_RSVD_TEST_3!U5D1!AM13!@baseboard_fab2_lib.baseboard_fab2(sch_1):page22_i204@chpset_lib.skx_ext_b(chips)!SKX_EXT_B_BGA1-IC,TBD!!!F100!TEST_3!!!!
S!TP_CPU0_RSVD_TEST_5!U5D1!AN14!@baseboard_fab2_lib.baseboard_fab2(sch_1):page22_i204@chpset_lib.skx_ext_b(chips)!SKX_EXT_B_BGA1-IC,TBD!!!F100!TEST_5!!!!
S!A_CPU0_PE012_RBIAS!U5D1!CN30!@baseboard_fab2_lib.baseboard_fab2(sch_1):page21_i259@chpset_lib.skx_ext_b(chips)!SKX_EXT_B_BGA1-IC,TBD!!!F101!PE012_RBIAS(0)!!!!
S!A_CPU0_PE012_RBIAS!U5D1!CL30!@baseboard_fab2_lib.baseboard_fab2(sch_1):page21_i259@chpset_lib.skx_ext_b(chips)!SKX_EXT_B_BGA1-IC,TBD!!!F101!PE012_RBIAS(1)!!!!
S!A_CPU0_PE3_RBIAS!U5D1!CP29!@baseboard_fab2_lib.baseboard_fab2(sch_1):page21_i259@chpset_lib.skx_ext_b(chips)!SKX_EXT_B_BGA1-IC,TBD!!!F101!PE3_RBIAS(0)!!!!
S!PD_CPU0_MCP01_DMON!U5D1!CN28!@baseboard_fab2_lib.baseboard_fab2(sch_1):page39_i127@chpset_lib.skx_ext_b(chips)!SKX_EXT_B_BGA1-IC,TBD!!!F80!RSVD(75)!!!!
S!PECI_CPU_G!U5D1!AU12!@baseboard_fab2_lib.baseboard_fab2(sch_1):page21_i259@chpset_lib.skx_ext_b(chips)!SKX_EXT_B_BGA1-IC,TBD!!!F101!PECI!!!!
S!TP_CPU0_PE_HP_SCL!U5D1!AM19!@baseboard_fab2_lib.baseboard_fab2(sch_1):page21_i259@chpset_lib.skx_ext_b(chips)!SKX_EXT_B_BGA1-IC,TBD!!!F101!PE_HP_SCL!!!!
S!TP_CPU0_PE_HP_SDA!U5D1!AL18!@baseboard_fab2_lib.baseboard_fab2(sch_1):page21_i259@chpset_lib.skx_ext_b(chips)!SKX_EXT_B_BGA1-IC,TBD!!!F101!PE_HP_SDA!!!!
S!PD_PIROM_CPU0_ADDR0!U5D1!CU58!@baseboard_fab2_lib.baseboard_fab2(sch_1):page21_i259@chpset_lib.skx_ext_b(chips)!SKX_EXT_B_BGA1-IC,TBD!!!F101!PIROM_ADDR(0)!!!!
S!PD_PIROM_CPU0_ADDR1!U5D1!CV57!@baseboard_fab2_lib.baseboard_fab2(sch_1):page21_i259@chpset_lib.skx_ext_b(chips)!SKX_EXT_B_BGA1-IC,TBD!!!F101!PIROM_ADDR(1)!!!!
S!PD_PIROM_CPU0_ADDR2!U5D1!CW56!@baseboard_fab2_lib.baseboard_fab2(sch_1):page21_i259@chpset_lib.skx_ext_b(chips)!SKX_EXT_B_BGA1-IC,TBD!!!F101!PIROM_ADDR(2)!!!!
S!FM_CPU0_PKGID0!U5D1!DC72!@baseboard_fab2_lib.baseboard_fab2(sch_1):page21_i259@chpset_lib.skx_ext_b(chips)!SKX_EXT_B_BGA1-IC,TBD!!!F101!PKGID(0)!!!!
S!FM_CPU0_PKGID1!U5D1!CW72!@baseboard_fab2_lib.baseboard_fab2(sch_1):page21_i259@chpset_lib.skx_ext_b(chips)!SKX_EXT_B_BGA1-IC,TBD!!!F101!PKGID(1)!!!!
S!FM_CPU0_PKGID2!U5D1!DA72!@baseboard_fab2_lib.baseboard_fab2(sch_1):page21_i259@chpset_lib.skx_ext_b(chips)!SKX_EXT_B_BGA1-IC,TBD!!!F101!PKGID(2)!!!!
S!H_PM_SYNC_GTL_R1!U5D1!AR14!@baseboard_fab2_lib.baseboard_fab2(sch_1):page21_i259@chpset_lib.skx_ext_b(chips)!SKX_EXT_B_BGA1-IC,TBD!!!F101!PMSYNC!!!!
S!H_PMSYNC_CLK_24M_CPU0!U5D1!AT19!@baseboard_fab2_lib.baseboard_fab2(sch_1):page21_i259@chpset_lib.skx_ext_b(chips)!SKX_EXT_B_BGA1-IC,TBD!!!F101!PMSYNC_CLK!!!!
S!H_CPU0_FAST_WAKE_N!U5D1!AF15!@baseboard_fab2_lib.baseboard_fab2(sch_1):page21_i259@chpset_lib.skx_ext_b(chips)!SKX_EXT_B_BGA1-IC,TBD!!!F101!PM_FAST_WAKE_N!!!!
S!XDP_CPU_PRDY_N!U5D1!AG16!@baseboard_fab2_lib.baseboard_fab2(sch_1):page21_i259@chpset_lib.skx_ext_b(chips)!SKX_EXT_B_BGA1-IC,TBD!!!F101!PRDY_N!!!!
S!XDP_CPU_PREQ_N!U5D1!AR12!@baseboard_fab2_lib.baseboard_fab2(sch_1):page21_i259@chpset_lib.skx_ext_b(chips)!SKX_EXT_B_BGA1-IC,TBD!!!F101!PREQ_N!!!!
S!TP_CPU0_PROCDIS_G_N!U5D1!AB17!@baseboard_fab2_lib.baseboard_fab2(sch_1):page21_i259@chpset_lib.skx_ext_b(chips)!SKX_EXT_B_BGA1-IC,TBD!!!F101!PROCDIS_N!!!!
S!H_CPU0_PROCHOT_G_N!U5D1!AC16!@baseboard_fab2_lib.baseboard_fab2(sch_1):page21_i259@chpset_lib.skx_ext_b(chips)!SKX_EXT_B_BGA1-IC,TBD!!!F101!PROCHOT_N!!!!
S!FM_CPU0_PROC_ID0!U5D1!CY71!@baseboard_fab2_lib.baseboard_fab2(sch_1):page21_i259@chpset_lib.skx_ext_b(chips)!SKX_EXT_B_BGA1-IC,TBD!!!F101!PROC_ID(0)!!!!
S!FM_CPU0_PROC_ID1!U5D1!DB71!@baseboard_fab2_lib.baseboard_fab2(sch_1):page21_i259@chpset_lib.skx_ext_b(chips)!SKX_EXT_B_BGA1-IC,TBD!!!F101!PROC_ID(1)!!!!
S!PWRGD_CPU0_G!U5D1!BC24!@baseboard_fab2_lib.baseboard_fab2(sch_1):page21_i259@chpset_lib.skx_ext_b(chips)!SKX_EXT_B_BGA1-IC,TBD!!!F101!PWRGOOD!!!!
S!RST_CPU0_G_N!U5D1!AP21!@baseboard_fab2_lib.baseboard_fab2(sch_1):page21_i259@chpset_lib.skx_ext_b(chips)!SKX_EXT_B_BGA1-IC,TBD!!!F101!RESET_N!!!!
S!FM_CPU0_SKTOCC_LVT3_N!U5D1!AB13!@baseboard_fab2_lib.baseboard_fab2(sch_1):page21_i259@chpset_lib.skx_ext_b(chips)!SKX_EXT_B_BGA1-IC,TBD!!!F101!SKTOCC_N!!!!
S!SMB_PIROM_CPU0_SCL!U5D1!CT59!@baseboard_fab2_lib.baseboard_fab2(sch_1):page21_i259@chpset_lib.skx_ext_b(chips)!SKX_EXT_B_BGA1-IC,TBD!!!F101!SMBCLK!!!!
S!SMB_PIROM_CPU0_SDA!U5D1!CW58!@baseboard_fab2_lib.baseboard_fab2(sch_1):page21_i259@chpset_lib.skx_ext_b(chips)!SKX_EXT_B_BGA1-IC,TBD!!!F101!SMBDAT!!!!
S!FM_CPU0_SM_WP!U5D1!CV59!@baseboard_fab2_lib.baseboard_fab2(sch_1):page21_i259@chpset_lib.skx_ext_b(chips)!SKX_EXT_B_BGA1-IC,TBD!!!F101!SM_WP!!!!
S!TP_CPU0_SOCKET_ID_2!U5D1!AU20!@baseboard_fab2_lib.baseboard_fab2(sch_1):page21_i259@chpset_lib.skx_ext_b(chips)!SKX_EXT_B_BGA1-IC,TBD!!!F101!SOCKET_ID(2)!!!!
S!SVID_ALERT0_CPU0_N!U5D1!DE44!@baseboard_fab2_lib.baseboard_fab2(sch_1):page21_i259@chpset_lib.skx_ext_b(chips)!SKX_EXT_B_BGA1-IC,TBD!!!F101!SVIDALERT_N(0)!!!!
S!SVID_ALERT1_CPU0_N!U5D1!DL44!@baseboard_fab2_lib.baseboard_fab2(sch_1):page21_i259@chpset_lib.skx_ext_b(chips)!SKX_EXT_B_BGA1-IC,TBD!!!F101!SVIDALERT_N(1)!!!!
S!SVID_CLK0_CPU0!U5D1!DC44!@baseboard_fab2_lib.baseboard_fab2(sch_1):page21_i259@chpset_lib.skx_ext_b(chips)!SKX_EXT_B_BGA1-IC,TBD!!!F101!SVIDCLK(0)!!!!
S!SVID_CLK1_CPU0!U5D1!DG44!@baseboard_fab2_lib.baseboard_fab2(sch_1):page21_i259@chpset_lib.skx_ext_b(chips)!SKX_EXT_B_BGA1-IC,TBD!!!F101!SVIDCLK(1)!!!!
S!SVID_DIO0_CPU0!U5D1!DB45!@baseboard_fab2_lib.baseboard_fab2(sch_1):page21_i259@chpset_lib.skx_ext_b(chips)!SKX_EXT_B_BGA1-IC,TBD!!!F101!SVIDDATA(0)!!!!
S!SVID_DIO1_CPU0!U5D1!DJ44!@baseboard_fab2_lib.baseboard_fab2(sch_1):page21_i259@chpset_lib.skx_ext_b(chips)!SKX_EXT_B_BGA1-IC,TBD!!!F101!SVIDDATA(1)!!!!
S!XDP_CPU_TCK0!U5D1!AA14!@baseboard_fab2_lib.baseboard_fab2(sch_1):page21_i259@chpset_lib.skx_ext_b(chips)!SKX_EXT_B_BGA1-IC,TBD!!!F101!TCK!!!!
S!XDP_CPU_TDI!U5D1!AC14!@baseboard_fab2_lib.baseboard_fab2(sch_1):page21_i259@chpset_lib.skx_ext_b(chips)!SKX_EXT_B_BGA1-IC,TBD!!!F101!TDI!!!!
S!XDP_CPU0_TDO!U5D1!AE14!@baseboard_fab2_lib.baseboard_fab2(sch_1):page21_i259@chpset_lib.skx_ext_b(chips)!SKX_EXT_B_BGA1-IC,TBD!!!F101!TDO!!!!
S!H_CPU0_THERMTRIP_G_N!U5D1!AB15!@baseboard_fab2_lib.baseboard_fab2(sch_1):page21_i259@chpset_lib.skx_ext_b(chips)!SKX_EXT_B_BGA1-IC,TBD!!!F101!THERMTRIP_N!!!!
S!XDP_CPU_TMS!U5D1!W14!@baseboard_fab2_lib.baseboard_fab2(sch_1):page21_i259@chpset_lib.skx_ext_b(chips)!SKX_EXT_B_BGA1-IC,TBD!!!F101!TMS!!!!
S!XDP_CPU_TRST_N!U5D1!Y13!@baseboard_fab2_lib.baseboard_fab2(sch_1):page21_i259@chpset_lib.skx_ext_b(chips)!SKX_EXT_B_BGA1-IC,TBD!!!F101!TRST_N!!!!
S!PU_CPU0_TSC_SYNC!U5D1!AM11!@baseboard_fab2_lib.baseboard_fab2(sch_1):page21_i259@chpset_lib.skx_ext_b(chips)!SKX_EXT_B_BGA1-IC,TBD!!!F101!TSC_SYNC!!!!
S!TP_CPU0_RSVD_114!U5D1!CB25!@baseboard_fab2_lib.baseboard_fab2(sch_1):page36_i15@chpset_lib.skx_ext_b(chips)!SKX_EXT_B_BGA1-IC,TBD!!!F86!RSVD(114)!!!!
S!TP_CPU0_RSVD_124!U5D1!BV23!@baseboard_fab2_lib.baseboard_fab2(sch_1):page36_i15@chpset_lib.skx_ext_b(chips)!SKX_EXT_B_BGA1-IC,TBD!!!F86!RSVD(124)!!!!
S!TP_CPU0_RSVD_108!U5D1!CD25!@baseboard_fab2_lib.baseboard_fab2(sch_1):page36_i15@chpset_lib.skx_ext_b(chips)!SKX_EXT_B_BGA1-IC,TBD!!!F86!RSVD(108)!!!!
S!TP_CPU0_RSVD_121!U5D1!BW22!@baseboard_fab2_lib.baseboard_fab2(sch_1):page36_i15@chpset_lib.skx_ext_b(chips)!SKX_EXT_B_BGA1-IC,TBD!!!F86!RSVD(121)!!!!
S!TP_CPU0_RSVD_117!U5D1!CA24!@baseboard_fab2_lib.baseboard_fab2(sch_1):page36_i15@chpset_lib.skx_ext_b(chips)!SKX_EXT_B_BGA1-IC,TBD!!!F86!RSVD(117)!!!!
S!TP_CPU0_RSVD_119!U5D1!BY25!@baseboard_fab2_lib.baseboard_fab2(sch_1):page36_i15@chpset_lib.skx_ext_b(chips)!SKX_EXT_B_BGA1-IC,TBD!!!F86!RSVD(119)!!!!
S!TP_CPU0_RSVD_91!U5D1!CH25!@baseboard_fab2_lib.baseboard_fab2(sch_1):page36_i16@chpset_lib.skx_ext_b(chips)!SKX_EXT_B_BGA1-IC,TBD!!!F85!RSVD(91)!!!!
S!TP_CPU0_RSVD_97!U5D1!CG24!@baseboard_fab2_lib.baseboard_fab2(sch_1):page36_i15@chpset_lib.skx_ext_b(chips)!SKX_EXT_B_BGA1-IC,TBD!!!F86!RSVD(97)!!!!
S!TP_CPU0_RSVD_281!U5D1!E24!@baseboard_fab2_lib.baseboard_fab2(sch_1):page22_i204@chpset_lib.skx_ext_b(chips)!SKX_EXT_B_BGA1-IC,TBD!!!F100!RSVD(281)!!!!
S!TP_CPU0_RSVD_278!U5D1!F23!@baseboard_fab2_lib.baseboard_fab2(sch_1):page22_i204@chpset_lib.skx_ext_b(chips)!SKX_EXT_B_BGA1-IC,TBD!!!F100!RSVD(278)!!!!
S!PD_CPU0_RSVD_TEST_2!U5D1!AG46!@baseboard_fab2_lib.baseboard_fab2(sch_1):page22_i204@chpset_lib.skx_ext_b(chips)!SKX_EXT_B_BGA1-IC,TBD!!!F100!TEST_2!!!!
S!PD_CPU0_RSVD_TEST_1!U5D1!AF45!@baseboard_fab2_lib.baseboard_fab2(sch_1):page22_i204@chpset_lib.skx_ext_b(chips)!SKX_EXT_B_BGA1-IC,TBD!!!F100!TEST_1!!!!
S!PD_CPU0_TEST13!U5D1!DB51!@baseboard_fab2_lib.baseboard_fab2(sch_1):page21_i259@chpset_lib.skx_ext_b(chips)!SKX_EXT_B_BGA1-IC,TBD!!!F101!TEST_13!!!!
S!PD_CPU0_TEST14!U5D1!DC50!@baseboard_fab2_lib.baseboard_fab2(sch_1):page21_i259@chpset_lib.skx_ext_b(chips)!SKX_EXT_B_BGA1-IC,TBD!!!F101!TEST_14!!!!
S!PD_CPU0_DMIMODE_OVERRIDE!U5D1!AW12!@baseboard_fab2_lib.baseboard_fab2(sch_1):page22_i204@chpset_lib.skx_ext_b(chips)!SKX_EXT_B_BGA1-IC,TBD!!!F100!DMIMODE_OVERRIDE!!!!
S!TP_CPU0_TEST_6!U5D1!AR16!@baseboard_fab2_lib.baseboard_fab2(sch_1):page36_i16@chpset_lib.skx_ext_b(chips)!SKX_EXT_B_BGA1-IC,TBD!!!F85!TEST_6!!!!
S!TP_CPU0_RSVD_233!U5D1!AH15!@baseboard_fab2_lib.baseboard_fab2(sch_1):page22_i204@chpset_lib.skx_ext_b(chips)!SKX_EXT_B_BGA1-IC,TBD!!!F100!RSVD(233)!!!!
S!H_CPU0_FIVR_FAULT_G!U5D1!AU14!@baseboard_fab2_lib.baseboard_fab2(sch_1):page22_i204@chpset_lib.skx_ext_b(chips)!SKX_EXT_B_BGA1-IC,TBD!!!F100!FIVR_FAULT!!!!
S!TP_CPU0_RSVD_232!U5D1!AH19!@baseboard_fab2_lib.baseboard_fab2(sch_1):page22_i204@chpset_lib.skx_ext_b(chips)!SKX_EXT_B_BGA1-IC,TBD!!!F100!RSVD(232)!!!!
S!TP_CPU0_RSVD_246!U5D1!AF19!@baseboard_fab2_lib.baseboard_fab2(sch_1):page22_i204@chpset_lib.skx_ext_b(chips)!SKX_EXT_B_BGA1-IC,TBD!!!F100!RSVD(246)!!!!
S!TP_CPU0_RSVD_189!U5D1!AT13!@baseboard_fab2_lib.baseboard_fab2(sch_1):page29_i61@chpset_lib.skx_ext_b(chips)!SKX_EXT_B_BGA1-IC,TBD!!!F93!RSVD(189)!!!!
S!TP_CPU0_RSVD_208!U5D1!AM23!@baseboard_fab2_lib.baseboard_fab2(sch_1):page22_i204@chpset_lib.skx_ext_b(chips)!SKX_EXT_B_BGA1-IC,TBD!!!F100!RSVD(208)!!!!
S!TP_CPU0_RSVD_276!U5D1!F83!@baseboard_fab2_lib.baseboard_fab2(sch_1):page22_i204@chpset_lib.skx_ext_b(chips)!SKX_EXT_B_BGA1-IC,TBD!!!F100!RSVD(276)!!!!
S!TP_CPU0_RSVD_273!U5D1!G84!@baseboard_fab2_lib.baseboard_fab2(sch_1):page22_i204@chpset_lib.skx_ext_b(chips)!SKX_EXT_B_BGA1-IC,TBD!!!F100!RSVD(273)!!!!
S!TP_CPU0_RSVD_16!U5D1!EB85!@baseboard_fab2_lib.baseboard_fab2(sch_1):page39_i127@chpset_lib.skx_ext_b(chips)!SKX_EXT_B_BGA1-IC,TBD!!!F80!RSVD(16)!!!!
S!TP_CPU0_RSVD_9!U5D1!ED83!@baseboard_fab2_lib.baseboard_fab2(sch_1):page39_i127@chpset_lib.skx_ext_b(chips)!SKX_EXT_B_BGA1-IC,TBD!!!F80!RSVD(9)!!!!
S!TP_CPU0_RSVD_12!U5D1!EC84!@baseboard_fab2_lib.baseboard_fab2(sch_1):page39_i127@chpset_lib.skx_ext_b(chips)!SKX_EXT_B_BGA1-IC,TBD!!!F80!RSVD(12)!!!!
S!TP_CPU0_RSVD_214!U5D1!AL22!@baseboard_fab2_lib.baseboard_fab2(sch_1):page22_i204@chpset_lib.skx_ext_b(chips)!SKX_EXT_B_BGA1-IC,TBD!!!F100!RSVD(214)!!!!
S!PD_CPU0_KSFC_DIS!U5D1!AW14!@baseboard_fab2_lib.baseboard_fab2(sch_1):page21_i259@chpset_lib.skx_ext_b(chips)!SKX_EXT_B_BGA1-IC,TBD!!!F101!TEST_15!!!!
S!TP_CPU0_RSVD_291!U5D1!C6!@baseboard_fab2_lib.baseboard_fab2(sch_1):page22_i204@chpset_lib.skx_ext_b(chips)!SKX_EXT_B_BGA1-IC,TBD!!!F100!RSVD(291)!!!!
S!TP_CPU0_RSVD_279!U5D1!F3!@baseboard_fab2_lib.baseboard_fab2(sch_1):page22_i204@chpset_lib.skx_ext_b(chips)!SKX_EXT_B_BGA1-IC,TBD!!!F100!RSVD(279)!!!!
S!TP_CPU0_RSVD_300!U5D1!A24!@baseboard_fab2_lib.baseboard_fab2(sch_1):page22_i204@chpset_lib.skx_ext_b(chips)!SKX_EXT_B_BGA1-IC,TBD!!!F100!RSVD(300)!!!!
S!TP_CPU0_RSVD_289!U5D1!C24!@baseboard_fab2_lib.baseboard_fab2(sch_1):page22_i204@chpset_lib.skx_ext_b(chips)!SKX_EXT_B_BGA1-IC,TBD!!!F100!RSVD(289)!!!!
S!TP_CPU0_RSVD_272!U5D1!H1!@baseboard_fab2_lib.baseboard_fab2(sch_1):page22_i204@chpset_lib.skx_ext_b(chips)!SKX_EXT_B_BGA1-IC,TBD!!!F100!RSVD(272)!!!!
S!TP_CPU0_RSVD_286!U5D1!D17!@baseboard_fab2_lib.baseboard_fab2(sch_1):page22_i204@chpset_lib.skx_ext_b(chips)!SKX_EXT_B_BGA1-IC,TBD!!!F100!RSVD(286)!!!!
S!TP_CPU0_RSVD_290!U5D1!C18!@baseboard_fab2_lib.baseboard_fab2(sch_1):page22_i204@chpset_lib.skx_ext_b(chips)!SKX_EXT_B_BGA1-IC,TBD!!!F100!RSVD(290)!!!!
S!TP_CPU0_RSVD_99!U5D1!CG10!@baseboard_fab2_lib.baseboard_fab2(sch_1):page36_i15@chpset_lib.skx_ext_b(chips)!SKX_EXT_B_BGA1-IC,TBD!!!F86!RSVD(99)!!!!
S!TP_CPU0_KTI2_AMONV!U5D1!CN22!@baseboard_fab2_lib.baseboard_fab2(sch_1):page39_i127@chpset_lib.skx_ext_b(chips)!SKX_EXT_B_BGA1-IC,TBD!!!F80!RSVD(77)!!!!
S!TP_CPU0_KTI2_DFX_DN!U5D1!CW22!@baseboard_fab2_lib.baseboard_fab2(sch_1):page39_i127@chpset_lib.skx_ext_b(chips)!SKX_EXT_B_BGA1-IC,TBD!!!F80!RSVD(63)!!!!
S!TP_CPU0_RSVD_59!U5D1!CY23!@baseboard_fab2_lib.baseboard_fab2(sch_1):page39_i127@chpset_lib.skx_ext_b(chips)!SKX_EXT_B_BGA1-IC,TBD!!!F80!RSVD(59)!!!!
S!TP_CPU0_RSVD_85!U5D1!CK19!@baseboard_fab2_lib.baseboard_fab2(sch_1):page36_i16@chpset_lib.skx_ext_b(chips)!SKX_EXT_B_BGA1-IC,TBD!!!F85!RSVD(85)!!!!
S!TP_CPU0_RSVD_15!U5D1!EC16!@baseboard_fab2_lib.baseboard_fab2(sch_1):page39_i127@chpset_lib.skx_ext_b(chips)!SKX_EXT_B_BGA1-IC,TBD!!!F80!RSVD(15)!!!!
S!TP_CPU0_RSVD_8!U5D1!EE16!@baseboard_fab2_lib.baseboard_fab2(sch_1):page39_i127@chpset_lib.skx_ext_b(chips)!SKX_EXT_B_BGA1-IC,TBD!!!F80!RSVD(8)!!!!
S!XDP_PRESENT_N!U5D1!AV21!@baseboard_fab2_lib.baseboard_fab2(sch_1):page22_i204@chpset_lib.skx_ext_b(chips)!SKX_EXT_B_BGA1-IC,TBD!!!F100!DEBUG_EN_N!!!!
S!TP_CPU0_RSVD_168!U5D1!BB15!@baseboard_fab2_lib.baseboard_fab2(sch_1):page36_i15@chpset_lib.skx_ext_b(chips)!SKX_EXT_B_BGA1-IC,TBD!!!F86!RSVD(168)!!!!
S!TP_CPU0_RSVD_176!U5D1!BA18!@baseboard_fab2_lib.baseboard_fab2(sch_1):page29_i61@chpset_lib.skx_ext_b(chips)!SKX_EXT_B_BGA1-IC,TBD!!!F93!RSVD(176)!!!!
S!TP_CPU0_RSVD_147!U5D1!BE22!@baseboard_fab2_lib.baseboard_fab2(sch_1):page36_i15@chpset_lib.skx_ext_b(chips)!SKX_EXT_B_BGA1-IC,TBD!!!F86!RSVD(147)!!!!
S!TP_CPU0_RSVD_159!U5D1!BC22!@baseboard_fab2_lib.baseboard_fab2(sch_1):page36_i15@chpset_lib.skx_ext_b(chips)!SKX_EXT_B_BGA1-IC,TBD!!!F86!RSVD(159)!!!!
S!TP_CPU0_RSVD_160!U5D1!BC20!@baseboard_fab2_lib.baseboard_fab2(sch_1):page36_i15@chpset_lib.skx_ext_b(chips)!SKX_EXT_B_BGA1-IC,TBD!!!F86!RSVD(160)!!!!
S!TP_CPU0_RSVD_148!U5D1!BE20!@baseboard_fab2_lib.baseboard_fab2(sch_1):page36_i15@chpset_lib.skx_ext_b(chips)!SKX_EXT_B_BGA1-IC,TBD!!!F86!RSVD(148)!!!!
S!TP_CPU0_RSVD_154!U5D1!BD19!@baseboard_fab2_lib.baseboard_fab2(sch_1):page36_i15@chpset_lib.skx_ext_b(chips)!SKX_EXT_B_BGA1-IC,TBD!!!F86!RSVD(154)!!!!
S!TP_CPU0_RSVD_178!U5D1!BA14!@baseboard_fab2_lib.baseboard_fab2(sch_1):page29_i61@chpset_lib.skx_ext_b(chips)!SKX_EXT_B_BGA1-IC,TBD!!!F93!RSVD(178)!!!!
S!TP_CPU0_RSVD_146!U5D1!BF21!@baseboard_fab2_lib.baseboard_fab2(sch_1):page36_i15@chpset_lib.skx_ext_b(chips)!SKX_EXT_B_BGA1-IC,TBD!!!F86!RSVD(146)!!!!
S!TP_CPU0_RSVD_169!U5D1!BB13!@baseboard_fab2_lib.baseboard_fab2(sch_1):page36_i15@chpset_lib.skx_ext_b(chips)!SKX_EXT_B_BGA1-IC,TBD!!!F86!RSVD(169)!!!!
S!TP_CPU0_RSVD_144!U5D1!BG20!@baseboard_fab2_lib.baseboard_fab2(sch_1):page36_i15@chpset_lib.skx_ext_b(chips)!SKX_EXT_B_BGA1-IC,TBD!!!F86!RSVD(144)!!!!
S!TP_CPU0_RSVD_145!U5D1!BG18!@baseboard_fab2_lib.baseboard_fab2(sch_1):page36_i15@chpset_lib.skx_ext_b(chips)!SKX_EXT_B_BGA1-IC,TBD!!!F86!RSVD(145)!!!!
S!TP_CPU0_RSVD_162!U5D1!BC14!@baseboard_fab2_lib.baseboard_fab2(sch_1):page36_i15@chpset_lib.skx_ext_b(chips)!SKX_EXT_B_BGA1-IC,TBD!!!F86!RSVD(162)!!!!
S!TP_CPU0_RSVD_167!U5D1!BB17!@baseboard_fab2_lib.baseboard_fab2(sch_1):page36_i15@chpset_lib.skx_ext_b(chips)!SKX_EXT_B_BGA1-IC,TBD!!!F86!RSVD(167)!!!!
S!TP_CPU0_RSVD_149!U5D1!BE18!@baseboard_fab2_lib.baseboard_fab2(sch_1):page36_i15@chpset_lib.skx_ext_b(chips)!SKX_EXT_B_BGA1-IC,TBD!!!F86!RSVD(149)!!!!
S!TP_CPU0_RSVD_177!U5D1!BA16!@baseboard_fab2_lib.baseboard_fab2(sch_1):page29_i61@chpset_lib.skx_ext_b(chips)!SKX_EXT_B_BGA1-IC,TBD!!!F93!RSVD(177)!!!!
S!TP_CPU0_RSVD_161!U5D1!BC18!@baseboard_fab2_lib.baseboard_fab2(sch_1):page36_i15@chpset_lib.skx_ext_b(chips)!SKX_EXT_B_BGA1-IC,TBD!!!F86!RSVD(161)!!!!
S!TP_CPU0_RSVD_166!U5D1!BB21!@baseboard_fab2_lib.baseboard_fab2(sch_1):page36_i15@chpset_lib.skx_ext_b(chips)!SKX_EXT_B_BGA1-IC,TBD!!!F86!RSVD(166)!!!!
S!TP_CPU0_RSVD_155!U5D1!BD17!@baseboard_fab2_lib.baseboard_fab2(sch_1):page36_i15@chpset_lib.skx_ext_b(chips)!SKX_EXT_B_BGA1-IC,TBD!!!F86!RSVD(155)!!!!
S!TP_CPU0_RSVD_175!U5D1!BA22!@baseboard_fab2_lib.baseboard_fab2(sch_1):page29_i61@chpset_lib.skx_ext_b(chips)!SKX_EXT_B_BGA1-IC,TBD!!!F93!RSVD(175)!!!!
S!TP_CPU0_RSVD_57!U5D1!CY39!@baseboard_fab2_lib.baseboard_fab2(sch_1):page39_i127@chpset_lib.skx_ext_b(chips)!SKX_EXT_B_BGA1-IC,TBD!!!F80!RSVD(57)!!!!
S!TP_CPU0_RSVD_51!U5D1!DA40!@baseboard_fab2_lib.baseboard_fab2(sch_1):page39_i127@chpset_lib.skx_ext_b(chips)!SKX_EXT_B_BGA1-IC,TBD!!!F80!RSVD(51)!!!!
S!TP_CPU0_RSVD_38!U5D1!DK37!@baseboard_fab2_lib.baseboard_fab2(sch_1):page39_i127@chpset_lib.skx_ext_b(chips)!SKX_EXT_B_BGA1-IC,TBD!!!F80!RSVD(38)!!!!
S!TP_CPU0_RSVD_35!U5D1!DL38!@baseboard_fab2_lib.baseboard_fab2(sch_1):page39_i127@chpset_lib.skx_ext_b(chips)!SKX_EXT_B_BGA1-IC,TBD!!!F80!RSVD(35)!!!!
S!A_CPU0_MCP01_RBIAS!U5D1!CU32!@baseboard_fab2_lib.baseboard_fab2(sch_1):page21_i259@chpset_lib.skx_ext_b(chips)!SKX_EXT_B_BGA1-IC,TBD!!!F101!MCP01_RBIAS(0)!!!!
S!TP_CPU0_RSVD_44!U5D1!DG36!@baseboard_fab2_lib.baseboard_fab2(sch_1):page39_i127@chpset_lib.skx_ext_b(chips)!SKX_EXT_B_BGA1-IC,TBD!!!F80!RSVD(44)!!!!
S!TP_CPU0_RSVD_41!U5D1!DJ36!@baseboard_fab2_lib.baseboard_fab2(sch_1):page39_i127@chpset_lib.skx_ext_b(chips)!SKX_EXT_B_BGA1-IC,TBD!!!F80!RSVD(41)!!!!
S!PD_CPU0_TEST12!U5D1!AY19!@baseboard_fab2_lib.baseboard_fab2(sch_1):page21_i259@chpset_lib.skx_ext_b(chips)!SKX_EXT_B_BGA1-IC,TBD!!!F101!TEST_12!!!!
S!TP_CPU0_RSVD_39!U5D1!DK15!@baseboard_fab2_lib.baseboard_fab2(sch_1):page39_i127@chpset_lib.skx_ext_b(chips)!SKX_EXT_B_BGA1-IC,TBD!!!F80!RSVD(39)!!!!
S!TP_CPU0_RSVD_30!U5D1!DP17!@baseboard_fab2_lib.baseboard_fab2(sch_1):page39_i127@chpset_lib.skx_ext_b(chips)!SKX_EXT_B_BGA1-IC,TBD!!!F80!RSVD(30)!!!!
S!TP_CPU0_RSVD_113!U5D1!CB5!@baseboard_fab2_lib.baseboard_fab2(sch_1):page36_i15@chpset_lib.skx_ext_b(chips)!SKX_EXT_B_BGA1-IC,TBD!!!F86!RSVD(113)!!!!
S!TP_CPU0_RSVD_111!U5D1!CC6!@baseboard_fab2_lib.baseboard_fab2(sch_1):page36_i15@chpset_lib.skx_ext_b(chips)!SKX_EXT_B_BGA1-IC,TBD!!!F86!RSVD(111)!!!!
S!TP_CPU0_RSVD_123!U5D1!BW10!@baseboard_fab2_lib.baseboard_fab2(sch_1):page36_i15@chpset_lib.skx_ext_b(chips)!SKX_EXT_B_BGA1-IC,TBD!!!F86!RSVD(123)!!!!
S!TP_CPU0_RSVD_70!U5D1!CT5!@baseboard_fab2_lib.baseboard_fab2(sch_1):page39_i127@chpset_lib.skx_ext_b(chips)!SKX_EXT_B_BGA1-IC,TBD!!!F80!RSVD(70)!!!!
S!TP_CPU0_RSVD_67!U5D1!CU6!@baseboard_fab2_lib.baseboard_fab2(sch_1):page39_i127@chpset_lib.skx_ext_b(chips)!SKX_EXT_B_BGA1-IC,TBD!!!F80!RSVD(67)!!!!
S!TP_CPU0_RSVD_14!U5D1!EC4!@baseboard_fab2_lib.baseboard_fab2(sch_1):page39_i127@chpset_lib.skx_ext_b(chips)!SKX_EXT_B_BGA1-IC,TBD!!!F80!RSVD(14)!!!!
S!TP_CPU0_RSVD_17!U5D1!EB5!@baseboard_fab2_lib.baseboard_fab2(sch_1):page39_i127@chpset_lib.skx_ext_b(chips)!SKX_EXT_B_BGA1-IC,TBD!!!F80!RSVD(17)!!!!
S!TP_CPU0_RSVD_21!U5D1!DY3!@baseboard_fab2_lib.baseboard_fab2(sch_1):page39_i127@chpset_lib.skx_ext_b(chips)!SKX_EXT_B_BGA1-IC,TBD!!!F80!RSVD(21)!!!!
S!TP_CPU0_RSVD_20!U5D1!EA4!@baseboard_fab2_lib.baseboard_fab2(sch_1):page39_i127@chpset_lib.skx_ext_b(chips)!SKX_EXT_B_BGA1-IC,TBD!!!F80!RSVD(20)!!!!
S!TP_CPU0_RSVD_18!U5D1!EB3!@baseboard_fab2_lib.baseboard_fab2(sch_1):page39_i127@chpset_lib.skx_ext_b(chips)!SKX_EXT_B_BGA1-IC,TBD!!!F80!RSVD(18)!!!!
S!TP_CPU0_RSVD_10!U5D1!ED5!@baseboard_fab2_lib.baseboard_fab2(sch_1):page39_i127@chpset_lib.skx_ext_b(chips)!SKX_EXT_B_BGA1-IC,TBD!!!F80!RSVD(10)!!!!
S!TP_CPU0_RSVD_6!U5D1!EE6!@baseboard_fab2_lib.baseboard_fab2(sch_1):page39_i127@chpset_lib.skx_ext_b(chips)!SKX_EXT_B_BGA1-IC,TBD!!!F80!RSVD(6)!!!!
S!XDP_CPU_PWR_DEBUG_N!U5D1!AP17!@baseboard_fab2_lib.baseboard_fab2(sch_1):page22_i204@chpset_lib.skx_ext_b(chips)!SKX_EXT_B_BGA1-IC,TBD!!!F100!PWR_DEBUG_N!!!!
S!TP_CPU0_RSVD_282!U5D1!E4!@baseboard_fab2_lib.baseboard_fab2(sch_1):page22_i204@chpset_lib.skx_ext_b(chips)!SKX_EXT_B_BGA1-IC,TBD!!!F100!RSVD(282)!!!!
S!TP_CPU0_RSVD_287!U5D1!D5!@baseboard_fab2_lib.baseboard_fab2(sch_1):page22_i204@chpset_lib.skx_ext_b(chips)!SKX_EXT_B_BGA1-IC,TBD!!!F100!RSVD(287)!!!!
S!TP_CPU0_RSVD_299!U5D1!B3!@baseboard_fab2_lib.baseboard_fab2(sch_1):page22_i204@chpset_lib.skx_ext_b(chips)!SKX_EXT_B_BGA1-IC,TBD!!!F100!RSVD(299)!!!!
S!TP_CPU0_RSVD_304!U5D1!A4!@baseboard_fab2_lib.baseboard_fab2(sch_1):page22_i204@chpset_lib.skx_ext_b(chips)!SKX_EXT_B_BGA1-IC,TBD!!!F100!RSVD(304)!!!!
S!TP_CPU0_RSVD_303!U5D1!A6!@baseboard_fab2_lib.baseboard_fab2(sch_1):page22_i204@chpset_lib.skx_ext_b(chips)!SKX_EXT_B_BGA1-IC,TBD!!!F100!RSVD(303)!!!!
S!TP_CPU0_RSVD_298!U5D1!B7!@baseboard_fab2_lib.baseboard_fab2(sch_1):page22_i204@chpset_lib.skx_ext_b(chips)!SKX_EXT_B_BGA1-IC,TBD!!!F100!RSVD(298)!!!!
S!TP_CPU0_RSVD_275!U5D1!G2!@baseboard_fab2_lib.baseboard_fab2(sch_1):page22_i204@chpset_lib.skx_ext_b(chips)!SKX_EXT_B_BGA1-IC,TBD!!!F100!RSVD(275)!!!!
S!TP_CPU0_RSVD_283!U5D1!E2!@baseboard_fab2_lib.baseboard_fab2(sch_1):page22_i204@chpset_lib.skx_ext_b(chips)!SKX_EXT_B_BGA1-IC,TBD!!!F100!RSVD(283)!!!!
S!TP_CPU0_RSVD_31!U5D1!DN66!@baseboard_fab2_lib.baseboard_fab2(sch_1):page39_i127@chpset_lib.skx_ext_b(chips)!SKX_EXT_B_BGA1-IC,TBD!!!F80!RSVD(31)!!!!
S!TP_CPU0_RSVD_33!U5D1!DM67!@baseboard_fab2_lib.baseboard_fab2(sch_1):page39_i127@chpset_lib.skx_ext_b(chips)!SKX_EXT_B_BGA1-IC,TBD!!!F80!RSVD(33)!!!!
S!TP_CPU0_RSVD_24!U5D1!DV71!@baseboard_fab2_lib.baseboard_fab2(sch_1):page39_i127@chpset_lib.skx_ext_b(chips)!SKX_EXT_B_BGA1-IC,TBD!!!F80!RSVD(24)!!!!
S!TP_CPU0_RSVD_27!U5D1!DT71!@baseboard_fab2_lib.baseboard_fab2(sch_1):page39_i127@chpset_lib.skx_ext_b(chips)!SKX_EXT_B_BGA1-IC,TBD!!!F80!RSVD(27)!!!!
S!TP_CPU0_RSVD_245!U5D1!AF47!@baseboard_fab2_lib.baseboard_fab2(sch_1):page22_i204@chpset_lib.skx_ext_b(chips)!SKX_EXT_B_BGA1-IC,TBD!!!F100!RSVD(245)!!!!
S!TP_CPU0_RSVD_50!U5D1!DA52!@baseboard_fab2_lib.baseboard_fab2(sch_1):page39_i127@chpset_lib.skx_ext_b(chips)!SKX_EXT_B_BGA1-IC,TBD!!!F80!RSVD(50)!!!!
S!TP_CPU0_RSVD_254!U5D1!AD47!@baseboard_fab2_lib.baseboard_fab2(sch_1):page22_i204@chpset_lib.skx_ext_b(chips)!SKX_EXT_B_BGA1-IC,TBD!!!F100!RSVD(254)!!!!
S!TP_CPU0_RSVD_56!U5D1!CY53!@baseboard_fab2_lib.baseboard_fab2(sch_1):page39_i127@chpset_lib.skx_ext_b(chips)!SKX_EXT_B_BGA1-IC,TBD!!!F80!RSVD(56)!!!!
S!M_A_ACT_N!U5D1!J60!@baseboard_fab2_lib.baseboard_fab2(sch_1):page23_i172@chpset_lib.skx_ext_b(chips)!SKX_EXT_B_BGA1-IC,TBD!!!F99!DDR0_ACT_N!!!!
S!M_A_ALERT_N!U5D1!B61!@baseboard_fab2_lib.baseboard_fab2(sch_1):page23_i172@chpset_lib.skx_ext_b(chips)!SKX_EXT_B_BGA1-IC,TBD!!!F99!DDR0_ALERT_N!!!!
S!M_A_BA<0>!U5D1!C52!@baseboard_fab2_lib.baseboard_fab2(sch_1):page23_i172@chpset_lib.skx_ext_b(chips)!SKX_EXT_B_BGA1-IC,TBD!!!F99!DDR0_BA(0)!!!!
S!M_A_BA<1>!U5D1!G54!@baseboard_fab2_lib.baseboard_fab2(sch_1):page23_i172@chpset_lib.skx_ext_b(chips)!SKX_EXT_B_BGA1-IC,TBD!!!F99!DDR0_BA(1)!!!!
S!M_A_BG<0>!U5D1!D61!@baseboard_fab2_lib.baseboard_fab2(sch_1):page23_i172@chpset_lib.skx_ext_b(chips)!SKX_EXT_B_BGA1-IC,TBD!!!F99!DDR0_BG(0)!!!!
S!M_A_BG<1>!U5D1!F63!@baseboard_fab2_lib.baseboard_fab2(sch_1):page23_i172@chpset_lib.skx_ext_b(chips)!SKX_EXT_B_BGA1-IC,TBD!!!F99!DDR0_BG(1)!!!!
S!M_A_C<2>!U5D1!G46!@baseboard_fab2_lib.baseboard_fab2(sch_1):page23_i172@chpset_lib.skx_ext_b(chips)!SKX_EXT_B_BGA1-IC,TBD!!!F99!DDR0_CID(2)!!!!
S!M_A_CKE<0>!U5D1!C62!@baseboard_fab2_lib.baseboard_fab2(sch_1):page23_i172@chpset_lib.skx_ext_b(chips)!SKX_EXT_B_BGA1-IC,TBD!!!F99!DDR0_CKE(0)!!!!
S!M_A_CKE<1>!U5D1!C64!@baseboard_fab2_lib.baseboard_fab2(sch_1):page23_i172@chpset_lib.skx_ext_b(chips)!SKX_EXT_B_BGA1-IC,TBD!!!F99!DDR0_CKE(1)!!!!
S!M_A_CKE<2>!U5D1!B63!@baseboard_fab2_lib.baseboard_fab2(sch_1):page23_i172@chpset_lib.skx_ext_b(chips)!SKX_EXT_B_BGA1-IC,TBD!!!F99!DDR0_CKE(2)!!!!
S!M_A_CKE<3>!U5D1!D63!@baseboard_fab2_lib.baseboard_fab2(sch_1):page23_i172@chpset_lib.skx_ext_b(chips)!SKX_EXT_B_BGA1-IC,TBD!!!F99!DDR0_CKE(3)!!!!
S!M_A_CLK_DN<0>!U5D1!F55!@baseboard_fab2_lib.baseboard_fab2(sch_1):page23_i172@chpset_lib.skx_ext_b(chips)!SKX_EXT_B_BGA1-IC,TBD!!!F99!DDR0_CLK_DN(0)!!!!
S!M_A_CLK_DN<2>!U5D1!J56!@baseboard_fab2_lib.baseboard_fab2(sch_1):page23_i172@chpset_lib.skx_ext_b(chips)!SKX_EXT_B_BGA1-IC,TBD!!!F99!DDR0_CLK_DN(2)!!!!
S!M_A_CLK_DN<1>!U5D1!C54!@baseboard_fab2_lib.baseboard_fab2(sch_1):page23_i172@chpset_lib.skx_ext_b(chips)!SKX_EXT_B_BGA1-IC,TBD!!!F99!DDR0_CLK_DN(1)!!!!
S!M_A_CLK_DN<3>!U5D1!C56!@baseboard_fab2_lib.baseboard_fab2(sch_1):page23_i172@chpset_lib.skx_ext_b(chips)!SKX_EXT_B_BGA1-IC,TBD!!!F99!DDR0_CLK_DN(3)!!!!
S!M_A_CLK_DP<0>!U5D1!D55!@baseboard_fab2_lib.baseboard_fab2(sch_1):page23_i172@chpset_lib.skx_ext_b(chips)!SKX_EXT_B_BGA1-IC,TBD!!!F99!DDR0_CLK_DP(0)!!!!
S!M_A_CLK_DP<2>!U5D1!G56!@baseboard_fab2_lib.baseboard_fab2(sch_1):page23_i172@chpset_lib.skx_ext_b(chips)!SKX_EXT_B_BGA1-IC,TBD!!!F99!DDR0_CLK_DP(2)!!!!
S!M_A_CLK_DP<1>!U5D1!B55!@baseboard_fab2_lib.baseboard_fab2(sch_1):page23_i172@chpset_lib.skx_ext_b(chips)!SKX_EXT_B_BGA1-IC,TBD!!!F99!DDR0_CLK_DP(1)!!!!
S!M_A_CLK_DP<3>!U5D1!B57!@baseboard_fab2_lib.baseboard_fab2(sch_1):page23_i172@chpset_lib.skx_ext_b(chips)!SKX_EXT_B_BGA1-IC,TBD!!!F99!DDR0_CLK_DP(3)!!!!
S!M_A_CS_N<0>!U5D1!G52!@baseboard_fab2_lib.baseboard_fab2(sch_1):page23_i172@chpset_lib.skx_ext_b(chips)!SKX_EXT_B_BGA1-IC,TBD!!!F99!DDR0_CS_N(0)!!!!
S!M_A_CS_N<1>!U5D1!F49!@baseboard_fab2_lib.baseboard_fab2(sch_1):page23_i172@chpset_lib.skx_ext_b(chips)!SKX_EXT_B_BGA1-IC,TBD!!!F99!DDR0_CS_N(1)!!!!
S!M_A_CS_N<2>!U5D1!D47!@baseboard_fab2_lib.baseboard_fab2(sch_1):page23_i172@chpset_lib.skx_ext_b(chips)!SKX_EXT_B_BGA1-IC,TBD!!!F99!DDR0_CS_N(2)!!!!
S!M_A_CS_N<3>!U5D1!F47!@baseboard_fab2_lib.baseboard_fab2(sch_1):page23_i172@chpset_lib.skx_ext_b(chips)!SKX_EXT_B_BGA1-IC,TBD!!!F99!DDR0_CS_N(3)!!!!
S!M_A_CS_N<4>!U5D1!B51!@baseboard_fab2_lib.baseboard_fab2(sch_1):page23_i172@chpset_lib.skx_ext_b(chips)!SKX_EXT_B_BGA1-IC,TBD!!!F99!DDR0_CS_N(4)!!!!
S!M_A_CS_N<5>!U5D1!D49!@baseboard_fab2_lib.baseboard_fab2(sch_1):page23_i172@chpset_lib.skx_ext_b(chips)!SKX_EXT_B_BGA1-IC,TBD!!!F99!DDR0_CS_N(5)!!!!
S!M_A_CS_N<6>!U5D1!F45!@baseboard_fab2_lib.baseboard_fab2(sch_1):page23_i172@chpset_lib.skx_ext_b(chips)!SKX_EXT_B_BGA1-IC,TBD!!!F99!DDR0_CS_N(6)!!!!
S!M_A_CS_N<7>!U5D1!K45!@baseboard_fab2_lib.baseboard_fab2(sch_1):page23_i172@chpset_lib.skx_ext_b(chips)!SKX_EXT_B_BGA1-IC,TBD!!!F99!DDR0_CS_N(7)!!!!
S!M_A_DQ<0>!U5D1!AN86!@baseboard_fab2_lib.baseboard_fab2(sch_1):page23_i172@chpset_lib.skx_ext_b(chips)!SKX_EXT_B_BGA1-IC,TBD!!!F99!DDR0_DQ(0)!!!!
S!M_A_DQ<10>!U5D1!L86!@baseboard_fab2_lib.baseboard_fab2(sch_1):page23_i172@chpset_lib.skx_ext_b(chips)!SKX_EXT_B_BGA1-IC,TBD!!!F99!DDR0_DQ(10)!!!!
S!M_A_DQ<11>!U5D1!L84!@baseboard_fab2_lib.baseboard_fab2(sch_1):page23_i172@chpset_lib.skx_ext_b(chips)!SKX_EXT_B_BGA1-IC,TBD!!!F99!DDR0_DQ(11)!!!!
S!M_A_DQ<12>!U5D1!AA86!@baseboard_fab2_lib.baseboard_fab2(sch_1):page23_i172@chpset_lib.skx_ext_b(chips)!SKX_EXT_B_BGA1-IC,TBD!!!F99!DDR0_DQ(12)!!!!
S!M_A_DQ<13>!U5D1!AA84!@baseboard_fab2_lib.baseboard_fab2(sch_1):page23_i172@chpset_lib.skx_ext_b(chips)!SKX_EXT_B_BGA1-IC,TBD!!!F99!DDR0_DQ(13)!!!!
S!M_A_DQ<14>!U5D1!N86!@baseboard_fab2_lib.baseboard_fab2(sch_1):page23_i172@chpset_lib.skx_ext_b(chips)!SKX_EXT_B_BGA1-IC,TBD!!!F99!DDR0_DQ(14)!!!!
S!M_A_DQ<15>!U5D1!N84!@baseboard_fab2_lib.baseboard_fab2(sch_1):page23_i172@chpset_lib.skx_ext_b(chips)!SKX_EXT_B_BGA1-IC,TBD!!!F99!DDR0_DQ(15)!!!!
S!M_A_DQ<16>!U5D1!V81!@baseboard_fab2_lib.baseboard_fab2(sch_1):page23_i172@chpset_lib.skx_ext_b(chips)!SKX_EXT_B_BGA1-IC,TBD!!!F99!DDR0_DQ(16)!!!!
S!M_A_DQ<17>!U5D1!T79!@baseboard_fab2_lib.baseboard_fab2(sch_1):page23_i172@chpset_lib.skx_ext_b(chips)!SKX_EXT_B_BGA1-IC,TBD!!!F99!DDR0_DQ(17)!!!!
S!M_A_DQ<18>!U5D1!N82!@baseboard_fab2_lib.baseboard_fab2(sch_1):page23_i172@chpset_lib.skx_ext_b(chips)!SKX_EXT_B_BGA1-IC,TBD!!!F99!DDR0_DQ(18)!!!!
S!M_A_DQ<19>!U5D1!M81!@baseboard_fab2_lib.baseboard_fab2(sch_1):page23_i172@chpset_lib.skx_ext_b(chips)!SKX_EXT_B_BGA1-IC,TBD!!!F99!DDR0_DQ(19)!!!!
S!M_A_DQ<1>!U5D1!AN84!@baseboard_fab2_lib.baseboard_fab2(sch_1):page23_i172@chpset_lib.skx_ext_b(chips)!SKX_EXT_B_BGA1-IC,TBD!!!F99!DDR0_DQ(1)!!!!
S!M_A_DQ<20>!U5D1!W80!@baseboard_fab2_lib.baseboard_fab2(sch_1):page23_i172@chpset_lib.skx_ext_b(chips)!SKX_EXT_B_BGA1-IC,TBD!!!F99!DDR0_DQ(20)!!!!
S!M_A_DQ<21>!U5D1!V79!@baseboard_fab2_lib.baseboard_fab2(sch_1):page23_i172@chpset_lib.skx_ext_b(chips)!SKX_EXT_B_BGA1-IC,TBD!!!F99!DDR0_DQ(21)!!!!
S!M_A_DQ<22>!U5D1!R82!@baseboard_fab2_lib.baseboard_fab2(sch_1):page23_i172@chpset_lib.skx_ext_b(chips)!SKX_EXT_B_BGA1-IC,TBD!!!F99!DDR0_DQ(22)!!!!
S!M_A_DQ<23>!U5D1!N80!@baseboard_fab2_lib.baseboard_fab2(sch_1):page23_i172@chpset_lib.skx_ext_b(chips)!SKX_EXT_B_BGA1-IC,TBD!!!F99!DDR0_DQ(23)!!!!
S!M_A_DQ<24>!U5D1!L76!@baseboard_fab2_lib.baseboard_fab2(sch_1):page23_i172@chpset_lib.skx_ext_b(chips)!SKX_EXT_B_BGA1-IC,TBD!!!F99!DDR0_DQ(24)!!!!
S!M_A_DQ<25>!U5D1!R76!@baseboard_fab2_lib.baseboard_fab2(sch_1):page23_i172@chpset_lib.skx_ext_b(chips)!SKX_EXT_B_BGA1-IC,TBD!!!F99!DDR0_DQ(25)!!!!
S!M_A_DQ<26>!U5D1!M73!@baseboard_fab2_lib.baseboard_fab2(sch_1):page23_i172@chpset_lib.skx_ext_b(chips)!SKX_EXT_B_BGA1-IC,TBD!!!F99!DDR0_DQ(26)!!!!
S!M_A_DQ<27>!U5D1!P73!@baseboard_fab2_lib.baseboard_fab2(sch_1):page23_i172@chpset_lib.skx_ext_b(chips)!SKX_EXT_B_BGA1-IC,TBD!!!F99!DDR0_DQ(27)!!!!
S!M_A_DQ<28>!U5D1!M77!@baseboard_fab2_lib.baseboard_fab2(sch_1):page23_i172@chpset_lib.skx_ext_b(chips)!SKX_EXT_B_BGA1-IC,TBD!!!F99!DDR0_DQ(28)!!!!
S!M_A_DQ<29>!U5D1!P77!@baseboard_fab2_lib.baseboard_fab2(sch_1):page23_i172@chpset_lib.skx_ext_b(chips)!SKX_EXT_B_BGA1-IC,TBD!!!F99!DDR0_DQ(29)!!!!
S!M_A_DQ<2>!U5D1!AE86!@baseboard_fab2_lib.baseboard_fab2(sch_1):page23_i172@chpset_lib.skx_ext_b(chips)!SKX_EXT_B_BGA1-IC,TBD!!!F99!DDR0_DQ(2)!!!!
S!M_A_DQ<30>!U5D1!L74!@baseboard_fab2_lib.baseboard_fab2(sch_1):page23_i172@chpset_lib.skx_ext_b(chips)!SKX_EXT_B_BGA1-IC,TBD!!!F99!DDR0_DQ(30)!!!!
S!M_A_DQ<31>!U5D1!R74!@baseboard_fab2_lib.baseboard_fab2(sch_1):page23_i172@chpset_lib.skx_ext_b(chips)!SKX_EXT_B_BGA1-IC,TBD!!!F99!DDR0_DQ(31)!!!!
S!M_A_DQ<32>!U5D1!C42!@baseboard_fab2_lib.baseboard_fab2(sch_1):page23_i172@chpset_lib.skx_ext_b(chips)!SKX_EXT_B_BGA1-IC,TBD!!!F99!DDR0_DQ(32)!!!!
S!M_A_DQ<33>!U5D1!B41!@baseboard_fab2_lib.baseboard_fab2(sch_1):page23_i172@chpset_lib.skx_ext_b(chips)!SKX_EXT_B_BGA1-IC,TBD!!!F99!DDR0_DQ(33)!!!!
S!M_A_DQ<34>!U5D1!C38!@baseboard_fab2_lib.baseboard_fab2(sch_1):page23_i172@chpset_lib.skx_ext_b(chips)!SKX_EXT_B_BGA1-IC,TBD!!!F99!DDR0_DQ(34)!!!!
S!M_A_DQ<35>!U5D1!E38!@baseboard_fab2_lib.baseboard_fab2(sch_1):page23_i172@chpset_lib.skx_ext_b(chips)!SKX_EXT_B_BGA1-IC,TBD!!!F99!DDR0_DQ(35)!!!!
S!M_A_DQ<36>!U5D1!E42!@baseboard_fab2_lib.baseboard_fab2(sch_1):page23_i172@chpset_lib.skx_ext_b(chips)!SKX_EXT_B_BGA1-IC,TBD!!!F99!DDR0_DQ(36)!!!!
S!M_A_DQ<37>!U5D1!F41!@baseboard_fab2_lib.baseboard_fab2(sch_1):page23_i172@chpset_lib.skx_ext_b(chips)!SKX_EXT_B_BGA1-IC,TBD!!!F99!DDR0_DQ(37)!!!!
S!M_A_DQ<38>!U5D1!B39!@baseboard_fab2_lib.baseboard_fab2(sch_1):page23_i172@chpset_lib.skx_ext_b(chips)!SKX_EXT_B_BGA1-IC,TBD!!!F99!DDR0_DQ(38)!!!!
S!M_A_DQ<39>!U5D1!F39!@baseboard_fab2_lib.baseboard_fab2(sch_1):page23_i172@chpset_lib.skx_ext_b(chips)!SKX_EXT_B_BGA1-IC,TBD!!!F99!DDR0_DQ(39)!!!!
S!M_A_DQ<3>!U5D1!AE84!@baseboard_fab2_lib.baseboard_fab2(sch_1):page23_i172@chpset_lib.skx_ext_b(chips)!SKX_EXT_B_BGA1-IC,TBD!!!F99!DDR0_DQ(3)!!!!
S!M_A_DQ<40>!U5D1!K37!@baseboard_fab2_lib.baseboard_fab2(sch_1):page23_i172@chpset_lib.skx_ext_b(chips)!SKX_EXT_B_BGA1-IC,TBD!!!F99!DDR0_DQ(40)!!!!
S!M_A_DQ<41>!U5D1!P37!@baseboard_fab2_lib.baseboard_fab2(sch_1):page23_i172@chpset_lib.skx_ext_b(chips)!SKX_EXT_B_BGA1-IC,TBD!!!F99!DDR0_DQ(41)!!!!
S!M_A_DQ<42>!U5D1!L34!@baseboard_fab2_lib.baseboard_fab2(sch_1):page23_i172@chpset_lib.skx_ext_b(chips)!SKX_EXT_B_BGA1-IC,TBD!!!F99!DDR0_DQ(42)!!!!
S!M_A_DQ<43>!U5D1!N34!@baseboard_fab2_lib.baseboard_fab2(sch_1):page23_i172@chpset_lib.skx_ext_b(chips)!SKX_EXT_B_BGA1-IC,TBD!!!F99!DDR0_DQ(43)!!!!
S!M_A_DQ<44>!U5D1!L38!@baseboard_fab2_lib.baseboard_fab2(sch_1):page23_i172@chpset_lib.skx_ext_b(chips)!SKX_EXT_B_BGA1-IC,TBD!!!F99!DDR0_DQ(44)!!!!
S!M_A_DQ<45>!U5D1!N38!@baseboard_fab2_lib.baseboard_fab2(sch_1):page23_i172@chpset_lib.skx_ext_b(chips)!SKX_EXT_B_BGA1-IC,TBD!!!F99!DDR0_DQ(45)!!!!
S!M_A_DQ<46>!U5D1!K35!@baseboard_fab2_lib.baseboard_fab2(sch_1):page23_i172@chpset_lib.skx_ext_b(chips)!SKX_EXT_B_BGA1-IC,TBD!!!F99!DDR0_DQ(46)!!!!
S!M_A_DQ<47>!U5D1!P35!@baseboard_fab2_lib.baseboard_fab2(sch_1):page23_i172@chpset_lib.skx_ext_b(chips)!SKX_EXT_B_BGA1-IC,TBD!!!F99!DDR0_DQ(47)!!!!
S!M_A_DQ<48>!U5D1!K31!@baseboard_fab2_lib.baseboard_fab2(sch_1):page23_i172@chpset_lib.skx_ext_b(chips)!SKX_EXT_B_BGA1-IC,TBD!!!F99!DDR0_DQ(48)!!!!
S!M_A_DQ<49>!U5D1!P31!@baseboard_fab2_lib.baseboard_fab2(sch_1):page23_i172@chpset_lib.skx_ext_b(chips)!SKX_EXT_B_BGA1-IC,TBD!!!F99!DDR0_DQ(49)!!!!
S!M_A_DQ<4>!U5D1!AR86!@baseboard_fab2_lib.baseboard_fab2(sch_1):page23_i172@chpset_lib.skx_ext_b(chips)!SKX_EXT_B_BGA1-IC,TBD!!!F99!DDR0_DQ(4)!!!!
S!M_A_DQ<50>!U5D1!L28!@baseboard_fab2_lib.baseboard_fab2(sch_1):page23_i172@chpset_lib.skx_ext_b(chips)!SKX_EXT_B_BGA1-IC,TBD!!!F99!DDR0_DQ(50)!!!!
S!M_A_DQ<51>!U5D1!N28!@baseboard_fab2_lib.baseboard_fab2(sch_1):page23_i172@chpset_lib.skx_ext_b(chips)!SKX_EXT_B_BGA1-IC,TBD!!!F99!DDR0_DQ(51)!!!!
S!M_A_DQ<52>!U5D1!L32!@baseboard_fab2_lib.baseboard_fab2(sch_1):page23_i172@chpset_lib.skx_ext_b(chips)!SKX_EXT_B_BGA1-IC,TBD!!!F99!DDR0_DQ(52)!!!!
S!M_A_DQ<53>!U5D1!N32!@baseboard_fab2_lib.baseboard_fab2(sch_1):page23_i172@chpset_lib.skx_ext_b(chips)!SKX_EXT_B_BGA1-IC,TBD!!!F99!DDR0_DQ(53)!!!!
S!M_A_DQ<54>!U5D1!K29!@baseboard_fab2_lib.baseboard_fab2(sch_1):page23_i172@chpset_lib.skx_ext_b(chips)!SKX_EXT_B_BGA1-IC,TBD!!!F99!DDR0_DQ(54)!!!!
S!M_A_DQ<55>!U5D1!P29!@baseboard_fab2_lib.baseboard_fab2(sch_1):page23_i172@chpset_lib.skx_ext_b(chips)!SKX_EXT_B_BGA1-IC,TBD!!!F99!DDR0_DQ(55)!!!!
S!M_A_DQ<56>!U5D1!K25!@baseboard_fab2_lib.baseboard_fab2(sch_1):page23_i172@chpset_lib.skx_ext_b(chips)!SKX_EXT_B_BGA1-IC,TBD!!!F99!DDR0_DQ(56)!!!!
S!M_A_DQ<57>!U5D1!P25!@baseboard_fab2_lib.baseboard_fab2(sch_1):page23_i172@chpset_lib.skx_ext_b(chips)!SKX_EXT_B_BGA1-IC,TBD!!!F99!DDR0_DQ(57)!!!!
S!M_A_DQ<58>!U5D1!P23!@baseboard_fab2_lib.baseboard_fab2(sch_1):page23_i172@chpset_lib.skx_ext_b(chips)!SKX_EXT_B_BGA1-IC,TBD!!!F99!DDR0_DQ(58)!!!!
S!M_A_DQ<59>!U5D1!T23!@baseboard_fab2_lib.baseboard_fab2(sch_1):page23_i172@chpset_lib.skx_ext_b(chips)!SKX_EXT_B_BGA1-IC,TBD!!!F99!DDR0_DQ(59)!!!!
S!M_A_DQ<5>!U5D1!AR84!@baseboard_fab2_lib.baseboard_fab2(sch_1):page23_i172@chpset_lib.skx_ext_b(chips)!SKX_EXT_B_BGA1-IC,TBD!!!F99!DDR0_DQ(5)!!!!
S!M_A_DQ<60>!U5D1!L26!@baseboard_fab2_lib.baseboard_fab2(sch_1):page23_i172@chpset_lib.skx_ext_b(chips)!SKX_EXT_B_BGA1-IC,TBD!!!F99!DDR0_DQ(60)!!!!
S!M_A_DQ<61>!U5D1!N26!@baseboard_fab2_lib.baseboard_fab2(sch_1):page23_i172@chpset_lib.skx_ext_b(chips)!SKX_EXT_B_BGA1-IC,TBD!!!F99!DDR0_DQ(61)!!!!
S!M_A_DQ<62>!U5D1!H23!@baseboard_fab2_lib.baseboard_fab2(sch_1):page23_i172@chpset_lib.skx_ext_b(chips)!SKX_EXT_B_BGA1-IC,TBD!!!F99!DDR0_DQ(62)!!!!
S!M_A_DQ<63>!U5D1!K23!@baseboard_fab2_lib.baseboard_fab2(sch_1):page23_i172@chpset_lib.skx_ext_b(chips)!SKX_EXT_B_BGA1-IC,TBD!!!F99!DDR0_DQ(63)!!!!
S!M_A_DQ<6>!U5D1!AG86!@baseboard_fab2_lib.baseboard_fab2(sch_1):page23_i172@chpset_lib.skx_ext_b(chips)!SKX_EXT_B_BGA1-IC,TBD!!!F99!DDR0_DQ(6)!!!!
S!M_A_DQ<7>!U5D1!AG84!@baseboard_fab2_lib.baseboard_fab2(sch_1):page23_i172@chpset_lib.skx_ext_b(chips)!SKX_EXT_B_BGA1-IC,TBD!!!F99!DDR0_DQ(7)!!!!
S!M_A_DQ<8>!U5D1!W86!@baseboard_fab2_lib.baseboard_fab2(sch_1):page23_i172@chpset_lib.skx_ext_b(chips)!SKX_EXT_B_BGA1-IC,TBD!!!F99!DDR0_DQ(8)!!!!
S!M_A_DQ<9>!U5D1!W84!@baseboard_fab2_lib.baseboard_fab2(sch_1):page23_i172@chpset_lib.skx_ext_b(chips)!SKX_EXT_B_BGA1-IC,TBD!!!F99!DDR0_DQ(9)!!!!
S!M_A_DQS_DN<0>!U5D1!AJ84!@baseboard_fab2_lib.baseboard_fab2(sch_1):page23_i172@chpset_lib.skx_ext_b(chips)!SKX_EXT_B_BGA1-IC,TBD!!!F99!DDR0_DQS_DN(0)!!!!
S!M_A_DQS_DN<10>!U5D1!U84!@baseboard_fab2_lib.baseboard_fab2(sch_1):page23_i172@chpset_lib.skx_ext_b(chips)!SKX_EXT_B_BGA1-IC,TBD!!!F99!DDR0_DQS_DN(10)!!!!
S!M_A_DQS_DN<11>!U5D1!U82!@baseboard_fab2_lib.baseboard_fab2(sch_1):page23_i172@chpset_lib.skx_ext_b(chips)!SKX_EXT_B_BGA1-IC,TBD!!!F99!DDR0_DQS_DN(11)!!!!
S!M_A_DQS_DN<12>!U5D1!K75!@baseboard_fab2_lib.baseboard_fab2(sch_1):page23_i172@chpset_lib.skx_ext_b(chips)!SKX_EXT_B_BGA1-IC,TBD!!!F99!DDR0_DQS_DN(12)!!!!
S!M_A_DQS_DN<13>!U5D1!A40!@baseboard_fab2_lib.baseboard_fab2(sch_1):page23_i172@chpset_lib.skx_ext_b(chips)!SKX_EXT_B_BGA1-IC,TBD!!!F99!DDR0_DQS_DN(13)!!!!
S!M_A_DQS_DN<14>!U5D1!J36!@baseboard_fab2_lib.baseboard_fab2(sch_1):page23_i172@chpset_lib.skx_ext_b(chips)!SKX_EXT_B_BGA1-IC,TBD!!!F99!DDR0_DQS_DN(14)!!!!
S!M_A_DQS_DN<15>!U5D1!J30!@baseboard_fab2_lib.baseboard_fab2(sch_1):page23_i172@chpset_lib.skx_ext_b(chips)!SKX_EXT_B_BGA1-IC,TBD!!!F99!DDR0_DQS_DN(15)!!!!
S!M_A_DQS_DN<16>!U5D1!J24!@baseboard_fab2_lib.baseboard_fab2(sch_1):page23_i172@chpset_lib.skx_ext_b(chips)!SKX_EXT_B_BGA1-IC,TBD!!!F99!DDR0_DQS_DN(16)!!!!
S!M_A_DQS_DN<17>!U5D1!AB67!@baseboard_fab2_lib.baseboard_fab2(sch_1):page23_i172@chpset_lib.skx_ext_b(chips)!SKX_EXT_B_BGA1-IC,TBD!!!F99!DDR0_DQS_DN(17)!!!!
S!M_A_DQS_DN<1>!U5D1!R84!@baseboard_fab2_lib.baseboard_fab2(sch_1):page23_i172@chpset_lib.skx_ext_b(chips)!SKX_EXT_B_BGA1-IC,TBD!!!F99!DDR0_DQS_DN(1)!!!!
S!M_A_DQS_DN<2>!U5D1!P79!@baseboard_fab2_lib.baseboard_fab2(sch_1):page23_i172@chpset_lib.skx_ext_b(chips)!SKX_EXT_B_BGA1-IC,TBD!!!F99!DDR0_DQS_DN(2)!!!!
S!M_A_DQS_DN<3>!U5D1!T75!@baseboard_fab2_lib.baseboard_fab2(sch_1):page23_i172@chpset_lib.skx_ext_b(chips)!SKX_EXT_B_BGA1-IC,TBD!!!F99!DDR0_DQS_DN(3)!!!!
S!M_A_DQS_DN<4>!U5D1!G40!@baseboard_fab2_lib.baseboard_fab2(sch_1):page23_i172@chpset_lib.skx_ext_b(chips)!SKX_EXT_B_BGA1-IC,TBD!!!F99!DDR0_DQS_DN(4)!!!!
S!M_A_DQS_DN<5>!U5D1!R36!@baseboard_fab2_lib.baseboard_fab2(sch_1):page23_i172@chpset_lib.skx_ext_b(chips)!SKX_EXT_B_BGA1-IC,TBD!!!F99!DDR0_DQS_DN(5)!!!!
S!M_A_DQS_DN<6>!U5D1!R30!@baseboard_fab2_lib.baseboard_fab2(sch_1):page23_i172@chpset_lib.skx_ext_b(chips)!SKX_EXT_B_BGA1-IC,TBD!!!F99!DDR0_DQS_DN(6)!!!!
S!M_A_DQS_DN<7>!U5D1!N24!@baseboard_fab2_lib.baseboard_fab2(sch_1):page23_i172@chpset_lib.skx_ext_b(chips)!SKX_EXT_B_BGA1-IC,TBD!!!F99!DDR0_DQS_DN(7)!!!!
S!M_A_DQS_DN<8>!U5D1!AH67!@baseboard_fab2_lib.baseboard_fab2(sch_1):page23_i172@chpset_lib.skx_ext_b(chips)!SKX_EXT_B_BGA1-IC,TBD!!!F99!DDR0_DQS_DN(8)!!!!
S!M_A_DQS_DN<9>!U5D1!AL84!@baseboard_fab2_lib.baseboard_fab2(sch_1):page23_i172@chpset_lib.skx_ext_b(chips)!SKX_EXT_B_BGA1-IC,TBD!!!F99!DDR0_DQS_DN(9)!!!!
S!M_A_DQS_DP<0>!U5D1!AH85!@baseboard_fab2_lib.baseboard_fab2(sch_1):page23_i172@chpset_lib.skx_ext_b(chips)!SKX_EXT_B_BGA1-IC,TBD!!!F99!DDR0_DQS_DP(0)!!!!
S!M_A_DQS_DP<10>!U5D1!V85!@baseboard_fab2_lib.baseboard_fab2(sch_1):page23_i172@chpset_lib.skx_ext_b(chips)!SKX_EXT_B_BGA1-IC,TBD!!!F99!DDR0_DQS_DP(10)!!!!
S!M_A_DQS_DP<11>!U5D1!T81!@baseboard_fab2_lib.baseboard_fab2(sch_1):page23_i172@chpset_lib.skx_ext_b(chips)!SKX_EXT_B_BGA1-IC,TBD!!!F99!DDR0_DQS_DP(11)!!!!
S!M_A_DQS_DP<12>!U5D1!M75!@baseboard_fab2_lib.baseboard_fab2(sch_1):page23_i172@chpset_lib.skx_ext_b(chips)!SKX_EXT_B_BGA1-IC,TBD!!!F99!DDR0_DQS_DP(12)!!!!
S!M_A_DQS_DP<13>!U5D1!C40!@baseboard_fab2_lib.baseboard_fab2(sch_1):page23_i172@chpset_lib.skx_ext_b(chips)!SKX_EXT_B_BGA1-IC,TBD!!!F99!DDR0_DQS_DP(13)!!!!
S!M_A_DQS_DP<14>!U5D1!L36!@baseboard_fab2_lib.baseboard_fab2(sch_1):page23_i172@chpset_lib.skx_ext_b(chips)!SKX_EXT_B_BGA1-IC,TBD!!!F99!DDR0_DQS_DP(14)!!!!
S!M_A_DQS_DP<15>!U5D1!L30!@baseboard_fab2_lib.baseboard_fab2(sch_1):page23_i172@chpset_lib.skx_ext_b(chips)!SKX_EXT_B_BGA1-IC,TBD!!!F99!DDR0_DQS_DP(15)!!!!
S!M_A_DQS_DP<16>!U5D1!L24!@baseboard_fab2_lib.baseboard_fab2(sch_1):page23_i172@chpset_lib.skx_ext_b(chips)!SKX_EXT_B_BGA1-IC,TBD!!!F99!DDR0_DQS_DP(16)!!!!
S!M_A_DQS_DP<17>!U5D1!AD67!@baseboard_fab2_lib.baseboard_fab2(sch_1):page23_i172@chpset_lib.skx_ext_b(chips)!SKX_EXT_B_BGA1-IC,TBD!!!F99!DDR0_DQS_DP(17)!!!!
S!M_A_DQS_DP<1>!U5D1!P85!@baseboard_fab2_lib.baseboard_fab2(sch_1):page23_i172@chpset_lib.skx_ext_b(chips)!SKX_EXT_B_BGA1-IC,TBD!!!F99!DDR0_DQS_DP(1)!!!!
S!M_A_DQS_DP<2>!U5D1!R80!@baseboard_fab2_lib.baseboard_fab2(sch_1):page23_i172@chpset_lib.skx_ext_b(chips)!SKX_EXT_B_BGA1-IC,TBD!!!F99!DDR0_DQS_DP(2)!!!!
S!M_A_DQS_DP<3>!U5D1!P75!@baseboard_fab2_lib.baseboard_fab2(sch_1):page23_i172@chpset_lib.skx_ext_b(chips)!SKX_EXT_B_BGA1-IC,TBD!!!F99!DDR0_DQS_DP(3)!!!!
S!M_A_DQS_DP<4>!U5D1!E40!@baseboard_fab2_lib.baseboard_fab2(sch_1):page23_i172@chpset_lib.skx_ext_b(chips)!SKX_EXT_B_BGA1-IC,TBD!!!F99!DDR0_DQS_DP(4)!!!!
S!M_A_DQS_DP<5>!U5D1!N36!@baseboard_fab2_lib.baseboard_fab2(sch_1):page23_i172@chpset_lib.skx_ext_b(chips)!SKX_EXT_B_BGA1-IC,TBD!!!F99!DDR0_DQS_DP(5)!!!!
S!M_A_DQS_DP<6>!U5D1!N30!@baseboard_fab2_lib.baseboard_fab2(sch_1):page23_i172@chpset_lib.skx_ext_b(chips)!SKX_EXT_B_BGA1-IC,TBD!!!F99!DDR0_DQS_DP(6)!!!!
S!M_A_DQS_DP<7>!U5D1!R24!@baseboard_fab2_lib.baseboard_fab2(sch_1):page23_i172@chpset_lib.skx_ext_b(chips)!SKX_EXT_B_BGA1-IC,TBD!!!F99!DDR0_DQS_DP(7)!!!!
S!M_A_DQS_DP<8>!U5D1!AF67!@baseboard_fab2_lib.baseboard_fab2(sch_1):page23_i172@chpset_lib.skx_ext_b(chips)!SKX_EXT_B_BGA1-IC,TBD!!!F99!DDR0_DQS_DP(8)!!!!
S!M_A_DQS_DP<9>!U5D1!AM85!@baseboard_fab2_lib.baseboard_fab2(sch_1):page23_i172@chpset_lib.skx_ext_b(chips)!SKX_EXT_B_BGA1-IC,TBD!!!F99!DDR0_DQS_DP(9)!!!!
S!M_A_ECC<0>!U5D1!AC68!@baseboard_fab2_lib.baseboard_fab2(sch_1):page23_i172@chpset_lib.skx_ext_b(chips)!SKX_EXT_B_BGA1-IC,TBD!!!F99!DDR0_ECC(0)!!!!
S!M_A_ECC<1>!U5D1!AG68!@baseboard_fab2_lib.baseboard_fab2(sch_1):page23_i172@chpset_lib.skx_ext_b(chips)!SKX_EXT_B_BGA1-IC,TBD!!!F99!DDR0_ECC(1)!!!!
S!M_A_ECC<2>!U5D1!AD65!@baseboard_fab2_lib.baseboard_fab2(sch_1):page23_i172@chpset_lib.skx_ext_b(chips)!SKX_EXT_B_BGA1-IC,TBD!!!F99!DDR0_ECC(2)!!!!
S!M_A_ECC<3>!U5D1!AF65!@baseboard_fab2_lib.baseboard_fab2(sch_1):page23_i172@chpset_lib.skx_ext_b(chips)!SKX_EXT_B_BGA1-IC,TBD!!!F99!DDR0_ECC(3)!!!!
S!M_A_ECC<4>!U5D1!AD69!@baseboard_fab2_lib.baseboard_fab2(sch_1):page23_i172@chpset_lib.skx_ext_b(chips)!SKX_EXT_B_BGA1-IC,TBD!!!F99!DDR0_ECC(4)!!!!
S!M_A_ECC<5>!U5D1!AF69!@baseboard_fab2_lib.baseboard_fab2(sch_1):page23_i172@chpset_lib.skx_ext_b(chips)!SKX_EXT_B_BGA1-IC,TBD!!!F99!DDR0_ECC(5)!!!!
S!M_A_ECC<6>!U5D1!AC66!@baseboard_fab2_lib.baseboard_fab2(sch_1):page23_i172@chpset_lib.skx_ext_b(chips)!SKX_EXT_B_BGA1-IC,TBD!!!F99!DDR0_ECC(6)!!!!
S!M_A_ECC<7>!U5D1!AG66!@baseboard_fab2_lib.baseboard_fab2(sch_1):page23_i172@chpset_lib.skx_ext_b(chips)!SKX_EXT_B_BGA1-IC,TBD!!!F99!DDR0_ECC(7)!!!!
S!M_A_MA<0>!U5D1!F53!@baseboard_fab2_lib.baseboard_fab2(sch_1):page23_i172@chpset_lib.skx_ext_b(chips)!SKX_EXT_B_BGA1-IC,TBD!!!F99!DDR0_MA(0)!!!!
S!M_A_MA<10>!U5D1!J54!@baseboard_fab2_lib.baseboard_fab2(sch_1):page23_i172@chpset_lib.skx_ext_b(chips)!SKX_EXT_B_BGA1-IC,TBD!!!F99!DDR0_MA(10)!!!!
S!M_A_MA<11>!U5D1!G62!@baseboard_fab2_lib.baseboard_fab2(sch_1):page23_i172@chpset_lib.skx_ext_b(chips)!SKX_EXT_B_BGA1-IC,TBD!!!F99!DDR0_MA(11)!!!!
S!M_A_MA<12>!U5D1!J64!@baseboard_fab2_lib.baseboard_fab2(sch_1):page23_i172@chpset_lib.skx_ext_b(chips)!SKX_EXT_B_BGA1-IC,TBD!!!F99!DDR0_MA(12)!!!!
S!M_A_MA<13>!U5D1!J48!@baseboard_fab2_lib.baseboard_fab2(sch_1):page23_i172@chpset_lib.skx_ext_b(chips)!SKX_EXT_B_BGA1-IC,TBD!!!F99!DDR0_MA(13)!!!!
S!M_A_MA<14>!U5D1!F51!@baseboard_fab2_lib.baseboard_fab2(sch_1):page23_i172@chpset_lib.skx_ext_b(chips)!SKX_EXT_B_BGA1-IC,TBD!!!F99!DDR0_MA(14)!!!!
S!M_A_MA<15>!U5D1!K49!@baseboard_fab2_lib.baseboard_fab2(sch_1):page23_i172@chpset_lib.skx_ext_b(chips)!SKX_EXT_B_BGA1-IC,TBD!!!F99!DDR0_MA(15)!!!!
S!M_A_MA<16>!U5D1!D51!@baseboard_fab2_lib.baseboard_fab2(sch_1):page23_i172@chpset_lib.skx_ext_b(chips)!SKX_EXT_B_BGA1-IC,TBD!!!F99!DDR0_MA(16)!!!!
S!M_A_MA<17>!U5D1!K47!@baseboard_fab2_lib.baseboard_fab2(sch_1):page23_i172@chpset_lib.skx_ext_b(chips)!SKX_EXT_B_BGA1-IC,TBD!!!F99!DDR0_MA(17)!!!!
S!M_A_MA<1>!U5D1!F57!@baseboard_fab2_lib.baseboard_fab2(sch_1):page23_i172@chpset_lib.skx_ext_b(chips)!SKX_EXT_B_BGA1-IC,TBD!!!F99!DDR0_MA(1)!!!!
S!M_A_MA<2>!U5D1!D57!@baseboard_fab2_lib.baseboard_fab2(sch_1):page23_i172@chpset_lib.skx_ext_b(chips)!SKX_EXT_B_BGA1-IC,TBD!!!F99!DDR0_MA(2)!!!!
S!M_A_MA<3>!U5D1!C58!@baseboard_fab2_lib.baseboard_fab2(sch_1):page23_i172@chpset_lib.skx_ext_b(chips)!SKX_EXT_B_BGA1-IC,TBD!!!F99!DDR0_MA(3)!!!!
S!M_A_MA<4>!U5D1!G58!@baseboard_fab2_lib.baseboard_fab2(sch_1):page23_i172@chpset_lib.skx_ext_b(chips)!SKX_EXT_B_BGA1-IC,TBD!!!F99!DDR0_MA(4)!!!!
S!M_A_MA<5>!U5D1!F59!@baseboard_fab2_lib.baseboard_fab2(sch_1):page23_i172@chpset_lib.skx_ext_b(chips)!SKX_EXT_B_BGA1-IC,TBD!!!F99!DDR0_MA(5)!!!!
S!M_A_MA<6>!U5D1!D59!@baseboard_fab2_lib.baseboard_fab2(sch_1):page23_i172@chpset_lib.skx_ext_b(chips)!SKX_EXT_B_BGA1-IC,TBD!!!F99!DDR0_MA(6)!!!!
S!M_A_MA<7>!U5D1!G60!@baseboard_fab2_lib.baseboard_fab2(sch_1):page23_i172@chpset_lib.skx_ext_b(chips)!SKX_EXT_B_BGA1-IC,TBD!!!F99!DDR0_MA(7)!!!!
S!M_A_MA<8>!U5D1!C60!@baseboard_fab2_lib.baseboard_fab2(sch_1):page23_i172@chpset_lib.skx_ext_b(chips)!SKX_EXT_B_BGA1-IC,TBD!!!F99!DDR0_MA(8)!!!!
S!M_A_MA<9>!U5D1!F61!@baseboard_fab2_lib.baseboard_fab2(sch_1):page23_i172@chpset_lib.skx_ext_b(chips)!SKX_EXT_B_BGA1-IC,TBD!!!F99!DDR0_MA(9)!!!!
S!M_A_ODT<0>!U5D1!C50!@baseboard_fab2_lib.baseboard_fab2(sch_1):page23_i172@chpset_lib.skx_ext_b(chips)!SKX_EXT_B_BGA1-IC,TBD!!!F99!DDR0_ODT(0)!!!!
S!M_A_ODT<1>!U5D1!C48!@baseboard_fab2_lib.baseboard_fab2(sch_1):page23_i172@chpset_lib.skx_ext_b(chips)!SKX_EXT_B_BGA1-IC,TBD!!!F99!DDR0_ODT(1)!!!!
S!M_A_ODT<2>!U5D1!G50!@baseboard_fab2_lib.baseboard_fab2(sch_1):page23_i172@chpset_lib.skx_ext_b(chips)!SKX_EXT_B_BGA1-IC,TBD!!!F99!DDR0_ODT(2)!!!!
S!M_A_ODT<3>!U5D1!G48!@baseboard_fab2_lib.baseboard_fab2(sch_1):page23_i172@chpset_lib.skx_ext_b(chips)!SKX_EXT_B_BGA1-IC,TBD!!!F99!DDR0_ODT(3)!!!!
S!M_A_PAR!U5D1!D53!@baseboard_fab2_lib.baseboard_fab2(sch_1):page23_i172@chpset_lib.skx_ext_b(chips)!SKX_EXT_B_BGA1-IC,TBD!!!F99!DDR0_PAR!!!!
S!M_B_ACT_N!U5D1!T63!@baseboard_fab2_lib.baseboard_fab2(sch_1):page24_i172@chpset_lib.skx_ext_b(chips)!SKX_EXT_B_BGA1-IC,TBD!!!F98!DDR1_ACT_N!!!!
S!M_B_ALERT_N!U5D1!W62!@baseboard_fab2_lib.baseboard_fab2(sch_1):page24_i172@chpset_lib.skx_ext_b(chips)!SKX_EXT_B_BGA1-IC,TBD!!!F98!DDR1_ALERT_N!!!!
S!M_B_BA<0>!U5D1!T53!@baseboard_fab2_lib.baseboard_fab2(sch_1):page24_i172@chpset_lib.skx_ext_b(chips)!SKX_EXT_B_BGA1-IC,TBD!!!F98!DDR1_BA(0)!!!!
S!M_B_BA<1>!U5D1!K55!@baseboard_fab2_lib.baseboard_fab2(sch_1):page24_i172@chpset_lib.skx_ext_b(chips)!SKX_EXT_B_BGA1-IC,TBD!!!F98!DDR1_BA(1)!!!!
S!M_B_BG<0>!U5D1!M61!@baseboard_fab2_lib.baseboard_fab2(sch_1):page24_i172@chpset_lib.skx_ext_b(chips)!SKX_EXT_B_BGA1-IC,TBD!!!F98!DDR1_BG(0)!!!!
S!M_B_BG<1>!U5D1!N60!@baseboard_fab2_lib.baseboard_fab2(sch_1):page24_i172@chpset_lib.skx_ext_b(chips)!SKX_EXT_B_BGA1-IC,TBD!!!F98!DDR1_BG(1)!!!!
S!M_B_C<2>!U5D1!M47!@baseboard_fab2_lib.baseboard_fab2(sch_1):page24_i172@chpset_lib.skx_ext_b(chips)!SKX_EXT_B_BGA1-IC,TBD!!!F98!DDR1_CID(2)!!!!
S!M_B_CKE<0>!U5D1!N62!@baseboard_fab2_lib.baseboard_fab2(sch_1):page24_i172@chpset_lib.skx_ext_b(chips)!SKX_EXT_B_BGA1-IC,TBD!!!F98!DDR1_CKE(0)!!!!
S!M_B_CKE<1>!U5D1!R64!@baseboard_fab2_lib.baseboard_fab2(sch_1):page24_i172@chpset_lib.skx_ext_b(chips)!SKX_EXT_B_BGA1-IC,TBD!!!F98!DDR1_CKE(1)!!!!
S!M_B_CKE<2>!U5D1!K63!@baseboard_fab2_lib.baseboard_fab2(sch_1):page24_i172@chpset_lib.skx_ext_b(chips)!SKX_EXT_B_BGA1-IC,TBD!!!F98!DDR1_CKE(2)!!!!
S!M_B_CKE<3>!U5D1!L64!@baseboard_fab2_lib.baseboard_fab2(sch_1):page24_i172@chpset_lib.skx_ext_b(chips)!SKX_EXT_B_BGA1-IC,TBD!!!F98!DDR1_CKE(3)!!!!
S!M_B_CLK_DN<0>!U5D1!M53!@baseboard_fab2_lib.baseboard_fab2(sch_1):page24_i172@chpset_lib.skx_ext_b(chips)!SKX_EXT_B_BGA1-IC,TBD!!!F98!DDR1_CLK_DN(0)!!!!
S!M_B_CLK_DN<2>!U5D1!N56!@baseboard_fab2_lib.baseboard_fab2(sch_1):page24_i172@chpset_lib.skx_ext_b(chips)!SKX_EXT_B_BGA1-IC,TBD!!!F98!DDR1_CLK_DN(2)!!!!
S!M_B_CLK_DN<1>!U5D1!R54!@baseboard_fab2_lib.baseboard_fab2(sch_1):page24_i172@chpset_lib.skx_ext_b(chips)!SKX_EXT_B_BGA1-IC,TBD!!!F98!DDR1_CLK_DN(1)!!!!
S!M_B_CLK_DN<3>!U5D1!R56!@baseboard_fab2_lib.baseboard_fab2(sch_1):page24_i172@chpset_lib.skx_ext_b(chips)!SKX_EXT_B_BGA1-IC,TBD!!!F98!DDR1_CLK_DN(3)!!!!
S!M_B_CLK_DP<0>!U5D1!N54!@baseboard_fab2_lib.baseboard_fab2(sch_1):page24_i172@chpset_lib.skx_ext_b(chips)!SKX_EXT_B_BGA1-IC,TBD!!!F98!DDR1_CLK_DP(0)!!!!
S!M_B_CLK_DP<2>!U5D1!M57!@baseboard_fab2_lib.baseboard_fab2(sch_1):page24_i172@chpset_lib.skx_ext_b(chips)!SKX_EXT_B_BGA1-IC,TBD!!!F98!DDR1_CLK_DP(2)!!!!
S!M_B_CLK_DP<1>!U5D1!T55!@baseboard_fab2_lib.baseboard_fab2(sch_1):page24_i172@chpset_lib.skx_ext_b(chips)!SKX_EXT_B_BGA1-IC,TBD!!!F98!DDR1_CLK_DP(1)!!!!
S!M_B_CLK_DP<3>!U5D1!T57!@baseboard_fab2_lib.baseboard_fab2(sch_1):page24_i172@chpset_lib.skx_ext_b(chips)!SKX_EXT_B_BGA1-IC,TBD!!!F98!DDR1_CLK_DP(3)!!!!
S!M_B_CS_N<0>!U5D1!K51!@baseboard_fab2_lib.baseboard_fab2(sch_1):page24_i172@chpset_lib.skx_ext_b(chips)!SKX_EXT_B_BGA1-IC,TBD!!!F98!DDR1_CS_N(0)!!!!
S!M_B_CS_N<1>!U5D1!R50!@baseboard_fab2_lib.baseboard_fab2(sch_1):page24_i172@chpset_lib.skx_ext_b(chips)!SKX_EXT_B_BGA1-IC,TBD!!!F98!DDR1_CS_N(1)!!!!
S!M_B_CS_N<2>!U5D1!N46!@baseboard_fab2_lib.baseboard_fab2(sch_1):page24_i172@chpset_lib.skx_ext_b(chips)!SKX_EXT_B_BGA1-IC,TBD!!!F98!DDR1_CS_N(2)!!!!
S!M_B_CS_N<3>!U5D1!V47!@baseboard_fab2_lib.baseboard_fab2(sch_1):page24_i172@chpset_lib.skx_ext_b(chips)!SKX_EXT_B_BGA1-IC,TBD!!!F98!DDR1_CS_N(3)!!!!
S!M_B_CS_N<4>!U5D1!J50!@baseboard_fab2_lib.baseboard_fab2(sch_1):page24_i172@chpset_lib.skx_ext_b(chips)!SKX_EXT_B_BGA1-IC,TBD!!!F98!DDR1_CS_N(4)!!!!
S!M_B_CS_N<5>!U5D1!T49!@baseboard_fab2_lib.baseboard_fab2(sch_1):page24_i172@chpset_lib.skx_ext_b(chips)!SKX_EXT_B_BGA1-IC,TBD!!!F98!DDR1_CS_N(5)!!!!
S!M_B_CS_N<6>!U5D1!M45!@baseboard_fab2_lib.baseboard_fab2(sch_1):page24_i172@chpset_lib.skx_ext_b(chips)!SKX_EXT_B_BGA1-IC,TBD!!!F98!DDR1_CS_N(6)!!!!
S!M_B_CS_N<7>!U5D1!R46!@baseboard_fab2_lib.baseboard_fab2(sch_1):page24_i172@chpset_lib.skx_ext_b(chips)!SKX_EXT_B_BGA1-IC,TBD!!!F98!DDR1_CS_N(7)!!!!
S!M_B_DQ<0>!U5D1!AV81!@baseboard_fab2_lib.baseboard_fab2(sch_1):page24_i172@chpset_lib.skx_ext_b(chips)!SKX_EXT_B_BGA1-IC,TBD!!!F98!DDR1_DQ(0)!!!!
S!M_B_DQ<10>!U5D1!AC82!@baseboard_fab2_lib.baseboard_fab2(sch_1):page24_i172@chpset_lib.skx_ext_b(chips)!SKX_EXT_B_BGA1-IC,TBD!!!F98!DDR1_DQ(10)!!!!
S!M_B_DQ<11>!U5D1!AB81!@baseboard_fab2_lib.baseboard_fab2(sch_1):page24_i172@chpset_lib.skx_ext_b(chips)!SKX_EXT_B_BGA1-IC,TBD!!!F98!DDR1_DQ(11)!!!!
S!M_B_DQ<12>!U5D1!AJ80!@baseboard_fab2_lib.baseboard_fab2(sch_1):page24_i172@chpset_lib.skx_ext_b(chips)!SKX_EXT_B_BGA1-IC,TBD!!!F98!DDR1_DQ(12)!!!!
S!M_B_DQ<13>!U5D1!AH79!@baseboard_fab2_lib.baseboard_fab2(sch_1):page24_i172@chpset_lib.skx_ext_b(chips)!SKX_EXT_B_BGA1-IC,TBD!!!F98!DDR1_DQ(13)!!!!
S!M_B_DQ<14>!U5D1!AE82!@baseboard_fab2_lib.baseboard_fab2(sch_1):page24_i172@chpset_lib.skx_ext_b(chips)!SKX_EXT_B_BGA1-IC,TBD!!!F98!DDR1_DQ(14)!!!!
S!M_B_DQ<15>!U5D1!AC80!@baseboard_fab2_lib.baseboard_fab2(sch_1):page24_i172@chpset_lib.skx_ext_b(chips)!SKX_EXT_B_BGA1-IC,TBD!!!F98!DDR1_DQ(15)!!!!
S!M_B_DQ<16>!U5D1!E80!@baseboard_fab2_lib.baseboard_fab2(sch_1):page24_i172@chpset_lib.skx_ext_b(chips)!SKX_EXT_B_BGA1-IC,TBD!!!F98!DDR1_DQ(16)!!!!
S!M_B_DQ<17>!U5D1!J80!@baseboard_fab2_lib.baseboard_fab2(sch_1):page24_i172@chpset_lib.skx_ext_b(chips)!SKX_EXT_B_BGA1-IC,TBD!!!F98!DDR1_DQ(17)!!!!
S!M_B_DQ<18>!U5D1!F77!@baseboard_fab2_lib.baseboard_fab2(sch_1):page24_i172@chpset_lib.skx_ext_b(chips)!SKX_EXT_B_BGA1-IC,TBD!!!F98!DDR1_DQ(18)!!!!
S!M_B_DQ<19>!U5D1!H77!@baseboard_fab2_lib.baseboard_fab2(sch_1):page24_i172@chpset_lib.skx_ext_b(chips)!SKX_EXT_B_BGA1-IC,TBD!!!F98!DDR1_DQ(19)!!!!
S!M_B_DQ<1>!U5D1!AT79!@baseboard_fab2_lib.baseboard_fab2(sch_1):page24_i172@chpset_lib.skx_ext_b(chips)!SKX_EXT_B_BGA1-IC,TBD!!!F98!DDR1_DQ(1)!!!!
S!M_B_DQ<20>!U5D1!F81!@baseboard_fab2_lib.baseboard_fab2(sch_1):page24_i172@chpset_lib.skx_ext_b(chips)!SKX_EXT_B_BGA1-IC,TBD!!!F98!DDR1_DQ(20)!!!!
S!M_B_DQ<21>!U5D1!H81!@baseboard_fab2_lib.baseboard_fab2(sch_1):page24_i172@chpset_lib.skx_ext_b(chips)!SKX_EXT_B_BGA1-IC,TBD!!!F98!DDR1_DQ(21)!!!!
S!M_B_DQ<22>!U5D1!E78!@baseboard_fab2_lib.baseboard_fab2(sch_1):page24_i172@chpset_lib.skx_ext_b(chips)!SKX_EXT_B_BGA1-IC,TBD!!!F98!DDR1_DQ(22)!!!!
S!M_B_DQ<23>!U5D1!J78!@baseboard_fab2_lib.baseboard_fab2(sch_1):page24_i172@chpset_lib.skx_ext_b(chips)!SKX_EXT_B_BGA1-IC,TBD!!!F98!DDR1_DQ(23)!!!!
S!M_B_DQ<24>!U5D1!D75!@baseboard_fab2_lib.baseboard_fab2(sch_1):page24_i172@chpset_lib.skx_ext_b(chips)!SKX_EXT_B_BGA1-IC,TBD!!!F98!DDR1_DQ(24)!!!!
S!M_B_DQ<25>!U5D1!C74!@baseboard_fab2_lib.baseboard_fab2(sch_1):page24_i172@chpset_lib.skx_ext_b(chips)!SKX_EXT_B_BGA1-IC,TBD!!!F98!DDR1_DQ(25)!!!!
S!M_B_DQ<26>!U5D1!D71!@baseboard_fab2_lib.baseboard_fab2(sch_1):page24_i172@chpset_lib.skx_ext_b(chips)!SKX_EXT_B_BGA1-IC,TBD!!!F98!DDR1_DQ(26)!!!!
S!M_B_DQ<27>!U5D1!F71!@baseboard_fab2_lib.baseboard_fab2(sch_1):page24_i172@chpset_lib.skx_ext_b(chips)!SKX_EXT_B_BGA1-IC,TBD!!!F98!DDR1_DQ(27)!!!!
S!M_B_DQ<28>!U5D1!F75!@baseboard_fab2_lib.baseboard_fab2(sch_1):page24_i172@chpset_lib.skx_ext_b(chips)!SKX_EXT_B_BGA1-IC,TBD!!!F98!DDR1_DQ(28)!!!!
S!M_B_DQ<29>!U5D1!G74!@baseboard_fab2_lib.baseboard_fab2(sch_1):page24_i172@chpset_lib.skx_ext_b(chips)!SKX_EXT_B_BGA1-IC,TBD!!!F98!DDR1_DQ(29)!!!!
S!M_B_DQ<2>!U5D1!AN82!@baseboard_fab2_lib.baseboard_fab2(sch_1):page24_i172@chpset_lib.skx_ext_b(chips)!SKX_EXT_B_BGA1-IC,TBD!!!F98!DDR1_DQ(2)!!!!
S!M_B_DQ<30>!U5D1!C72!@baseboard_fab2_lib.baseboard_fab2(sch_1):page24_i172@chpset_lib.skx_ext_b(chips)!SKX_EXT_B_BGA1-IC,TBD!!!F98!DDR1_DQ(30)!!!!
S!M_B_DQ<31>!U5D1!G72!@baseboard_fab2_lib.baseboard_fab2(sch_1):page24_i172@chpset_lib.skx_ext_b(chips)!SKX_EXT_B_BGA1-IC,TBD!!!F98!DDR1_DQ(31)!!!!
S!M_B_DQ<32>!U5D1!K43!@baseboard_fab2_lib.baseboard_fab2(sch_1):page24_i172@chpset_lib.skx_ext_b(chips)!SKX_EXT_B_BGA1-IC,TBD!!!F98!DDR1_DQ(32)!!!!
S!M_B_DQ<33>!U5D1!H43!@baseboard_fab2_lib.baseboard_fab2(sch_1):page24_i172@chpset_lib.skx_ext_b(chips)!SKX_EXT_B_BGA1-IC,TBD!!!F98!DDR1_DQ(33)!!!!
S!M_B_DQ<34>!U5D1!L40!@baseboard_fab2_lib.baseboard_fab2(sch_1):page24_i172@chpset_lib.skx_ext_b(chips)!SKX_EXT_B_BGA1-IC,TBD!!!F98!DDR1_DQ(34)!!!!
S!M_B_DQ<35>!U5D1!N40!@baseboard_fab2_lib.baseboard_fab2(sch_1):page24_i172@chpset_lib.skx_ext_b(chips)!SKX_EXT_B_BGA1-IC,TBD!!!F98!DDR1_DQ(35)!!!!
S!M_B_DQ<36>!U5D1!P43!@baseboard_fab2_lib.baseboard_fab2(sch_1):page24_i172@chpset_lib.skx_ext_b(chips)!SKX_EXT_B_BGA1-IC,TBD!!!F98!DDR1_DQ(36)!!!!
S!M_B_DQ<37>!U5D1!T43!@baseboard_fab2_lib.baseboard_fab2(sch_1):page24_i172@chpset_lib.skx_ext_b(chips)!SKX_EXT_B_BGA1-IC,TBD!!!F98!DDR1_DQ(37)!!!!
S!M_B_DQ<38>!U5D1!K41!@baseboard_fab2_lib.baseboard_fab2(sch_1):page24_i172@chpset_lib.skx_ext_b(chips)!SKX_EXT_B_BGA1-IC,TBD!!!F98!DDR1_DQ(38)!!!!
S!M_B_DQ<39>!U5D1!P41!@baseboard_fab2_lib.baseboard_fab2(sch_1):page24_i172@chpset_lib.skx_ext_b(chips)!SKX_EXT_B_BGA1-IC,TBD!!!F98!DDR1_DQ(39)!!!!
S!M_B_DQ<3>!U5D1!AM81!@baseboard_fab2_lib.baseboard_fab2(sch_1):page24_i172@chpset_lib.skx_ext_b(chips)!SKX_EXT_B_BGA1-IC,TBD!!!F98!DDR1_DQ(3)!!!!
S!M_B_DQ<40>!U5D1!C36!@baseboard_fab2_lib.baseboard_fab2(sch_1):page24_i172@chpset_lib.skx_ext_b(chips)!SKX_EXT_B_BGA1-IC,TBD!!!F98!DDR1_DQ(40)!!!!
S!M_B_DQ<41>!U5D1!B35!@baseboard_fab2_lib.baseboard_fab2(sch_1):page24_i172@chpset_lib.skx_ext_b(chips)!SKX_EXT_B_BGA1-IC,TBD!!!F98!DDR1_DQ(41)!!!!
S!M_B_DQ<42>!U5D1!C32!@baseboard_fab2_lib.baseboard_fab2(sch_1):page24_i172@chpset_lib.skx_ext_b(chips)!SKX_EXT_B_BGA1-IC,TBD!!!F98!DDR1_DQ(42)!!!!
S!M_B_DQ<43>!U5D1!E32!@baseboard_fab2_lib.baseboard_fab2(sch_1):page24_i172@chpset_lib.skx_ext_b(chips)!SKX_EXT_B_BGA1-IC,TBD!!!F98!DDR1_DQ(43)!!!!
S!M_B_DQ<44>!U5D1!E36!@baseboard_fab2_lib.baseboard_fab2(sch_1):page24_i172@chpset_lib.skx_ext_b(chips)!SKX_EXT_B_BGA1-IC,TBD!!!F98!DDR1_DQ(44)!!!!
S!M_B_DQ<45>!U5D1!F35!@baseboard_fab2_lib.baseboard_fab2(sch_1):page24_i172@chpset_lib.skx_ext_b(chips)!SKX_EXT_B_BGA1-IC,TBD!!!F98!DDR1_DQ(45)!!!!
S!M_B_DQ<46>!U5D1!B33!@baseboard_fab2_lib.baseboard_fab2(sch_1):page24_i172@chpset_lib.skx_ext_b(chips)!SKX_EXT_B_BGA1-IC,TBD!!!F98!DDR1_DQ(46)!!!!
S!M_B_DQ<47>!U5D1!F33!@baseboard_fab2_lib.baseboard_fab2(sch_1):page24_i172@chpset_lib.skx_ext_b(chips)!SKX_EXT_B_BGA1-IC,TBD!!!F98!DDR1_DQ(47)!!!!
S!M_B_DQ<48>!U5D1!C30!@baseboard_fab2_lib.baseboard_fab2(sch_1):page24_i172@chpset_lib.skx_ext_b(chips)!SKX_EXT_B_BGA1-IC,TBD!!!F98!DDR1_DQ(48)!!!!
S!M_B_DQ<49>!U5D1!B29!@baseboard_fab2_lib.baseboard_fab2(sch_1):page24_i172@chpset_lib.skx_ext_b(chips)!SKX_EXT_B_BGA1-IC,TBD!!!F98!DDR1_DQ(49)!!!!
S!M_B_DQ<4>!U5D1!AW80!@baseboard_fab2_lib.baseboard_fab2(sch_1):page24_i172@chpset_lib.skx_ext_b(chips)!SKX_EXT_B_BGA1-IC,TBD!!!F98!DDR1_DQ(4)!!!!
S!M_B_DQ<50>!U5D1!C26!@baseboard_fab2_lib.baseboard_fab2(sch_1):page24_i172@chpset_lib.skx_ext_b(chips)!SKX_EXT_B_BGA1-IC,TBD!!!F98!DDR1_DQ(50)!!!!
S!M_B_DQ<51>!U5D1!E26!@baseboard_fab2_lib.baseboard_fab2(sch_1):page24_i172@chpset_lib.skx_ext_b(chips)!SKX_EXT_B_BGA1-IC,TBD!!!F98!DDR1_DQ(51)!!!!
S!M_B_DQ<52>!U5D1!E30!@baseboard_fab2_lib.baseboard_fab2(sch_1):page24_i172@chpset_lib.skx_ext_b(chips)!SKX_EXT_B_BGA1-IC,TBD!!!F98!DDR1_DQ(52)!!!!
S!M_B_DQ<53>!U5D1!F29!@baseboard_fab2_lib.baseboard_fab2(sch_1):page24_i172@chpset_lib.skx_ext_b(chips)!SKX_EXT_B_BGA1-IC,TBD!!!F98!DDR1_DQ(53)!!!!
S!M_B_DQ<54>!U5D1!B27!@baseboard_fab2_lib.baseboard_fab2(sch_1):page24_i172@chpset_lib.skx_ext_b(chips)!SKX_EXT_B_BGA1-IC,TBD!!!F98!DDR1_DQ(54)!!!!
S!M_B_DQ<55>!U5D1!F27!@baseboard_fab2_lib.baseboard_fab2(sch_1):page24_i172@chpset_lib.skx_ext_b(chips)!SKX_EXT_B_BGA1-IC,TBD!!!F98!DDR1_DQ(55)!!!!
S!M_B_DQ<56>!U5D1!U28!@baseboard_fab2_lib.baseboard_fab2(sch_1):page24_i172@chpset_lib.skx_ext_b(chips)!SKX_EXT_B_BGA1-IC,TBD!!!F98!DDR1_DQ(56)!!!!
S!M_B_DQ<57>!U5D1!AA28!@baseboard_fab2_lib.baseboard_fab2(sch_1):page24_i172@chpset_lib.skx_ext_b(chips)!SKX_EXT_B_BGA1-IC,TBD!!!F98!DDR1_DQ(57)!!!!
S!M_B_DQ<58>!U5D1!V25!@baseboard_fab2_lib.baseboard_fab2(sch_1):page24_i172@chpset_lib.skx_ext_b(chips)!SKX_EXT_B_BGA1-IC,TBD!!!F98!DDR1_DQ(58)!!!!
S!M_B_DQ<59>!U5D1!Y25!@baseboard_fab2_lib.baseboard_fab2(sch_1):page24_i172@chpset_lib.skx_ext_b(chips)!SKX_EXT_B_BGA1-IC,TBD!!!F98!DDR1_DQ(59)!!!!
S!M_B_DQ<5>!U5D1!AV79!@baseboard_fab2_lib.baseboard_fab2(sch_1):page24_i172@chpset_lib.skx_ext_b(chips)!SKX_EXT_B_BGA1-IC,TBD!!!F98!DDR1_DQ(5)!!!!
S!M_B_DQ<60>!U5D1!V29!@baseboard_fab2_lib.baseboard_fab2(sch_1):page24_i172@chpset_lib.skx_ext_b(chips)!SKX_EXT_B_BGA1-IC,TBD!!!F98!DDR1_DQ(60)!!!!
S!M_B_DQ<61>!U5D1!Y29!@baseboard_fab2_lib.baseboard_fab2(sch_1):page24_i172@chpset_lib.skx_ext_b(chips)!SKX_EXT_B_BGA1-IC,TBD!!!F98!DDR1_DQ(61)!!!!
S!M_B_DQ<62>!U5D1!U26!@baseboard_fab2_lib.baseboard_fab2(sch_1):page24_i172@chpset_lib.skx_ext_b(chips)!SKX_EXT_B_BGA1-IC,TBD!!!F98!DDR1_DQ(62)!!!!
S!M_B_DQ<63>!U5D1!AA26!@baseboard_fab2_lib.baseboard_fab2(sch_1):page24_i172@chpset_lib.skx_ext_b(chips)!SKX_EXT_B_BGA1-IC,TBD!!!F98!DDR1_DQ(63)!!!!
S!M_B_DQ<6>!U5D1!AR82!@baseboard_fab2_lib.baseboard_fab2(sch_1):page24_i172@chpset_lib.skx_ext_b(chips)!SKX_EXT_B_BGA1-IC,TBD!!!F98!DDR1_DQ(6)!!!!
S!M_B_DQ<7>!U5D1!AN80!@baseboard_fab2_lib.baseboard_fab2(sch_1):page24_i172@chpset_lib.skx_ext_b(chips)!SKX_EXT_B_BGA1-IC,TBD!!!F98!DDR1_DQ(7)!!!!
S!M_B_DQ<8>!U5D1!AH81!@baseboard_fab2_lib.baseboard_fab2(sch_1):page24_i172@chpset_lib.skx_ext_b(chips)!SKX_EXT_B_BGA1-IC,TBD!!!F98!DDR1_DQ(8)!!!!
S!M_B_DQ<9>!U5D1!AF79!@baseboard_fab2_lib.baseboard_fab2(sch_1):page24_i172@chpset_lib.skx_ext_b(chips)!SKX_EXT_B_BGA1-IC,TBD!!!F98!DDR1_DQ(9)!!!!
S!M_B_DQS_DN<0>!U5D1!AP79!@baseboard_fab2_lib.baseboard_fab2(sch_1):page24_i172@chpset_lib.skx_ext_b(chips)!SKX_EXT_B_BGA1-IC,TBD!!!F98!DDR1_DQS_DN(0)!!!!
S!M_B_DQS_DN<10>!U5D1!AG82!@baseboard_fab2_lib.baseboard_fab2(sch_1):page24_i172@chpset_lib.skx_ext_b(chips)!SKX_EXT_B_BGA1-IC,TBD!!!F98!DDR1_DQS_DN(10)!!!!
S!M_B_DQS_DN<11>!U5D1!D79!@baseboard_fab2_lib.baseboard_fab2(sch_1):page24_i172@chpset_lib.skx_ext_b(chips)!SKX_EXT_B_BGA1-IC,TBD!!!F98!DDR1_DQS_DN(11)!!!!
S!M_B_DQS_DN<12>!U5D1!B73!@baseboard_fab2_lib.baseboard_fab2(sch_1):page24_i172@chpset_lib.skx_ext_b(chips)!SKX_EXT_B_BGA1-IC,TBD!!!F98!DDR1_DQS_DN(12)!!!!
S!M_B_DQS_DN<13>!U5D1!J42!@baseboard_fab2_lib.baseboard_fab2(sch_1):page24_i172@chpset_lib.skx_ext_b(chips)!SKX_EXT_B_BGA1-IC,TBD!!!F98!DDR1_DQS_DN(13)!!!!
S!M_B_DQS_DN<14>!U5D1!A34!@baseboard_fab2_lib.baseboard_fab2(sch_1):page24_i172@chpset_lib.skx_ext_b(chips)!SKX_EXT_B_BGA1-IC,TBD!!!F98!DDR1_DQS_DN(14)!!!!
S!M_B_DQS_DN<15>!U5D1!A28!@baseboard_fab2_lib.baseboard_fab2(sch_1):page24_i172@chpset_lib.skx_ext_b(chips)!SKX_EXT_B_BGA1-IC,TBD!!!F98!DDR1_DQS_DN(15)!!!!
S!M_B_DQS_DN<16>!U5D1!T27!@baseboard_fab2_lib.baseboard_fab2(sch_1):page24_i172@chpset_lib.skx_ext_b(chips)!SKX_EXT_B_BGA1-IC,TBD!!!F98!DDR1_DQS_DN(16)!!!!
S!M_B_DQS_DN<17>!U5D1!G68!@baseboard_fab2_lib.baseboard_fab2(sch_1):page24_i172@chpset_lib.skx_ext_b(chips)!SKX_EXT_B_BGA1-IC,TBD!!!F98!DDR1_DQS_DN(17)!!!!
S!M_B_DQS_DN<1>!U5D1!AD79!@baseboard_fab2_lib.baseboard_fab2(sch_1):page24_i172@chpset_lib.skx_ext_b(chips)!SKX_EXT_B_BGA1-IC,TBD!!!F98!DDR1_DQS_DN(1)!!!!
S!M_B_DQS_DN<2>!U5D1!K79!@baseboard_fab2_lib.baseboard_fab2(sch_1):page24_i172@chpset_lib.skx_ext_b(chips)!SKX_EXT_B_BGA1-IC,TBD!!!F98!DDR1_DQS_DN(2)!!!!
S!M_B_DQS_DN<3>!U5D1!H73!@baseboard_fab2_lib.baseboard_fab2(sch_1):page24_i172@chpset_lib.skx_ext_b(chips)!SKX_EXT_B_BGA1-IC,TBD!!!F98!DDR1_DQS_DN(3)!!!!
S!M_B_DQS_DN<4>!U5D1!N42!@baseboard_fab2_lib.baseboard_fab2(sch_1):page24_i172@chpset_lib.skx_ext_b(chips)!SKX_EXT_B_BGA1-IC,TBD!!!F98!DDR1_DQS_DN(4)!!!!
S!M_B_DQS_DN<5>!U5D1!G34!@baseboard_fab2_lib.baseboard_fab2(sch_1):page24_i172@chpset_lib.skx_ext_b(chips)!SKX_EXT_B_BGA1-IC,TBD!!!F98!DDR1_DQS_DN(5)!!!!
S!M_B_DQS_DN<6>!U5D1!G28!@baseboard_fab2_lib.baseboard_fab2(sch_1):page24_i172@chpset_lib.skx_ext_b(chips)!SKX_EXT_B_BGA1-IC,TBD!!!F98!DDR1_DQS_DN(6)!!!!
S!M_B_DQS_DN<7>!U5D1!AB27!@baseboard_fab2_lib.baseboard_fab2(sch_1):page24_i172@chpset_lib.skx_ext_b(chips)!SKX_EXT_B_BGA1-IC,TBD!!!F98!DDR1_DQS_DN(7)!!!!
S!M_B_DQS_DN<8>!U5D1!N68!@baseboard_fab2_lib.baseboard_fab2(sch_1):page24_i172@chpset_lib.skx_ext_b(chips)!SKX_EXT_B_BGA1-IC,TBD!!!F98!DDR1_DQS_DN(8)!!!!
S!M_B_DQS_DN<9>!U5D1!AU82!@baseboard_fab2_lib.baseboard_fab2(sch_1):page24_i172@chpset_lib.skx_ext_b(chips)!SKX_EXT_B_BGA1-IC,TBD!!!F98!DDR1_DQS_DN(9)!!!!
S!M_B_DQS_DP<0>!U5D1!AR80!@baseboard_fab2_lib.baseboard_fab2(sch_1):page24_i172@chpset_lib.skx_ext_b(chips)!SKX_EXT_B_BGA1-IC,TBD!!!F98!DDR1_DQS_DP(0)!!!!
S!M_B_DQS_DP<10>!U5D1!AF81!@baseboard_fab2_lib.baseboard_fab2(sch_1):page24_i172@chpset_lib.skx_ext_b(chips)!SKX_EXT_B_BGA1-IC,TBD!!!F98!DDR1_DQS_DP(10)!!!!
S!M_B_DQS_DP<11>!U5D1!F79!@baseboard_fab2_lib.baseboard_fab2(sch_1):page24_i172@chpset_lib.skx_ext_b(chips)!SKX_EXT_B_BGA1-IC,TBD!!!F98!DDR1_DQS_DP(11)!!!!
S!M_B_DQS_DP<12>!U5D1!D73!@baseboard_fab2_lib.baseboard_fab2(sch_1):page24_i172@chpset_lib.skx_ext_b(chips)!SKX_EXT_B_BGA1-IC,TBD!!!F98!DDR1_DQS_DP(12)!!!!
S!M_B_DQS_DP<13>!U5D1!L42!@baseboard_fab2_lib.baseboard_fab2(sch_1):page24_i172@chpset_lib.skx_ext_b(chips)!SKX_EXT_B_BGA1-IC,TBD!!!F98!DDR1_DQS_DP(13)!!!!
S!M_B_DQS_DP<14>!U5D1!C34!@baseboard_fab2_lib.baseboard_fab2(sch_1):page24_i172@chpset_lib.skx_ext_b(chips)!SKX_EXT_B_BGA1-IC,TBD!!!F98!DDR1_DQS_DP(14)!!!!
S!M_B_DQS_DP<15>!U5D1!C28!@baseboard_fab2_lib.baseboard_fab2(sch_1):page24_i172@chpset_lib.skx_ext_b(chips)!SKX_EXT_B_BGA1-IC,TBD!!!F98!DDR1_DQS_DP(15)!!!!
S!M_B_DQS_DP<16>!U5D1!V27!@baseboard_fab2_lib.baseboard_fab2(sch_1):page24_i172@chpset_lib.skx_ext_b(chips)!SKX_EXT_B_BGA1-IC,TBD!!!F98!DDR1_DQS_DP(16)!!!!
S!M_B_DQS_DP<17>!U5D1!J68!@baseboard_fab2_lib.baseboard_fab2(sch_1):page24_i172@chpset_lib.skx_ext_b(chips)!SKX_EXT_B_BGA1-IC,TBD!!!F98!DDR1_DQS_DP(17)!!!!
S!M_B_DQS_DP<1>!U5D1!AE80!@baseboard_fab2_lib.baseboard_fab2(sch_1):page24_i172@chpset_lib.skx_ext_b(chips)!SKX_EXT_B_BGA1-IC,TBD!!!F98!DDR1_DQS_DP(1)!!!!
S!M_B_DQS_DP<2>!U5D1!H79!@baseboard_fab2_lib.baseboard_fab2(sch_1):page24_i172@chpset_lib.skx_ext_b(chips)!SKX_EXT_B_BGA1-IC,TBD!!!F98!DDR1_DQS_DP(2)!!!!
S!M_B_DQS_DP<3>!U5D1!F73!@baseboard_fab2_lib.baseboard_fab2(sch_1):page24_i172@chpset_lib.skx_ext_b(chips)!SKX_EXT_B_BGA1-IC,TBD!!!F98!DDR1_DQS_DP(3)!!!!
S!M_B_DQS_DP<4>!U5D1!R42!@baseboard_fab2_lib.baseboard_fab2(sch_1):page24_i172@chpset_lib.skx_ext_b(chips)!SKX_EXT_B_BGA1-IC,TBD!!!F98!DDR1_DQS_DP(4)!!!!
S!M_B_DQS_DP<5>!U5D1!E34!@baseboard_fab2_lib.baseboard_fab2(sch_1):page24_i172@chpset_lib.skx_ext_b(chips)!SKX_EXT_B_BGA1-IC,TBD!!!F98!DDR1_DQS_DP(5)!!!!
S!M_B_DQS_DP<6>!U5D1!E28!@baseboard_fab2_lib.baseboard_fab2(sch_1):page24_i172@chpset_lib.skx_ext_b(chips)!SKX_EXT_B_BGA1-IC,TBD!!!F98!DDR1_DQS_DP(6)!!!!
S!M_B_DQS_DP<7>!U5D1!Y27!@baseboard_fab2_lib.baseboard_fab2(sch_1):page24_i172@chpset_lib.skx_ext_b(chips)!SKX_EXT_B_BGA1-IC,TBD!!!F98!DDR1_DQS_DP(7)!!!!
S!M_B_DQS_DP<8>!U5D1!L68!@baseboard_fab2_lib.baseboard_fab2(sch_1):page24_i172@chpset_lib.skx_ext_b(chips)!SKX_EXT_B_BGA1-IC,TBD!!!F98!DDR1_DQS_DP(8)!!!!
S!M_B_DQS_DP<9>!U5D1!AT81!@baseboard_fab2_lib.baseboard_fab2(sch_1):page24_i172@chpset_lib.skx_ext_b(chips)!SKX_EXT_B_BGA1-IC,TBD!!!F98!DDR1_DQS_DP(9)!!!!
S!M_B_ECC<0>!U5D1!J70!@baseboard_fab2_lib.baseboard_fab2(sch_1):page24_i172@chpset_lib.skx_ext_b(chips)!SKX_EXT_B_BGA1-IC,TBD!!!F98!DDR1_ECC(0)!!!!
S!M_B_ECC<1>!U5D1!H69!@baseboard_fab2_lib.baseboard_fab2(sch_1):page24_i172@chpset_lib.skx_ext_b(chips)!SKX_EXT_B_BGA1-IC,TBD!!!F98!DDR1_ECC(1)!!!!
S!M_B_ECC<2>!U5D1!J66!@baseboard_fab2_lib.baseboard_fab2(sch_1):page24_i172@chpset_lib.skx_ext_b(chips)!SKX_EXT_B_BGA1-IC,TBD!!!F98!DDR1_ECC(2)!!!!
S!M_B_ECC<3>!U5D1!L66!@baseboard_fab2_lib.baseboard_fab2(sch_1):page24_i172@chpset_lib.skx_ext_b(chips)!SKX_EXT_B_BGA1-IC,TBD!!!F98!DDR1_ECC(3)!!!!
S!M_B_ECC<4>!U5D1!L70!@baseboard_fab2_lib.baseboard_fab2(sch_1):page24_i172@chpset_lib.skx_ext_b(chips)!SKX_EXT_B_BGA1-IC,TBD!!!F98!DDR1_ECC(4)!!!!
S!M_B_ECC<5>!U5D1!M69!@baseboard_fab2_lib.baseboard_fab2(sch_1):page24_i172@chpset_lib.skx_ext_b(chips)!SKX_EXT_B_BGA1-IC,TBD!!!F98!DDR1_ECC(5)!!!!
S!M_B_ECC<6>!U5D1!H67!@baseboard_fab2_lib.baseboard_fab2(sch_1):page24_i172@chpset_lib.skx_ext_b(chips)!SKX_EXT_B_BGA1-IC,TBD!!!F98!DDR1_ECC(6)!!!!
S!M_B_ECC<7>!U5D1!M67!@baseboard_fab2_lib.baseboard_fab2(sch_1):page24_i172@chpset_lib.skx_ext_b(chips)!SKX_EXT_B_BGA1-IC,TBD!!!F98!DDR1_ECC(7)!!!!
S!M_B_MA<0>!U5D1!J52!@baseboard_fab2_lib.baseboard_fab2(sch_1):page24_i172@chpset_lib.skx_ext_b(chips)!SKX_EXT_B_BGA1-IC,TBD!!!F98!DDR1_MA(0)!!!!
S!M_B_MA<10>!U5D1!M55!@baseboard_fab2_lib.baseboard_fab2(sch_1):page24_i172@chpset_lib.skx_ext_b(chips)!SKX_EXT_B_BGA1-IC,TBD!!!F98!DDR1_MA(10)!!!!
S!M_B_MA<11>!U5D1!R60!@baseboard_fab2_lib.baseboard_fab2(sch_1):page24_i172@chpset_lib.skx_ext_b(chips)!SKX_EXT_B_BGA1-IC,TBD!!!F98!DDR1_MA(11)!!!!
S!M_B_MA<12>!U5D1!T61!@baseboard_fab2_lib.baseboard_fab2(sch_1):page24_i172@chpset_lib.skx_ext_b(chips)!SKX_EXT_B_BGA1-IC,TBD!!!F98!DDR1_MA(12)!!!!
S!M_B_MA<13>!U5D1!M51!@baseboard_fab2_lib.baseboard_fab2(sch_1):page24_i172@chpset_lib.skx_ext_b(chips)!SKX_EXT_B_BGA1-IC,TBD!!!F98!DDR1_MA(13)!!!!
S!M_B_MA<14>!U5D1!T51!@baseboard_fab2_lib.baseboard_fab2(sch_1):page24_i172@chpset_lib.skx_ext_b(chips)!SKX_EXT_B_BGA1-IC,TBD!!!F98!DDR1_MA(14)!!!!
S!M_B_MA<15>!U5D1!N52!@baseboard_fab2_lib.baseboard_fab2(sch_1):page24_i172@chpset_lib.skx_ext_b(chips)!SKX_EXT_B_BGA1-IC,TBD!!!F98!DDR1_MA(15)!!!!
S!M_B_MA<16>!U5D1!R52!@baseboard_fab2_lib.baseboard_fab2(sch_1):page24_i172@chpset_lib.skx_ext_b(chips)!SKX_EXT_B_BGA1-IC,TBD!!!F98!DDR1_MA(16)!!!!
S!M_B_MA<17>!U5D1!N48!@baseboard_fab2_lib.baseboard_fab2(sch_1):page24_i172@chpset_lib.skx_ext_b(chips)!SKX_EXT_B_BGA1-IC,TBD!!!F98!DDR1_MA(17)!!!!
S!M_B_MA<1>!U5D1!J58!@baseboard_fab2_lib.baseboard_fab2(sch_1):page24_i172@chpset_lib.skx_ext_b(chips)!SKX_EXT_B_BGA1-IC,TBD!!!F98!DDR1_MA(1)!!!!
S!M_B_MA<2>!U5D1!K57!@baseboard_fab2_lib.baseboard_fab2(sch_1):page24_i172@chpset_lib.skx_ext_b(chips)!SKX_EXT_B_BGA1-IC,TBD!!!F98!DDR1_MA(2)!!!!
S!M_B_MA<3>!U5D1!N58!@baseboard_fab2_lib.baseboard_fab2(sch_1):page24_i172@chpset_lib.skx_ext_b(chips)!SKX_EXT_B_BGA1-IC,TBD!!!F98!DDR1_MA(3)!!!!
S!M_B_MA<4>!U5D1!M59!@baseboard_fab2_lib.baseboard_fab2(sch_1):page24_i172@chpset_lib.skx_ext_b(chips)!SKX_EXT_B_BGA1-IC,TBD!!!F98!DDR1_MA(4)!!!!
S!M_B_MA<5>!U5D1!R58!@baseboard_fab2_lib.baseboard_fab2(sch_1):page24_i172@chpset_lib.skx_ext_b(chips)!SKX_EXT_B_BGA1-IC,TBD!!!F98!DDR1_MA(5)!!!!
S!M_B_MA<6>!U5D1!T59!@baseboard_fab2_lib.baseboard_fab2(sch_1):page24_i172@chpset_lib.skx_ext_b(chips)!SKX_EXT_B_BGA1-IC,TBD!!!F98!DDR1_MA(6)!!!!
S!M_B_MA<7>!U5D1!V61!@baseboard_fab2_lib.baseboard_fab2(sch_1):page24_i172@chpset_lib.skx_ext_b(chips)!SKX_EXT_B_BGA1-IC,TBD!!!F98!DDR1_MA(7)!!!!
S!M_B_MA<8>!U5D1!W60!@baseboard_fab2_lib.baseboard_fab2(sch_1):page24_i172@chpset_lib.skx_ext_b(chips)!SKX_EXT_B_BGA1-IC,TBD!!!F98!DDR1_MA(8)!!!!
S!M_B_MA<9>!U5D1!K59!@baseboard_fab2_lib.baseboard_fab2(sch_1):page24_i172@chpset_lib.skx_ext_b(chips)!SKX_EXT_B_BGA1-IC,TBD!!!F98!DDR1_MA(9)!!!!
S!M_B_ODT<0>!U5D1!N50!@baseboard_fab2_lib.baseboard_fab2(sch_1):page24_i172@chpset_lib.skx_ext_b(chips)!SKX_EXT_B_BGA1-IC,TBD!!!F98!DDR1_ODT(0)!!!!
S!M_B_ODT<1>!U5D1!R48!@baseboard_fab2_lib.baseboard_fab2(sch_1):page24_i172@chpset_lib.skx_ext_b(chips)!SKX_EXT_B_BGA1-IC,TBD!!!F98!DDR1_ODT(1)!!!!
S!M_B_ODT<2>!U5D1!M49!@baseboard_fab2_lib.baseboard_fab2(sch_1):page24_i172@chpset_lib.skx_ext_b(chips)!SKX_EXT_B_BGA1-IC,TBD!!!F98!DDR1_ODT(2)!!!!
S!M_B_ODT<3>!U5D1!T47!@baseboard_fab2_lib.baseboard_fab2(sch_1):page24_i172@chpset_lib.skx_ext_b(chips)!SKX_EXT_B_BGA1-IC,TBD!!!F98!DDR1_ODT(3)!!!!
S!M_B_PAR!U5D1!K53!@baseboard_fab2_lib.baseboard_fab2(sch_1):page24_i172@chpset_lib.skx_ext_b(chips)!SKX_EXT_B_BGA1-IC,TBD!!!F98!DDR1_PAR!!!!
S!M_C_ACT_N!U5D1!AB61!@baseboard_fab2_lib.baseboard_fab2(sch_1):page25_i172@chpset_lib.skx_ext_b(chips)!SKX_EXT_B_BGA1-IC,TBD!!!F97!DDR2_ACT_N!!!!
S!M_C_ALERT_N!U5D1!AD61!@baseboard_fab2_lib.baseboard_fab2(sch_1):page25_i172@chpset_lib.skx_ext_b(chips)!SKX_EXT_B_BGA1-IC,TBD!!!F97!DDR2_ALERT_N!!!!
S!M_C_BA<0>!U5D1!W52!@baseboard_fab2_lib.baseboard_fab2(sch_1):page25_i172@chpset_lib.skx_ext_b(chips)!SKX_EXT_B_BGA1-IC,TBD!!!F97!DDR2_BA(0)!!!!
S!M_C_BA<1>!U5D1!AE56!@baseboard_fab2_lib.baseboard_fab2(sch_1):page25_i172@chpset_lib.skx_ext_b(chips)!SKX_EXT_B_BGA1-IC,TBD!!!F97!DDR2_BA(1)!!!!
S!M_C_BG<0>!U5D1!AA60!@baseboard_fab2_lib.baseboard_fab2(sch_1):page25_i172@chpset_lib.skx_ext_b(chips)!SKX_EXT_B_BGA1-IC,TBD!!!F97!DDR2_BG(0)!!!!
S!M_C_BG<1>!U5D1!AE62!@baseboard_fab2_lib.baseboard_fab2(sch_1):page25_i172@chpset_lib.skx_ext_b(chips)!SKX_EXT_B_BGA1-IC,TBD!!!F97!DDR2_BG(1)!!!!
S!M_C_C<2>!U5D1!AB45!@baseboard_fab2_lib.baseboard_fab2(sch_1):page25_i172@chpset_lib.skx_ext_b(chips)!SKX_EXT_B_BGA1-IC,TBD!!!F97!DDR2_CID(2)!!!!
S!M_C_CKE<0>!U5D1!AA62!@baseboard_fab2_lib.baseboard_fab2(sch_1):page25_i172@chpset_lib.skx_ext_b(chips)!SKX_EXT_B_BGA1-IC,TBD!!!F97!DDR2_CKE(0)!!!!
S!M_C_CKE<1>!U5D1!AD63!@baseboard_fab2_lib.baseboard_fab2(sch_1):page25_i172@chpset_lib.skx_ext_b(chips)!SKX_EXT_B_BGA1-IC,TBD!!!F97!DDR2_CKE(1)!!!!
S!M_C_CKE<2>!U5D1!V63!@baseboard_fab2_lib.baseboard_fab2(sch_1):page25_i172@chpset_lib.skx_ext_b(chips)!SKX_EXT_B_BGA1-IC,TBD!!!F97!DDR2_CKE(2)!!!!
S!M_C_CKE<3>!U5D1!AB63!@baseboard_fab2_lib.baseboard_fab2(sch_1):page25_i172@chpset_lib.skx_ext_b(chips)!SKX_EXT_B_BGA1-IC,TBD!!!F97!DDR2_CKE(3)!!!!
S!M_C_CLK_DN<0>!U5D1!AA54!@baseboard_fab2_lib.baseboard_fab2(sch_1):page25_i172@chpset_lib.skx_ext_b(chips)!SKX_EXT_B_BGA1-IC,TBD!!!F97!DDR2_CLK_DN(0)!!!!
S!M_C_CLK_DN<2>!U5D1!AA56!@baseboard_fab2_lib.baseboard_fab2(sch_1):page25_i172@chpset_lib.skx_ext_b(chips)!SKX_EXT_B_BGA1-IC,TBD!!!F97!DDR2_CLK_DN(2)!!!!
S!M_C_CLK_DN<1>!U5D1!W54!@baseboard_fab2_lib.baseboard_fab2(sch_1):page25_i172@chpset_lib.skx_ext_b(chips)!SKX_EXT_B_BGA1-IC,TBD!!!F97!DDR2_CLK_DN(1)!!!!
S!M_C_CLK_DN<3>!U5D1!W56!@baseboard_fab2_lib.baseboard_fab2(sch_1):page25_i172@chpset_lib.skx_ext_b(chips)!SKX_EXT_B_BGA1-IC,TBD!!!F97!DDR2_CLK_DN(3)!!!!
S!M_C_CLK_DP<0>!U5D1!AB55!@baseboard_fab2_lib.baseboard_fab2(sch_1):page25_i172@chpset_lib.skx_ext_b(chips)!SKX_EXT_B_BGA1-IC,TBD!!!F97!DDR2_CLK_DP(0)!!!!
S!M_C_CLK_DP<2>!U5D1!AB57!@baseboard_fab2_lib.baseboard_fab2(sch_1):page25_i172@chpset_lib.skx_ext_b(chips)!SKX_EXT_B_BGA1-IC,TBD!!!F97!DDR2_CLK_DP(2)!!!!
S!M_C_CLK_DP<1>!U5D1!V55!@baseboard_fab2_lib.baseboard_fab2(sch_1):page25_i172@chpset_lib.skx_ext_b(chips)!SKX_EXT_B_BGA1-IC,TBD!!!F97!DDR2_CLK_DP(1)!!!!
S!M_C_CLK_DP<3>!U5D1!V57!@baseboard_fab2_lib.baseboard_fab2(sch_1):page25_i172@chpset_lib.skx_ext_b(chips)!SKX_EXT_B_BGA1-IC,TBD!!!F97!DDR2_CLK_DP(3)!!!!
S!M_C_CS_N<0>!U5D1!V51!@baseboard_fab2_lib.baseboard_fab2(sch_1):page25_i172@chpset_lib.skx_ext_b(chips)!SKX_EXT_B_BGA1-IC,TBD!!!F97!DDR2_CS_N(0)!!!!
S!M_C_CS_N<1>!U5D1!AB49!@baseboard_fab2_lib.baseboard_fab2(sch_1):page25_i172@chpset_lib.skx_ext_b(chips)!SKX_EXT_B_BGA1-IC,TBD!!!F97!DDR2_CS_N(1)!!!!
S!M_C_CS_N<2>!U5D1!W46!@baseboard_fab2_lib.baseboard_fab2(sch_1):page25_i172@chpset_lib.skx_ext_b(chips)!SKX_EXT_B_BGA1-IC,TBD!!!F97!DDR2_CS_N(2)!!!!
S!M_C_CS_N<3>!U5D1!AA46!@baseboard_fab2_lib.baseboard_fab2(sch_1):page25_i172@chpset_lib.skx_ext_b(chips)!SKX_EXT_B_BGA1-IC,TBD!!!F97!DDR2_CS_N(3)!!!!
S!M_C_CS_N<4>!U5D1!AB51!@baseboard_fab2_lib.baseboard_fab2(sch_1):page25_i172@chpset_lib.skx_ext_b(chips)!SKX_EXT_B_BGA1-IC,TBD!!!F97!DDR2_CS_N(4)!!!!
S!M_C_CS_N<5>!U5D1!W48!@baseboard_fab2_lib.baseboard_fab2(sch_1):page25_i172@chpset_lib.skx_ext_b(chips)!SKX_EXT_B_BGA1-IC,TBD!!!F97!DDR2_CS_N(5)!!!!
S!M_C_CS_N<6>!U5D1!T45!@baseboard_fab2_lib.baseboard_fab2(sch_1):page25_i172@chpset_lib.skx_ext_b(chips)!SKX_EXT_B_BGA1-IC,TBD!!!F97!DDR2_CS_N(6)!!!!
S!M_C_CS_N<7>!U5D1!V45!@baseboard_fab2_lib.baseboard_fab2(sch_1):page25_i172@chpset_lib.skx_ext_b(chips)!SKX_EXT_B_BGA1-IC,TBD!!!F97!DDR2_CS_N(7)!!!!
S!M_C_DQ<0>!U5D1!AR76!@baseboard_fab2_lib.baseboard_fab2(sch_1):page25_i172@chpset_lib.skx_ext_b(chips)!SKX_EXT_B_BGA1-IC,TBD!!!F97!DDR2_DQ(0)!!!!
S!M_C_DQ<10>!U5D1!Y77!@baseboard_fab2_lib.baseboard_fab2(sch_1):page25_i172@chpset_lib.skx_ext_b(chips)!SKX_EXT_B_BGA1-IC,TBD!!!F97!DDR2_DQ(10)!!!!
S!M_C_DQ<11>!U5D1!W76!@baseboard_fab2_lib.baseboard_fab2(sch_1):page25_i172@chpset_lib.skx_ext_b(chips)!SKX_EXT_B_BGA1-IC,TBD!!!F97!DDR2_DQ(11)!!!!
S!M_C_DQ<12>!U5D1!AF75!@baseboard_fab2_lib.baseboard_fab2(sch_1):page25_i172@chpset_lib.skx_ext_b(chips)!SKX_EXT_B_BGA1-IC,TBD!!!F97!DDR2_DQ(12)!!!!
S!M_C_DQ<13>!U5D1!AE74!@baseboard_fab2_lib.baseboard_fab2(sch_1):page25_i172@chpset_lib.skx_ext_b(chips)!SKX_EXT_B_BGA1-IC,TBD!!!F97!DDR2_DQ(13)!!!!
S!M_C_DQ<14>!U5D1!AB77!@baseboard_fab2_lib.baseboard_fab2(sch_1):page25_i172@chpset_lib.skx_ext_b(chips)!SKX_EXT_B_BGA1-IC,TBD!!!F97!DDR2_DQ(14)!!!!
S!M_C_DQ<15>!U5D1!Y75!@baseboard_fab2_lib.baseboard_fab2(sch_1):page25_i172@chpset_lib.skx_ext_b(chips)!SKX_EXT_B_BGA1-IC,TBD!!!F97!DDR2_DQ(15)!!!!
S!M_C_DQ<16>!U5D1!W72!@baseboard_fab2_lib.baseboard_fab2(sch_1):page25_i172@chpset_lib.skx_ext_b(chips)!SKX_EXT_B_BGA1-IC,TBD!!!F97!DDR2_DQ(16)!!!!
S!M_C_DQ<17>!U5D1!AA70!@baseboard_fab2_lib.baseboard_fab2(sch_1):page25_i172@chpset_lib.skx_ext_b(chips)!SKX_EXT_B_BGA1-IC,TBD!!!F97!DDR2_DQ(17)!!!!
S!M_C_DQ<18>!U5D1!R70!@baseboard_fab2_lib.baseboard_fab2(sch_1):page25_i172@chpset_lib.skx_ext_b(chips)!SKX_EXT_B_BGA1-IC,TBD!!!F97!DDR2_DQ(18)!!!!
S!M_C_DQ<19>!U5D1!T69!@baseboard_fab2_lib.baseboard_fab2(sch_1):page25_i172@chpset_lib.skx_ext_b(chips)!SKX_EXT_B_BGA1-IC,TBD!!!F97!DDR2_DQ(19)!!!!
S!M_C_DQ<1>!U5D1!AN74!@baseboard_fab2_lib.baseboard_fab2(sch_1):page25_i172@chpset_lib.skx_ext_b(chips)!SKX_EXT_B_BGA1-IC,TBD!!!F97!DDR2_DQ(1)!!!!
S!M_C_DQ<20>!U5D1!AA72!@baseboard_fab2_lib.baseboard_fab2(sch_1):page25_i172@chpset_lib.skx_ext_b(chips)!SKX_EXT_B_BGA1-IC,TBD!!!F97!DDR2_DQ(20)!!!!
S!M_C_DQ<21>!U5D1!AB71!@baseboard_fab2_lib.baseboard_fab2(sch_1):page25_i172@chpset_lib.skx_ext_b(chips)!SKX_EXT_B_BGA1-IC,TBD!!!F97!DDR2_DQ(21)!!!!
S!M_C_DQ<22>!U5D1!T71!@baseboard_fab2_lib.baseboard_fab2(sch_1):page25_i172@chpset_lib.skx_ext_b(chips)!SKX_EXT_B_BGA1-IC,TBD!!!F97!DDR2_DQ(22)!!!!
S!M_C_DQ<23>!U5D1!V69!@baseboard_fab2_lib.baseboard_fab2(sch_1):page25_i172@chpset_lib.skx_ext_b(chips)!SKX_EXT_B_BGA1-IC,TBD!!!F97!DDR2_DQ(23)!!!!
S!M_C_DQ<24>!U5D1!AM67!@baseboard_fab2_lib.baseboard_fab2(sch_1):page25_i172@chpset_lib.skx_ext_b(chips)!SKX_EXT_B_BGA1-IC,TBD!!!F97!DDR2_DQ(24)!!!!
S!M_C_DQ<25>!U5D1!AT67!@baseboard_fab2_lib.baseboard_fab2(sch_1):page25_i172@chpset_lib.skx_ext_b(chips)!SKX_EXT_B_BGA1-IC,TBD!!!F97!DDR2_DQ(25)!!!!
S!M_C_DQ<26>!U5D1!AN64!@baseboard_fab2_lib.baseboard_fab2(sch_1):page25_i172@chpset_lib.skx_ext_b(chips)!SKX_EXT_B_BGA1-IC,TBD!!!F97!DDR2_DQ(26)!!!!
S!M_C_DQ<27>!U5D1!AR64!@baseboard_fab2_lib.baseboard_fab2(sch_1):page25_i172@chpset_lib.skx_ext_b(chips)!SKX_EXT_B_BGA1-IC,TBD!!!F97!DDR2_DQ(27)!!!!
S!M_C_DQ<28>!U5D1!AN68!@baseboard_fab2_lib.baseboard_fab2(sch_1):page25_i172@chpset_lib.skx_ext_b(chips)!SKX_EXT_B_BGA1-IC,TBD!!!F97!DDR2_DQ(28)!!!!
S!M_C_DQ<29>!U5D1!AR68!@baseboard_fab2_lib.baseboard_fab2(sch_1):page25_i172@chpset_lib.skx_ext_b(chips)!SKX_EXT_B_BGA1-IC,TBD!!!F97!DDR2_DQ(29)!!!!
S!M_C_DQ<2>!U5D1!AK77!@baseboard_fab2_lib.baseboard_fab2(sch_1):page25_i172@chpset_lib.skx_ext_b(chips)!SKX_EXT_B_BGA1-IC,TBD!!!F97!DDR2_DQ(2)!!!!
S!M_C_DQ<30>!U5D1!AM65!@baseboard_fab2_lib.baseboard_fab2(sch_1):page25_i172@chpset_lib.skx_ext_b(chips)!SKX_EXT_B_BGA1-IC,TBD!!!F97!DDR2_DQ(30)!!!!
S!M_C_DQ<31>!U5D1!AT65!@baseboard_fab2_lib.baseboard_fab2(sch_1):page25_i172@chpset_lib.skx_ext_b(chips)!SKX_EXT_B_BGA1-IC,TBD!!!F97!DDR2_DQ(31)!!!!
S!M_C_DQ<32>!U5D1!U40!@baseboard_fab2_lib.baseboard_fab2(sch_1):page25_i172@chpset_lib.skx_ext_b(chips)!SKX_EXT_B_BGA1-IC,TBD!!!F97!DDR2_DQ(32)!!!!
S!M_C_DQ<33>!U5D1!AA40!@baseboard_fab2_lib.baseboard_fab2(sch_1):page25_i172@chpset_lib.skx_ext_b(chips)!SKX_EXT_B_BGA1-IC,TBD!!!F97!DDR2_DQ(33)!!!!
S!M_C_DQ<34>!U5D1!V37!@baseboard_fab2_lib.baseboard_fab2(sch_1):page25_i172@chpset_lib.skx_ext_b(chips)!SKX_EXT_B_BGA1-IC,TBD!!!F97!DDR2_DQ(34)!!!!
S!M_C_DQ<35>!U5D1!Y37!@baseboard_fab2_lib.baseboard_fab2(sch_1):page25_i172@chpset_lib.skx_ext_b(chips)!SKX_EXT_B_BGA1-IC,TBD!!!F97!DDR2_DQ(35)!!!!
S!M_C_DQ<36>!U5D1!V41!@baseboard_fab2_lib.baseboard_fab2(sch_1):page25_i172@chpset_lib.skx_ext_b(chips)!SKX_EXT_B_BGA1-IC,TBD!!!F97!DDR2_DQ(36)!!!!
S!M_C_DQ<37>!U5D1!Y41!@baseboard_fab2_lib.baseboard_fab2(sch_1):page25_i172@chpset_lib.skx_ext_b(chips)!SKX_EXT_B_BGA1-IC,TBD!!!F97!DDR2_DQ(37)!!!!
S!M_C_DQ<38>!U5D1!U38!@baseboard_fab2_lib.baseboard_fab2(sch_1):page25_i172@chpset_lib.skx_ext_b(chips)!SKX_EXT_B_BGA1-IC,TBD!!!F97!DDR2_DQ(38)!!!!
S!M_C_DQ<39>!U5D1!AA38!@baseboard_fab2_lib.baseboard_fab2(sch_1):page25_i172@chpset_lib.skx_ext_b(chips)!SKX_EXT_B_BGA1-IC,TBD!!!F97!DDR2_DQ(39)!!!!
S!M_C_DQ<3>!U5D1!AJ76!@baseboard_fab2_lib.baseboard_fab2(sch_1):page25_i172@chpset_lib.skx_ext_b(chips)!SKX_EXT_B_BGA1-IC,TBD!!!F97!DDR2_DQ(3)!!!!
S!M_C_DQ<40>!U5D1!U34!@baseboard_fab2_lib.baseboard_fab2(sch_1):page25_i172@chpset_lib.skx_ext_b(chips)!SKX_EXT_B_BGA1-IC,TBD!!!F97!DDR2_DQ(40)!!!!
S!M_C_DQ<41>!U5D1!AA34!@baseboard_fab2_lib.baseboard_fab2(sch_1):page25_i172@chpset_lib.skx_ext_b(chips)!SKX_EXT_B_BGA1-IC,TBD!!!F97!DDR2_DQ(41)!!!!
S!M_C_DQ<42>!U5D1!V31!@baseboard_fab2_lib.baseboard_fab2(sch_1):page25_i172@chpset_lib.skx_ext_b(chips)!SKX_EXT_B_BGA1-IC,TBD!!!F97!DDR2_DQ(42)!!!!
S!M_C_DQ<43>!U5D1!Y31!@baseboard_fab2_lib.baseboard_fab2(sch_1):page25_i172@chpset_lib.skx_ext_b(chips)!SKX_EXT_B_BGA1-IC,TBD!!!F97!DDR2_DQ(43)!!!!
S!M_C_DQ<44>!U5D1!V35!@baseboard_fab2_lib.baseboard_fab2(sch_1):page25_i172@chpset_lib.skx_ext_b(chips)!SKX_EXT_B_BGA1-IC,TBD!!!F97!DDR2_DQ(44)!!!!
S!M_C_DQ<45>!U5D1!Y35!@baseboard_fab2_lib.baseboard_fab2(sch_1):page25_i172@chpset_lib.skx_ext_b(chips)!SKX_EXT_B_BGA1-IC,TBD!!!F97!DDR2_DQ(45)!!!!
S!M_C_DQ<46>!U5D1!U32!@baseboard_fab2_lib.baseboard_fab2(sch_1):page25_i172@chpset_lib.skx_ext_b(chips)!SKX_EXT_B_BGA1-IC,TBD!!!F97!DDR2_DQ(46)!!!!
S!M_C_DQ<47>!U5D1!AA32!@baseboard_fab2_lib.baseboard_fab2(sch_1):page25_i172@chpset_lib.skx_ext_b(chips)!SKX_EXT_B_BGA1-IC,TBD!!!F97!DDR2_DQ(47)!!!!
S!M_C_DQ<48>!U5D1!AD31!@baseboard_fab2_lib.baseboard_fab2(sch_1):page25_i172@chpset_lib.skx_ext_b(chips)!SKX_EXT_B_BGA1-IC,TBD!!!F97!DDR2_DQ(48)!!!!
S!M_C_DQ<49>!U5D1!AH31!@baseboard_fab2_lib.baseboard_fab2(sch_1):page25_i172@chpset_lib.skx_ext_b(chips)!SKX_EXT_B_BGA1-IC,TBD!!!F97!DDR2_DQ(49)!!!!
S!M_C_DQ<4>!U5D1!AT75!@baseboard_fab2_lib.baseboard_fab2(sch_1):page25_i172@chpset_lib.skx_ext_b(chips)!SKX_EXT_B_BGA1-IC,TBD!!!F97!DDR2_DQ(4)!!!!
S!M_C_DQ<50>!U5D1!AE28!@baseboard_fab2_lib.baseboard_fab2(sch_1):page25_i172@chpset_lib.skx_ext_b(chips)!SKX_EXT_B_BGA1-IC,TBD!!!F97!DDR2_DQ(50)!!!!
S!M_C_DQ<51>!U5D1!AG28!@baseboard_fab2_lib.baseboard_fab2(sch_1):page25_i172@chpset_lib.skx_ext_b(chips)!SKX_EXT_B_BGA1-IC,TBD!!!F97!DDR2_DQ(51)!!!!
S!M_C_DQ<52>!U5D1!AE32!@baseboard_fab2_lib.baseboard_fab2(sch_1):page25_i172@chpset_lib.skx_ext_b(chips)!SKX_EXT_B_BGA1-IC,TBD!!!F97!DDR2_DQ(52)!!!!
S!M_C_DQ<53>!U5D1!AG32!@baseboard_fab2_lib.baseboard_fab2(sch_1):page25_i172@chpset_lib.skx_ext_b(chips)!SKX_EXT_B_BGA1-IC,TBD!!!F97!DDR2_DQ(53)!!!!
S!M_C_DQ<54>!U5D1!AD29!@baseboard_fab2_lib.baseboard_fab2(sch_1):page25_i172@chpset_lib.skx_ext_b(chips)!SKX_EXT_B_BGA1-IC,TBD!!!F97!DDR2_DQ(54)!!!!
S!M_C_DQ<55>!U5D1!AH29!@baseboard_fab2_lib.baseboard_fab2(sch_1):page25_i172@chpset_lib.skx_ext_b(chips)!SKX_EXT_B_BGA1-IC,TBD!!!F97!DDR2_DQ(55)!!!!
S!M_C_DQ<56>!U5D1!AD25!@baseboard_fab2_lib.baseboard_fab2(sch_1):page25_i172@chpset_lib.skx_ext_b(chips)!SKX_EXT_B_BGA1-IC,TBD!!!F97!DDR2_DQ(56)!!!!
S!M_C_DQ<57>!U5D1!AH25!@baseboard_fab2_lib.baseboard_fab2(sch_1):page25_i172@chpset_lib.skx_ext_b(chips)!SKX_EXT_B_BGA1-IC,TBD!!!F97!DDR2_DQ(57)!!!!
S!M_C_DQ<58>!U5D1!AE22!@baseboard_fab2_lib.baseboard_fab2(sch_1):page25_i172@chpset_lib.skx_ext_b(chips)!SKX_EXT_B_BGA1-IC,TBD!!!F97!DDR2_DQ(58)!!!!
S!M_C_DQ<59>!U5D1!AG22!@baseboard_fab2_lib.baseboard_fab2(sch_1):page25_i172@chpset_lib.skx_ext_b(chips)!SKX_EXT_B_BGA1-IC,TBD!!!F97!DDR2_DQ(59)!!!!
S!M_C_DQ<5>!U5D1!AR74!@baseboard_fab2_lib.baseboard_fab2(sch_1):page25_i172@chpset_lib.skx_ext_b(chips)!SKX_EXT_B_BGA1-IC,TBD!!!F97!DDR2_DQ(5)!!!!
S!M_C_DQ<60>!U5D1!AE26!@baseboard_fab2_lib.baseboard_fab2(sch_1):page25_i172@chpset_lib.skx_ext_b(chips)!SKX_EXT_B_BGA1-IC,TBD!!!F97!DDR2_DQ(60)!!!!
S!M_C_DQ<61>!U5D1!AG26!@baseboard_fab2_lib.baseboard_fab2(sch_1):page25_i172@chpset_lib.skx_ext_b(chips)!SKX_EXT_B_BGA1-IC,TBD!!!F97!DDR2_DQ(61)!!!!
S!M_C_DQ<62>!U5D1!AD23!@baseboard_fab2_lib.baseboard_fab2(sch_1):page25_i172@chpset_lib.skx_ext_b(chips)!SKX_EXT_B_BGA1-IC,TBD!!!F97!DDR2_DQ(62)!!!!
S!M_C_DQ<63>!U5D1!AH23!@baseboard_fab2_lib.baseboard_fab2(sch_1):page25_i172@chpset_lib.skx_ext_b(chips)!SKX_EXT_B_BGA1-IC,TBD!!!F97!DDR2_DQ(63)!!!!
S!M_C_DQ<6>!U5D1!AM77!@baseboard_fab2_lib.baseboard_fab2(sch_1):page25_i172@chpset_lib.skx_ext_b(chips)!SKX_EXT_B_BGA1-IC,TBD!!!F97!DDR2_DQ(6)!!!!
S!M_C_DQ<7>!U5D1!AK75!@baseboard_fab2_lib.baseboard_fab2(sch_1):page25_i172@chpset_lib.skx_ext_b(chips)!SKX_EXT_B_BGA1-IC,TBD!!!F97!DDR2_DQ(7)!!!!
S!M_C_DQ<8>!U5D1!AE76!@baseboard_fab2_lib.baseboard_fab2(sch_1):page25_i172@chpset_lib.skx_ext_b(chips)!SKX_EXT_B_BGA1-IC,TBD!!!F97!DDR2_DQ(8)!!!!
S!M_C_DQ<9>!U5D1!AC74!@baseboard_fab2_lib.baseboard_fab2(sch_1):page25_i172@chpset_lib.skx_ext_b(chips)!SKX_EXT_B_BGA1-IC,TBD!!!F97!DDR2_DQ(9)!!!!
S!M_C_DQS_DN<0>!U5D1!AL74!@baseboard_fab2_lib.baseboard_fab2(sch_1):page25_i172@chpset_lib.skx_ext_b(chips)!SKX_EXT_B_BGA1-IC,TBD!!!F97!DDR2_DQS_DN(0)!!!!
S!M_C_DQS_DN<10>!U5D1!AD77!@baseboard_fab2_lib.baseboard_fab2(sch_1):page25_i172@chpset_lib.skx_ext_b(chips)!SKX_EXT_B_BGA1-IC,TBD!!!F97!DDR2_DQS_DN(10)!!!!
S!M_C_DQS_DN<11>!U5D1!U72!@baseboard_fab2_lib.baseboard_fab2(sch_1):page25_i172@chpset_lib.skx_ext_b(chips)!SKX_EXT_B_BGA1-IC,TBD!!!F97!DDR2_DQS_DN(11)!!!!
S!M_C_DQS_DN<12>!U5D1!AL66!@baseboard_fab2_lib.baseboard_fab2(sch_1):page25_i172@chpset_lib.skx_ext_b(chips)!SKX_EXT_B_BGA1-IC,TBD!!!F97!DDR2_DQS_DN(12)!!!!
S!M_C_DQS_DN<13>!U5D1!T39!@baseboard_fab2_lib.baseboard_fab2(sch_1):page25_i172@chpset_lib.skx_ext_b(chips)!SKX_EXT_B_BGA1-IC,TBD!!!F97!DDR2_DQS_DN(13)!!!!
S!M_C_DQS_DN<14>!U5D1!T33!@baseboard_fab2_lib.baseboard_fab2(sch_1):page25_i172@chpset_lib.skx_ext_b(chips)!SKX_EXT_B_BGA1-IC,TBD!!!F97!DDR2_DQS_DN(14)!!!!
S!M_C_DQS_DN<15>!U5D1!AC30!@baseboard_fab2_lib.baseboard_fab2(sch_1):page25_i172@chpset_lib.skx_ext_b(chips)!SKX_EXT_B_BGA1-IC,TBD!!!F97!DDR2_DQS_DN(15)!!!!
S!M_C_DQS_DN<16>!U5D1!AC24!@baseboard_fab2_lib.baseboard_fab2(sch_1):page25_i172@chpset_lib.skx_ext_b(chips)!SKX_EXT_B_BGA1-IC,TBD!!!F97!DDR2_DQS_DN(16)!!!!
S!M_C_DQS_DN<17>!U5D1!AT71!@baseboard_fab2_lib.baseboard_fab2(sch_1):page25_i172@chpset_lib.skx_ext_b(chips)!SKX_EXT_B_BGA1-IC,TBD!!!F97!DDR2_DQS_DN(17)!!!!
S!M_C_DQS_DN<1>!U5D1!AA74!@baseboard_fab2_lib.baseboard_fab2(sch_1):page25_i172@chpset_lib.skx_ext_b(chips)!SKX_EXT_B_BGA1-IC,TBD!!!F97!DDR2_DQS_DN(1)!!!!
S!M_C_DQS_DN<2>!U5D1!Y69!@baseboard_fab2_lib.baseboard_fab2(sch_1):page25_i172@chpset_lib.skx_ext_b(chips)!SKX_EXT_B_BGA1-IC,TBD!!!F97!DDR2_DQS_DN(2)!!!!
S!M_C_DQS_DN<3>!U5D1!AU66!@baseboard_fab2_lib.baseboard_fab2(sch_1):page25_i172@chpset_lib.skx_ext_b(chips)!SKX_EXT_B_BGA1-IC,TBD!!!F97!DDR2_DQS_DN(3)!!!!
S!M_C_DQS_DN<4>!U5D1!AB39!@baseboard_fab2_lib.baseboard_fab2(sch_1):page25_i172@chpset_lib.skx_ext_b(chips)!SKX_EXT_B_BGA1-IC,TBD!!!F97!DDR2_DQS_DN(4)!!!!
S!M_C_DQS_DN<5>!U5D1!AB33!@baseboard_fab2_lib.baseboard_fab2(sch_1):page25_i172@chpset_lib.skx_ext_b(chips)!SKX_EXT_B_BGA1-IC,TBD!!!F97!DDR2_DQS_DN(5)!!!!
S!M_C_DQS_DN<6>!U5D1!AJ30!@baseboard_fab2_lib.baseboard_fab2(sch_1):page25_i172@chpset_lib.skx_ext_b(chips)!SKX_EXT_B_BGA1-IC,TBD!!!F97!DDR2_DQS_DN(6)!!!!
S!M_C_DQS_DN<7>!U5D1!AJ24!@baseboard_fab2_lib.baseboard_fab2(sch_1):page25_i172@chpset_lib.skx_ext_b(chips)!SKX_EXT_B_BGA1-IC,TBD!!!F97!DDR2_DQS_DN(7)!!!!
S!M_C_DQS_DN<8>!U5D1!BB71!@baseboard_fab2_lib.baseboard_fab2(sch_1):page25_i172@chpset_lib.skx_ext_b(chips)!SKX_EXT_B_BGA1-IC,TBD!!!F97!DDR2_DQS_DN(8)!!!!
S!M_C_DQS_DN<9>!U5D1!AP77!@baseboard_fab2_lib.baseboard_fab2(sch_1):page25_i172@chpset_lib.skx_ext_b(chips)!SKX_EXT_B_BGA1-IC,TBD!!!F97!DDR2_DQS_DN(9)!!!!
S!M_C_DQS_DP<0>!U5D1!AM75!@baseboard_fab2_lib.baseboard_fab2(sch_1):page25_i172@chpset_lib.skx_ext_b(chips)!SKX_EXT_B_BGA1-IC,TBD!!!F97!DDR2_DQS_DP(0)!!!!
S!M_C_DQS_DP<10>!U5D1!AC76!@baseboard_fab2_lib.baseboard_fab2(sch_1):page25_i172@chpset_lib.skx_ext_b(chips)!SKX_EXT_B_BGA1-IC,TBD!!!F97!DDR2_DQS_DP(10)!!!!
S!M_C_DQS_DP<11>!U5D1!V71!@baseboard_fab2_lib.baseboard_fab2(sch_1):page25_i172@chpset_lib.skx_ext_b(chips)!SKX_EXT_B_BGA1-IC,TBD!!!F97!DDR2_DQS_DP(11)!!!!
S!M_C_DQS_DP<12>!U5D1!AN66!@baseboard_fab2_lib.baseboard_fab2(sch_1):page25_i172@chpset_lib.skx_ext_b(chips)!SKX_EXT_B_BGA1-IC,TBD!!!F97!DDR2_DQS_DP(12)!!!!
S!M_C_DQS_DP<13>!U5D1!V39!@baseboard_fab2_lib.baseboard_fab2(sch_1):page25_i172@chpset_lib.skx_ext_b(chips)!SKX_EXT_B_BGA1-IC,TBD!!!F97!DDR2_DQS_DP(13)!!!!
S!M_C_DQS_DP<14>!U5D1!V33!@baseboard_fab2_lib.baseboard_fab2(sch_1):page25_i172@chpset_lib.skx_ext_b(chips)!SKX_EXT_B_BGA1-IC,TBD!!!F97!DDR2_DQS_DP(14)!!!!
S!M_C_DQS_DP<15>!U5D1!AE30!@baseboard_fab2_lib.baseboard_fab2(sch_1):page25_i172@chpset_lib.skx_ext_b(chips)!SKX_EXT_B_BGA1-IC,TBD!!!F97!DDR2_DQS_DP(15)!!!!
S!M_C_DQS_DP<16>!U5D1!AE24!@baseboard_fab2_lib.baseboard_fab2(sch_1):page25_i172@chpset_lib.skx_ext_b(chips)!SKX_EXT_B_BGA1-IC,TBD!!!F97!DDR2_DQS_DP(16)!!!!
S!M_C_DQS_DP<17>!U5D1!AV71!@baseboard_fab2_lib.baseboard_fab2(sch_1):page25_i172@chpset_lib.skx_ext_b(chips)!SKX_EXT_B_BGA1-IC,TBD!!!F97!DDR2_DQS_DP(17)!!!!
S!M_C_DQS_DP<1>!U5D1!AB75!@baseboard_fab2_lib.baseboard_fab2(sch_1):page25_i172@chpset_lib.skx_ext_b(chips)!SKX_EXT_B_BGA1-IC,TBD!!!F97!DDR2_DQS_DP(1)!!!!
S!M_C_DQS_DP<2>!U5D1!W70!@baseboard_fab2_lib.baseboard_fab2(sch_1):page25_i172@chpset_lib.skx_ext_b(chips)!SKX_EXT_B_BGA1-IC,TBD!!!F97!DDR2_DQS_DP(2)!!!!
S!M_C_DQS_DP<3>!U5D1!AR66!@baseboard_fab2_lib.baseboard_fab2(sch_1):page25_i172@chpset_lib.skx_ext_b(chips)!SKX_EXT_B_BGA1-IC,TBD!!!F97!DDR2_DQS_DP(3)!!!!
S!M_C_DQS_DP<4>!U5D1!Y39!@baseboard_fab2_lib.baseboard_fab2(sch_1):page25_i172@chpset_lib.skx_ext_b(chips)!SKX_EXT_B_BGA1-IC,TBD!!!F97!DDR2_DQS_DP(4)!!!!
S!M_C_DQS_DP<5>!U5D1!Y33!@baseboard_fab2_lib.baseboard_fab2(sch_1):page25_i172@chpset_lib.skx_ext_b(chips)!SKX_EXT_B_BGA1-IC,TBD!!!F97!DDR2_DQS_DP(5)!!!!
S!M_C_DQS_DP<6>!U5D1!AG30!@baseboard_fab2_lib.baseboard_fab2(sch_1):page25_i172@chpset_lib.skx_ext_b(chips)!SKX_EXT_B_BGA1-IC,TBD!!!F97!DDR2_DQS_DP(6)!!!!
S!M_C_DQS_DP<7>!U5D1!AG24!@baseboard_fab2_lib.baseboard_fab2(sch_1):page25_i172@chpset_lib.skx_ext_b(chips)!SKX_EXT_B_BGA1-IC,TBD!!!F97!DDR2_DQS_DP(7)!!!!
S!M_C_DQS_DP<8>!U5D1!AY71!@baseboard_fab2_lib.baseboard_fab2(sch_1):page25_i172@chpset_lib.skx_ext_b(chips)!SKX_EXT_B_BGA1-IC,TBD!!!F97!DDR2_DQS_DP(8)!!!!
S!M_C_DQS_DP<9>!U5D1!AN76!@baseboard_fab2_lib.baseboard_fab2(sch_1):page25_i172@chpset_lib.skx_ext_b(chips)!SKX_EXT_B_BGA1-IC,TBD!!!F97!DDR2_DQS_DP(9)!!!!
S!M_C_ECC<0>!U5D1!AU72!@baseboard_fab2_lib.baseboard_fab2(sch_1):page25_i172@chpset_lib.skx_ext_b(chips)!SKX_EXT_B_BGA1-IC,TBD!!!F97!DDR2_ECC(0)!!!!
S!M_C_ECC<1>!U5D1!BA72!@baseboard_fab2_lib.baseboard_fab2(sch_1):page25_i172@chpset_lib.skx_ext_b(chips)!SKX_EXT_B_BGA1-IC,TBD!!!F97!DDR2_ECC(1)!!!!
S!M_C_ECC<2>!U5D1!AV69!@baseboard_fab2_lib.baseboard_fab2(sch_1):page25_i172@chpset_lib.skx_ext_b(chips)!SKX_EXT_B_BGA1-IC,TBD!!!F97!DDR2_ECC(2)!!!!
S!M_C_ECC<3>!U5D1!AY69!@baseboard_fab2_lib.baseboard_fab2(sch_1):page25_i172@chpset_lib.skx_ext_b(chips)!SKX_EXT_B_BGA1-IC,TBD!!!F97!DDR2_ECC(3)!!!!
S!M_C_ECC<4>!U5D1!AV73!@baseboard_fab2_lib.baseboard_fab2(sch_1):page25_i172@chpset_lib.skx_ext_b(chips)!SKX_EXT_B_BGA1-IC,TBD!!!F97!DDR2_ECC(4)!!!!
S!M_C_ECC<5>!U5D1!AY73!@baseboard_fab2_lib.baseboard_fab2(sch_1):page25_i172@chpset_lib.skx_ext_b(chips)!SKX_EXT_B_BGA1-IC,TBD!!!F97!DDR2_ECC(5)!!!!
S!M_C_ECC<6>!U5D1!AU70!@baseboard_fab2_lib.baseboard_fab2(sch_1):page25_i172@chpset_lib.skx_ext_b(chips)!SKX_EXT_B_BGA1-IC,TBD!!!F97!DDR2_ECC(6)!!!!
S!M_C_ECC<7>!U5D1!BA70!@baseboard_fab2_lib.baseboard_fab2(sch_1):page25_i172@chpset_lib.skx_ext_b(chips)!SKX_EXT_B_BGA1-IC,TBD!!!F97!DDR2_ECC(7)!!!!
S!M_C_MA<0>!U5D1!AB53!@baseboard_fab2_lib.baseboard_fab2(sch_1):page25_i172@chpset_lib.skx_ext_b(chips)!SKX_EXT_B_BGA1-IC,TBD!!!F97!DDR2_MA(0)!!!!
S!M_C_MA<10>!U5D1!AD55!@baseboard_fab2_lib.baseboard_fab2(sch_1):page25_i172@chpset_lib.skx_ext_b(chips)!SKX_EXT_B_BGA1-IC,TBD!!!F97!DDR2_MA(10)!!!!
S!M_C_MA<11>!U5D1!AG60!@baseboard_fab2_lib.baseboard_fab2(sch_1):page25_i172@chpset_lib.skx_ext_b(chips)!SKX_EXT_B_BGA1-IC,TBD!!!F97!DDR2_MA(11)!!!!
S!M_C_MA<12>!U5D1!AG62!@baseboard_fab2_lib.baseboard_fab2(sch_1):page25_i172@chpset_lib.skx_ext_b(chips)!SKX_EXT_B_BGA1-IC,TBD!!!F97!DDR2_MA(12)!!!!
S!M_C_MA<13>!U5D1!AD53!@baseboard_fab2_lib.baseboard_fab2(sch_1):page25_i172@chpset_lib.skx_ext_b(chips)!SKX_EXT_B_BGA1-IC,TBD!!!F97!DDR2_MA(13)!!!!
S!M_C_MA<14>!U5D1!W50!@baseboard_fab2_lib.baseboard_fab2(sch_1):page25_i172@chpset_lib.skx_ext_b(chips)!SKX_EXT_B_BGA1-IC,TBD!!!F97!DDR2_MA(14)!!!!
S!M_C_MA<15>!U5D1!AE54!@baseboard_fab2_lib.baseboard_fab2(sch_1):page25_i172@chpset_lib.skx_ext_b(chips)!SKX_EXT_B_BGA1-IC,TBD!!!F97!DDR2_MA(15)!!!!
S!M_C_MA<16>!U5D1!AA52!@baseboard_fab2_lib.baseboard_fab2(sch_1):page25_i172@chpset_lib.skx_ext_b(chips)!SKX_EXT_B_BGA1-IC,TBD!!!F97!DDR2_MA(16)!!!!
S!M_C_MA<17>!U5D1!AC46!@baseboard_fab2_lib.baseboard_fab2(sch_1):page25_i172@chpset_lib.skx_ext_b(chips)!SKX_EXT_B_BGA1-IC,TBD!!!F97!DDR2_MA(17)!!!!
S!M_C_MA<1>!U5D1!AE58!@baseboard_fab2_lib.baseboard_fab2(sch_1):page25_i172@chpset_lib.skx_ext_b(chips)!SKX_EXT_B_BGA1-IC,TBD!!!F97!DDR2_MA(1)!!!!
S!M_C_MA<2>!U5D1!AD57!@baseboard_fab2_lib.baseboard_fab2(sch_1):page25_i172@chpset_lib.skx_ext_b(chips)!SKX_EXT_B_BGA1-IC,TBD!!!F97!DDR2_MA(2)!!!!
S!M_C_MA<3>!U5D1!W58!@baseboard_fab2_lib.baseboard_fab2(sch_1):page25_i172@chpset_lib.skx_ext_b(chips)!SKX_EXT_B_BGA1-IC,TBD!!!F97!DDR2_MA(3)!!!!
S!M_C_MA<4>!U5D1!AA58!@baseboard_fab2_lib.baseboard_fab2(sch_1):page25_i172@chpset_lib.skx_ext_b(chips)!SKX_EXT_B_BGA1-IC,TBD!!!F97!DDR2_MA(4)!!!!
S!M_C_MA<5>!U5D1!V59!@baseboard_fab2_lib.baseboard_fab2(sch_1):page25_i172@chpset_lib.skx_ext_b(chips)!SKX_EXT_B_BGA1-IC,TBD!!!F97!DDR2_MA(5)!!!!
S!M_C_MA<6>!U5D1!AB59!@baseboard_fab2_lib.baseboard_fab2(sch_1):page25_i172@chpset_lib.skx_ext_b(chips)!SKX_EXT_B_BGA1-IC,TBD!!!F97!DDR2_MA(6)!!!!
S!M_C_MA<7>!U5D1!AE60!@baseboard_fab2_lib.baseboard_fab2(sch_1):page25_i172@chpset_lib.skx_ext_b(chips)!SKX_EXT_B_BGA1-IC,TBD!!!F97!DDR2_MA(7)!!!!
S!M_C_MA<8>!U5D1!AD59!@baseboard_fab2_lib.baseboard_fab2(sch_1):page25_i172@chpset_lib.skx_ext_b(chips)!SKX_EXT_B_BGA1-IC,TBD!!!F97!DDR2_MA(8)!!!!
S!M_C_MA<9>!U5D1!AG58!@baseboard_fab2_lib.baseboard_fab2(sch_1):page25_i172@chpset_lib.skx_ext_b(chips)!SKX_EXT_B_BGA1-IC,TBD!!!F97!DDR2_MA(9)!!!!
S!M_C_ODT<0>!U5D1!AA50!@baseboard_fab2_lib.baseboard_fab2(sch_1):page25_i172@chpset_lib.skx_ext_b(chips)!SKX_EXT_B_BGA1-IC,TBD!!!F97!DDR2_ODT(0)!!!!
S!M_C_ODT<1>!U5D1!AA48!@baseboard_fab2_lib.baseboard_fab2(sch_1):page25_i172@chpset_lib.skx_ext_b(chips)!SKX_EXT_B_BGA1-IC,TBD!!!F97!DDR2_ODT(1)!!!!
S!M_C_ODT<2>!U5D1!V49!@baseboard_fab2_lib.baseboard_fab2(sch_1):page25_i172@chpset_lib.skx_ext_b(chips)!SKX_EXT_B_BGA1-IC,TBD!!!F97!DDR2_ODT(2)!!!!
S!M_C_ODT<3>!U5D1!AB47!@baseboard_fab2_lib.baseboard_fab2(sch_1):page25_i172@chpset_lib.skx_ext_b(chips)!SKX_EXT_B_BGA1-IC,TBD!!!F97!DDR2_ODT(3)!!!!
S!M_C_PAR!U5D1!V53!@baseboard_fab2_lib.baseboard_fab2(sch_1):page25_i172@chpset_lib.skx_ext_b(chips)!SKX_EXT_B_BGA1-IC,TBD!!!F97!DDR2_PAR!!!!
S!M_D_ACT_N!U5D1!DW60!@baseboard_fab2_lib.baseboard_fab2(sch_1):page26_i172@chpset_lib.skx_ext_b(chips)!SKX_EXT_B_BGA1-IC,TBD!!!F96!DDR3_ACT_N!!!!
S!M_D_ALERT_N!U5D1!ED63!@baseboard_fab2_lib.baseboard_fab2(sch_1):page26_i172@chpset_lib.skx_ext_b(chips)!SKX_EXT_B_BGA1-IC,TBD!!!F96!DDR3_ALERT_N!!!!
S!M_D_BA<0>!U5D1!EE52!@baseboard_fab2_lib.baseboard_fab2(sch_1):page26_i172@chpset_lib.skx_ext_b(chips)!SKX_EXT_B_BGA1-IC,TBD!!!F96!DDR3_BA(0)!!!!
S!M_D_BA<1>!U5D1!EA54!@baseboard_fab2_lib.baseboard_fab2(sch_1):page26_i172@chpset_lib.skx_ext_b(chips)!SKX_EXT_B_BGA1-IC,TBD!!!F96!DDR3_BA(1)!!!!
S!M_D_BG<0>!U5D1!ED61!@baseboard_fab2_lib.baseboard_fab2(sch_1):page26_i172@chpset_lib.skx_ext_b(chips)!SKX_EXT_B_BGA1-IC,TBD!!!F96!DDR3_BG(0)!!!!
S!M_D_BG<1>!U5D1!DW62!@baseboard_fab2_lib.baseboard_fab2(sch_1):page26_i172@chpset_lib.skx_ext_b(chips)!SKX_EXT_B_BGA1-IC,TBD!!!F96!DDR3_BG(1)!!!!
S!M_D_C<2>!U5D1!DV47!@baseboard_fab2_lib.baseboard_fab2(sch_1):page26_i172@chpset_lib.skx_ext_b(chips)!SKX_EXT_B_BGA1-IC,TBD!!!F96!DDR3_CID(2)!!!!
S!M_D_CKE<0>!U5D1!EE62!@baseboard_fab2_lib.baseboard_fab2(sch_1):page26_i172@chpset_lib.skx_ext_b(chips)!SKX_EXT_B_BGA1-IC,TBD!!!F96!DDR3_CKE(0)!!!!
S!M_D_CKE<1>!U5D1!EF63!@baseboard_fab2_lib.baseboard_fab2(sch_1):page26_i172@chpset_lib.skx_ext_b(chips)!SKX_EXT_B_BGA1-IC,TBD!!!F96!DDR3_CKE(1)!!!!
S!M_D_CKE<2>!U5D1!EA62!@baseboard_fab2_lib.baseboard_fab2(sch_1):page26_i172@chpset_lib.skx_ext_b(chips)!SKX_EXT_B_BGA1-IC,TBD!!!F96!DDR3_CKE(2)!!!!
S!M_D_CKE<3>!U5D1!EB63!@baseboard_fab2_lib.baseboard_fab2(sch_1):page26_i172@chpset_lib.skx_ext_b(chips)!SKX_EXT_B_BGA1-IC,TBD!!!F96!DDR3_CKE(3)!!!!
S!M_D_CLK_DN<0>!U5D1!ED55!@baseboard_fab2_lib.baseboard_fab2(sch_1):page26_i172@chpset_lib.skx_ext_b(chips)!SKX_EXT_B_BGA1-IC,TBD!!!F96!DDR3_CLK_DN(0)!!!!
S!M_D_CLK_DN<2>!U5D1!DW56!@baseboard_fab2_lib.baseboard_fab2(sch_1):page26_i172@chpset_lib.skx_ext_b(chips)!SKX_EXT_B_BGA1-IC,TBD!!!F96!DDR3_CLK_DN(2)!!!!
S!M_D_CLK_DN<1>!U5D1!EF55!@baseboard_fab2_lib.baseboard_fab2(sch_1):page26_i172@chpset_lib.skx_ext_b(chips)!SKX_EXT_B_BGA1-IC,TBD!!!F96!DDR3_CLK_DN(1)!!!!
S!M_D_CLK_DN<3>!U5D1!EF57!@baseboard_fab2_lib.baseboard_fab2(sch_1):page26_i172@chpset_lib.skx_ext_b(chips)!SKX_EXT_B_BGA1-IC,TBD!!!F96!DDR3_CLK_DN(3)!!!!
S!M_D_CLK_DP<0>!U5D1!EB55!@baseboard_fab2_lib.baseboard_fab2(sch_1):page26_i172@chpset_lib.skx_ext_b(chips)!SKX_EXT_B_BGA1-IC,TBD!!!F96!DDR3_CLK_DP(0)!!!!
S!M_D_CLK_DP<2>!U5D1!EA56!@baseboard_fab2_lib.baseboard_fab2(sch_1):page26_i172@chpset_lib.skx_ext_b(chips)!SKX_EXT_B_BGA1-IC,TBD!!!F96!DDR3_CLK_DP(2)!!!!
S!M_D_CLK_DP<1>!U5D1!EE54!@baseboard_fab2_lib.baseboard_fab2(sch_1):page26_i172@chpset_lib.skx_ext_b(chips)!SKX_EXT_B_BGA1-IC,TBD!!!F96!DDR3_CLK_DP(1)!!!!
S!M_D_CLK_DP<3>!U5D1!EE56!@baseboard_fab2_lib.baseboard_fab2(sch_1):page26_i172@chpset_lib.skx_ext_b(chips)!SKX_EXT_B_BGA1-IC,TBD!!!F96!DDR3_CLK_DP(3)!!!!
S!M_D_CS_N<0>!U5D1!EF51!@baseboard_fab2_lib.baseboard_fab2(sch_1):page26_i172@chpset_lib.skx_ext_b(chips)!SKX_EXT_B_BGA1-IC,TBD!!!F96!DDR3_CS_N(0)!!!!
S!M_D_CS_N<1>!U5D1!ED49!@baseboard_fab2_lib.baseboard_fab2(sch_1):page26_i172@chpset_lib.skx_ext_b(chips)!SKX_EXT_B_BGA1-IC,TBD!!!F96!DDR3_CS_N(1)!!!!
S!M_D_CS_N<2>!U5D1!ED47!@baseboard_fab2_lib.baseboard_fab2(sch_1):page26_i172@chpset_lib.skx_ext_b(chips)!SKX_EXT_B_BGA1-IC,TBD!!!F96!DDR3_CS_N(2)!!!!
S!M_D_CS_N<3>!U5D1!EB47!@baseboard_fab2_lib.baseboard_fab2(sch_1):page26_i172@chpset_lib.skx_ext_b(chips)!SKX_EXT_B_BGA1-IC,TBD!!!F96!DDR3_CS_N(3)!!!!
S!M_D_CS_N<4>!U5D1!EB51!@baseboard_fab2_lib.baseboard_fab2(sch_1):page26_i172@chpset_lib.skx_ext_b(chips)!SKX_EXT_B_BGA1-IC,TBD!!!F96!DDR3_CS_N(4)!!!!
S!M_D_CS_N<5>!U5D1!EB49!@baseboard_fab2_lib.baseboard_fab2(sch_1):page26_i172@chpset_lib.skx_ext_b(chips)!SKX_EXT_B_BGA1-IC,TBD!!!F96!DDR3_CS_N(5)!!!!
S!M_D_CS_N<6>!U5D1!DV45!@baseboard_fab2_lib.baseboard_fab2(sch_1):page26_i172@chpset_lib.skx_ext_b(chips)!SKX_EXT_B_BGA1-IC,TBD!!!F96!DDR3_CS_N(6)!!!!
S!M_D_CS_N<7>!U5D1!EB45!@baseboard_fab2_lib.baseboard_fab2(sch_1):page26_i172@chpset_lib.skx_ext_b(chips)!SKX_EXT_B_BGA1-IC,TBD!!!F96!DDR3_CS_N(7)!!!!
S!M_D_DQ<0>!U5D1!CN84!@baseboard_fab2_lib.baseboard_fab2(sch_1):page26_i172@chpset_lib.skx_ext_b(chips)!SKX_EXT_B_BGA1-IC,TBD!!!F96!DDR3_DQ(0)!!!!
S!M_D_DQ<10>!U5D1!DV83!@baseboard_fab2_lib.baseboard_fab2(sch_1):page26_i172@chpset_lib.skx_ext_b(chips)!SKX_EXT_B_BGA1-IC,TBD!!!F96!DDR3_DQ(10)!!!!
S!M_D_DQ<11>!U5D1!DY83!@baseboard_fab2_lib.baseboard_fab2(sch_1):page26_i172@chpset_lib.skx_ext_b(chips)!SKX_EXT_B_BGA1-IC,TBD!!!F96!DDR3_DQ(11)!!!!
S!M_D_DQ<12>!U5D1!DD85!@baseboard_fab2_lib.baseboard_fab2(sch_1):page26_i172@chpset_lib.skx_ext_b(chips)!SKX_EXT_B_BGA1-IC,TBD!!!F96!DDR3_DQ(12)!!!!
S!M_D_DQ<13>!U5D1!DE84!@baseboard_fab2_lib.baseboard_fab2(sch_1):page26_i172@chpset_lib.skx_ext_b(chips)!SKX_EXT_B_BGA1-IC,TBD!!!F96!DDR3_DQ(13)!!!!
S!M_D_DQ<14>!U5D1!DR84!@baseboard_fab2_lib.baseboard_fab2(sch_1):page26_i172@chpset_lib.skx_ext_b(chips)!SKX_EXT_B_BGA1-IC,TBD!!!F96!DDR3_DQ(14)!!!!
S!M_D_DQ<15>!U5D1!DV85!@baseboard_fab2_lib.baseboard_fab2(sch_1):page26_i172@chpset_lib.skx_ext_b(chips)!SKX_EXT_B_BGA1-IC,TBD!!!F96!DDR3_DQ(15)!!!!
S!M_D_DQ<16>!U5D1!DM79!@baseboard_fab2_lib.baseboard_fab2(sch_1):page26_i172@chpset_lib.skx_ext_b(chips)!SKX_EXT_B_BGA1-IC,TBD!!!F96!DDR3_DQ(16)!!!!
S!M_D_DQ<17>!U5D1!DK81!@baseboard_fab2_lib.baseboard_fab2(sch_1):page26_i172@chpset_lib.skx_ext_b(chips)!SKX_EXT_B_BGA1-IC,TBD!!!F96!DDR3_DQ(17)!!!!
S!M_D_DQ<18>!U5D1!DT81!@baseboard_fab2_lib.baseboard_fab2(sch_1):page26_i172@chpset_lib.skx_ext_b(chips)!SKX_EXT_B_BGA1-IC,TBD!!!F96!DDR3_DQ(18)!!!!
S!M_D_DQ<19>!U5D1!DR82!@baseboard_fab2_lib.baseboard_fab2(sch_1):page26_i172@chpset_lib.skx_ext_b(chips)!SKX_EXT_B_BGA1-IC,TBD!!!F96!DDR3_DQ(19)!!!!
S!M_D_DQ<1>!U5D1!CN86!@baseboard_fab2_lib.baseboard_fab2(sch_1):page26_i172@chpset_lib.skx_ext_b(chips)!SKX_EXT_B_BGA1-IC,TBD!!!F96!DDR3_DQ(1)!!!!
S!M_D_DQ<20>!U5D1!DK79!@baseboard_fab2_lib.baseboard_fab2(sch_1):page26_i172@chpset_lib.skx_ext_b(chips)!SKX_EXT_B_BGA1-IC,TBD!!!F96!DDR3_DQ(20)!!!!
S!M_D_DQ<21>!U5D1!DJ80!@baseboard_fab2_lib.baseboard_fab2(sch_1):page26_i172@chpset_lib.skx_ext_b(chips)!SKX_EXT_B_BGA1-IC,TBD!!!F96!DDR3_DQ(21)!!!!
S!M_D_DQ<22>!U5D1!DR80!@baseboard_fab2_lib.baseboard_fab2(sch_1):page26_i172@chpset_lib.skx_ext_b(chips)!SKX_EXT_B_BGA1-IC,TBD!!!F96!DDR3_DQ(22)!!!!
S!M_D_DQ<23>!U5D1!DN82!@baseboard_fab2_lib.baseboard_fab2(sch_1):page26_i172@chpset_lib.skx_ext_b(chips)!SKX_EXT_B_BGA1-IC,TBD!!!F96!DDR3_DQ(23)!!!!
S!M_D_DQ<24>!U5D1!DN76!@baseboard_fab2_lib.baseboard_fab2(sch_1):page26_i172@chpset_lib.skx_ext_b(chips)!SKX_EXT_B_BGA1-IC,TBD!!!F96!DDR3_DQ(24)!!!!
S!M_D_DQ<25>!U5D1!DU76!@baseboard_fab2_lib.baseboard_fab2(sch_1):page26_i172@chpset_lib.skx_ext_b(chips)!SKX_EXT_B_BGA1-IC,TBD!!!F96!DDR3_DQ(25)!!!!
S!M_D_DQ<26>!U5D1!DP73!@baseboard_fab2_lib.baseboard_fab2(sch_1):page26_i172@chpset_lib.skx_ext_b(chips)!SKX_EXT_B_BGA1-IC,TBD!!!F96!DDR3_DQ(26)!!!!
S!M_D_DQ<27>!U5D1!DT73!@baseboard_fab2_lib.baseboard_fab2(sch_1):page26_i172@chpset_lib.skx_ext_b(chips)!SKX_EXT_B_BGA1-IC,TBD!!!F96!DDR3_DQ(27)!!!!
S!M_D_DQ<28>!U5D1!DP77!@baseboard_fab2_lib.baseboard_fab2(sch_1):page26_i172@chpset_lib.skx_ext_b(chips)!SKX_EXT_B_BGA1-IC,TBD!!!F96!DDR3_DQ(28)!!!!
S!M_D_DQ<29>!U5D1!DT77!@baseboard_fab2_lib.baseboard_fab2(sch_1):page26_i172@chpset_lib.skx_ext_b(chips)!SKX_EXT_B_BGA1-IC,TBD!!!F96!DDR3_DQ(29)!!!!
S!M_D_DQ<2>!U5D1!DA86!@baseboard_fab2_lib.baseboard_fab2(sch_1):page26_i172@chpset_lib.skx_ext_b(chips)!SKX_EXT_B_BGA1-IC,TBD!!!F96!DDR3_DQ(2)!!!!
S!M_D_DQ<30>!U5D1!DN74!@baseboard_fab2_lib.baseboard_fab2(sch_1):page26_i172@chpset_lib.skx_ext_b(chips)!SKX_EXT_B_BGA1-IC,TBD!!!F96!DDR3_DQ(30)!!!!
S!M_D_DQ<31>!U5D1!DU74!@baseboard_fab2_lib.baseboard_fab2(sch_1):page26_i172@chpset_lib.skx_ext_b(chips)!SKX_EXT_B_BGA1-IC,TBD!!!F96!DDR3_DQ(31)!!!!
S!M_D_DQ<32>!U5D1!EC40!@baseboard_fab2_lib.baseboard_fab2(sch_1):page26_i172@chpset_lib.skx_ext_b(chips)!SKX_EXT_B_BGA1-IC,TBD!!!F96!DDR3_DQ(32)!!!!
S!M_D_DQ<33>!U5D1!ED39!@baseboard_fab2_lib.baseboard_fab2(sch_1):page26_i172@chpset_lib.skx_ext_b(chips)!SKX_EXT_B_BGA1-IC,TBD!!!F96!DDR3_DQ(33)!!!!
S!M_D_DQ<34>!U5D1!EA36!@baseboard_fab2_lib.baseboard_fab2(sch_1):page26_i172@chpset_lib.skx_ext_b(chips)!SKX_EXT_B_BGA1-IC,TBD!!!F96!DDR3_DQ(34)!!!!
S!M_D_DQ<35>!U5D1!EC36!@baseboard_fab2_lib.baseboard_fab2(sch_1):page26_i172@chpset_lib.skx_ext_b(chips)!SKX_EXT_B_BGA1-IC,TBD!!!F96!DDR3_DQ(35)!!!!
S!M_D_DQ<36>!U5D1!DY39!@baseboard_fab2_lib.baseboard_fab2(sch_1):page26_i172@chpset_lib.skx_ext_b(chips)!SKX_EXT_B_BGA1-IC,TBD!!!F96!DDR3_DQ(36)!!!!
S!M_D_DQ<37>!U5D1!EA40!@baseboard_fab2_lib.baseboard_fab2(sch_1):page26_i172@chpset_lib.skx_ext_b(chips)!SKX_EXT_B_BGA1-IC,TBD!!!F96!DDR3_DQ(37)!!!!
S!M_D_DQ<38>!U5D1!DY37!@baseboard_fab2_lib.baseboard_fab2(sch_1):page26_i172@chpset_lib.skx_ext_b(chips)!SKX_EXT_B_BGA1-IC,TBD!!!F96!DDR3_DQ(38)!!!!
S!M_D_DQ<39>!U5D1!ED37!@baseboard_fab2_lib.baseboard_fab2(sch_1):page26_i172@chpset_lib.skx_ext_b(chips)!SKX_EXT_B_BGA1-IC,TBD!!!F96!DDR3_DQ(39)!!!!
S!M_D_DQ<3>!U5D1!DA84!@baseboard_fab2_lib.baseboard_fab2(sch_1):page26_i172@chpset_lib.skx_ext_b(chips)!SKX_EXT_B_BGA1-IC,TBD!!!F96!DDR3_DQ(3)!!!!
S!M_D_DQ<40>!U5D1!DN36!@baseboard_fab2_lib.baseboard_fab2(sch_1):page26_i172@chpset_lib.skx_ext_b(chips)!SKX_EXT_B_BGA1-IC,TBD!!!F96!DDR3_DQ(40)!!!!
S!M_D_DQ<41>!U5D1!DU36!@baseboard_fab2_lib.baseboard_fab2(sch_1):page26_i172@chpset_lib.skx_ext_b(chips)!SKX_EXT_B_BGA1-IC,TBD!!!F96!DDR3_DQ(41)!!!!
S!M_D_DQ<42>!U5D1!DP33!@baseboard_fab2_lib.baseboard_fab2(sch_1):page26_i172@chpset_lib.skx_ext_b(chips)!SKX_EXT_B_BGA1-IC,TBD!!!F96!DDR3_DQ(42)!!!!
S!M_D_DQ<43>!U5D1!DT33!@baseboard_fab2_lib.baseboard_fab2(sch_1):page26_i172@chpset_lib.skx_ext_b(chips)!SKX_EXT_B_BGA1-IC,TBD!!!F96!DDR3_DQ(43)!!!!
S!M_D_DQ<44>!U5D1!DP37!@baseboard_fab2_lib.baseboard_fab2(sch_1):page26_i172@chpset_lib.skx_ext_b(chips)!SKX_EXT_B_BGA1-IC,TBD!!!F96!DDR3_DQ(44)!!!!
S!M_D_DQ<45>!U5D1!DT37!@baseboard_fab2_lib.baseboard_fab2(sch_1):page26_i172@chpset_lib.skx_ext_b(chips)!SKX_EXT_B_BGA1-IC,TBD!!!F96!DDR3_DQ(45)!!!!
S!M_D_DQ<46>!U5D1!DN34!@baseboard_fab2_lib.baseboard_fab2(sch_1):page26_i172@chpset_lib.skx_ext_b(chips)!SKX_EXT_B_BGA1-IC,TBD!!!F96!DDR3_DQ(46)!!!!
S!M_D_DQ<47>!U5D1!DU34!@baseboard_fab2_lib.baseboard_fab2(sch_1):page26_i172@chpset_lib.skx_ext_b(chips)!SKX_EXT_B_BGA1-IC,TBD!!!F96!DDR3_DQ(47)!!!!
S!M_D_DQ<48>!U5D1!DN30!@baseboard_fab2_lib.baseboard_fab2(sch_1):page26_i172@chpset_lib.skx_ext_b(chips)!SKX_EXT_B_BGA1-IC,TBD!!!F96!DDR3_DQ(48)!!!!
S!M_D_DQ<49>!U5D1!DU30!@baseboard_fab2_lib.baseboard_fab2(sch_1):page26_i172@chpset_lib.skx_ext_b(chips)!SKX_EXT_B_BGA1-IC,TBD!!!F96!DDR3_DQ(49)!!!!
S!M_D_DQ<4>!U5D1!CL84!@baseboard_fab2_lib.baseboard_fab2(sch_1):page26_i172@chpset_lib.skx_ext_b(chips)!SKX_EXT_B_BGA1-IC,TBD!!!F96!DDR3_DQ(4)!!!!
S!M_D_DQ<50>!U5D1!DP27!@baseboard_fab2_lib.baseboard_fab2(sch_1):page26_i172@chpset_lib.skx_ext_b(chips)!SKX_EXT_B_BGA1-IC,TBD!!!F96!DDR3_DQ(50)!!!!
S!M_D_DQ<51>!U5D1!DT27!@baseboard_fab2_lib.baseboard_fab2(sch_1):page26_i172@chpset_lib.skx_ext_b(chips)!SKX_EXT_B_BGA1-IC,TBD!!!F96!DDR3_DQ(51)!!!!
S!M_D_DQ<52>!U5D1!DP31!@baseboard_fab2_lib.baseboard_fab2(sch_1):page26_i172@chpset_lib.skx_ext_b(chips)!SKX_EXT_B_BGA1-IC,TBD!!!F96!DDR3_DQ(52)!!!!
S!M_D_DQ<53>!U5D1!DT31!@baseboard_fab2_lib.baseboard_fab2(sch_1):page26_i172@chpset_lib.skx_ext_b(chips)!SKX_EXT_B_BGA1-IC,TBD!!!F96!DDR3_DQ(53)!!!!
S!M_D_DQ<54>!U5D1!DN28!@baseboard_fab2_lib.baseboard_fab2(sch_1):page26_i172@chpset_lib.skx_ext_b(chips)!SKX_EXT_B_BGA1-IC,TBD!!!F96!DDR3_DQ(54)!!!!
S!M_D_DQ<55>!U5D1!DU28!@baseboard_fab2_lib.baseboard_fab2(sch_1):page26_i172@chpset_lib.skx_ext_b(chips)!SKX_EXT_B_BGA1-IC,TBD!!!F96!DDR3_DQ(55)!!!!
S!M_D_DQ<56>!U5D1!DN24!@baseboard_fab2_lib.baseboard_fab2(sch_1):page26_i172@chpset_lib.skx_ext_b(chips)!SKX_EXT_B_BGA1-IC,TBD!!!F96!DDR3_DQ(56)!!!!
S!M_D_DQ<57>!U5D1!DU24!@baseboard_fab2_lib.baseboard_fab2(sch_1):page26_i172@chpset_lib.skx_ext_b(chips)!SKX_EXT_B_BGA1-IC,TBD!!!F96!DDR3_DQ(57)!!!!
S!M_D_DQ<59>!U5D1!EB21!@baseboard_fab2_lib.baseboard_fab2(sch_1):page26_i172@chpset_lib.skx_ext_b(chips)!SKX_EXT_B_BGA1-IC,TBD!!!F96!DDR3_DQ(59)!!!!
S!M_D_DQ<58>!U5D1!DY21!@baseboard_fab2_lib.baseboard_fab2(sch_1):page26_i172@chpset_lib.skx_ext_b(chips)!SKX_EXT_B_BGA1-IC,TBD!!!F96!DDR3_DQ(58)!!!!
S!M_D_DQ<5>!U5D1!CL86!@baseboard_fab2_lib.baseboard_fab2(sch_1):page26_i172@chpset_lib.skx_ext_b(chips)!SKX_EXT_B_BGA1-IC,TBD!!!F96!DDR3_DQ(5)!!!!
S!M_D_DQ<60>!U5D1!DP25!@baseboard_fab2_lib.baseboard_fab2(sch_1):page26_i172@chpset_lib.skx_ext_b(chips)!SKX_EXT_B_BGA1-IC,TBD!!!F96!DDR3_DQ(60)!!!!
S!M_D_DQ<61>!U5D1!DT25!@baseboard_fab2_lib.baseboard_fab2(sch_1):page26_i172@chpset_lib.skx_ext_b(chips)!SKX_EXT_B_BGA1-IC,TBD!!!F96!DDR3_DQ(61)!!!!
S!M_D_DQ<62>!U5D1!EC22!@baseboard_fab2_lib.baseboard_fab2(sch_1):page26_i172@chpset_lib.skx_ext_b(chips)!SKX_EXT_B_BGA1-IC,TBD!!!F96!DDR3_DQ(62)!!!!
S!M_D_DQ<63>!U5D1!DW22!@baseboard_fab2_lib.baseboard_fab2(sch_1):page26_i172@chpset_lib.skx_ext_b(chips)!SKX_EXT_B_BGA1-IC,TBD!!!F96!DDR3_DQ(63)!!!!
S!M_D_DQ<6>!U5D1!CW86!@baseboard_fab2_lib.baseboard_fab2(sch_1):page26_i172@chpset_lib.skx_ext_b(chips)!SKX_EXT_B_BGA1-IC,TBD!!!F96!DDR3_DQ(6)!!!!
S!M_D_DQ<7>!U5D1!CW84!@baseboard_fab2_lib.baseboard_fab2(sch_1):page26_i172@chpset_lib.skx_ext_b(chips)!SKX_EXT_B_BGA1-IC,TBD!!!F96!DDR3_DQ(7)!!!!
S!M_D_DQ<8>!U5D1!DG84!@baseboard_fab2_lib.baseboard_fab2(sch_1):page26_i172@chpset_lib.skx_ext_b(chips)!SKX_EXT_B_BGA1-IC,TBD!!!F96!DDR3_DQ(8)!!!!
S!M_D_DQ<9>!U5D1!DH85!@baseboard_fab2_lib.baseboard_fab2(sch_1):page26_i172@chpset_lib.skx_ext_b(chips)!SKX_EXT_B_BGA1-IC,TBD!!!F96!DDR3_DQ(9)!!!!
S!M_D_DQS_DN<0>!U5D1!CU84!@baseboard_fab2_lib.baseboard_fab2(sch_1):page26_i172@chpset_lib.skx_ext_b(chips)!SKX_EXT_B_BGA1-IC,TBD!!!F96!DDR3_DQS_DN(0)!!!!
S!M_D_DQS_DN<10>!U5D1!DM85!@baseboard_fab2_lib.baseboard_fab2(sch_1):page26_i172@chpset_lib.skx_ext_b(chips)!SKX_EXT_B_BGA1-IC,TBD!!!F96!DDR3_DQS_DN(10)!!!!
S!M_D_DQS_DN<11>!U5D1!DN80!@baseboard_fab2_lib.baseboard_fab2(sch_1):page26_i172@chpset_lib.skx_ext_b(chips)!SKX_EXT_B_BGA1-IC,TBD!!!F96!DDR3_DQS_DN(11)!!!!
S!M_D_DQS_DN<12>!U5D1!DP75!@baseboard_fab2_lib.baseboard_fab2(sch_1):page26_i172@chpset_lib.skx_ext_b(chips)!SKX_EXT_B_BGA1-IC,TBD!!!F96!DDR3_DQS_DN(12)!!!!
S!M_D_DQS_DN<13>!U5D1!EA38!@baseboard_fab2_lib.baseboard_fab2(sch_1):page26_i172@chpset_lib.skx_ext_b(chips)!SKX_EXT_B_BGA1-IC,TBD!!!F96!DDR3_DQS_DN(13)!!!!
S!M_D_DQS_DN<14>!U5D1!DP35!@baseboard_fab2_lib.baseboard_fab2(sch_1):page26_i172@chpset_lib.skx_ext_b(chips)!SKX_EXT_B_BGA1-IC,TBD!!!F96!DDR3_DQS_DN(14)!!!!
S!M_D_DQS_DN<15>!U5D1!DM29!@baseboard_fab2_lib.baseboard_fab2(sch_1):page26_i172@chpset_lib.skx_ext_b(chips)!SKX_EXT_B_BGA1-IC,TBD!!!F96!DDR3_DQS_DN(15)!!!!
S!M_D_DQS_DN<16>!U5D1!DM23!@baseboard_fab2_lib.baseboard_fab2(sch_1):page26_i172@chpset_lib.skx_ext_b(chips)!SKX_EXT_B_BGA1-IC,TBD!!!F96!DDR3_DQS_DN(16)!!!!
S!M_D_DQS_DN<17>!U5D1!DB67!@baseboard_fab2_lib.baseboard_fab2(sch_1):page26_i172@chpset_lib.skx_ext_b(chips)!SKX_EXT_B_BGA1-IC,TBD!!!F96!DDR3_DQS_DN(17)!!!!
S!M_D_DQS_DN<1>!U5D1!DN84!@baseboard_fab2_lib.baseboard_fab2(sch_1):page26_i172@chpset_lib.skx_ext_b(chips)!SKX_EXT_B_BGA1-IC,TBD!!!F96!DDR3_DQS_DN(1)!!!!
S!M_D_DQS_DN<2>!U5D1!DL82!@baseboard_fab2_lib.baseboard_fab2(sch_1):page26_i172@chpset_lib.skx_ext_b(chips)!SKX_EXT_B_BGA1-IC,TBD!!!F96!DDR3_DQS_DN(2)!!!!
S!M_D_DQS_DN<3>!U5D1!DV75!@baseboard_fab2_lib.baseboard_fab2(sch_1):page26_i172@chpset_lib.skx_ext_b(chips)!SKX_EXT_B_BGA1-IC,TBD!!!F96!DDR3_DQS_DN(3)!!!!
S!M_D_DQS_DN<4>!U5D1!EE38!@baseboard_fab2_lib.baseboard_fab2(sch_1):page26_i172@chpset_lib.skx_ext_b(chips)!SKX_EXT_B_BGA1-IC,TBD!!!F96!DDR3_DQS_DN(4)!!!!
S!M_D_DQS_DN<5>!U5D1!DV35!@baseboard_fab2_lib.baseboard_fab2(sch_1):page26_i172@chpset_lib.skx_ext_b(chips)!SKX_EXT_B_BGA1-IC,TBD!!!F96!DDR3_DQS_DN(5)!!!!
S!M_D_DQS_DN<6>!U5D1!DV29!@baseboard_fab2_lib.baseboard_fab2(sch_1):page26_i172@chpset_lib.skx_ext_b(chips)!SKX_EXT_B_BGA1-IC,TBD!!!F96!DDR3_DQS_DN(6)!!!!
S!M_D_DQS_DN<7>!U5D1!DV23!@baseboard_fab2_lib.baseboard_fab2(sch_1):page26_i172@chpset_lib.skx_ext_b(chips)!SKX_EXT_B_BGA1-IC,TBD!!!F96!DDR3_DQS_DN(7)!!!!
S!M_D_DQS_DN<8>!U5D1!DF67!@baseboard_fab2_lib.baseboard_fab2(sch_1):page26_i172@chpset_lib.skx_ext_b(chips)!SKX_EXT_B_BGA1-IC,TBD!!!F96!DDR3_DQS_DN(8)!!!!
S!M_D_DQS_DN<9>!U5D1!CR84!@baseboard_fab2_lib.baseboard_fab2(sch_1):page26_i172@chpset_lib.skx_ext_b(chips)!SKX_EXT_B_BGA1-IC,TBD!!!F96!DDR3_DQS_DN(9)!!!!
S!M_D_DQS_DP<0>!U5D1!CV85!@baseboard_fab2_lib.baseboard_fab2(sch_1):page26_i172@chpset_lib.skx_ext_b(chips)!SKX_EXT_B_BGA1-IC,TBD!!!F96!DDR3_DQS_DP(0)!!!!
S!M_D_DQS_DP<10>!U5D1!DL84!@baseboard_fab2_lib.baseboard_fab2(sch_1):page26_i172@chpset_lib.skx_ext_b(chips)!SKX_EXT_B_BGA1-IC,TBD!!!F96!DDR3_DQS_DP(10)!!!!
S!M_D_DQS_DP<11>!U5D1!DP79!@baseboard_fab2_lib.baseboard_fab2(sch_1):page26_i172@chpset_lib.skx_ext_b(chips)!SKX_EXT_B_BGA1-IC,TBD!!!F96!DDR3_DQS_DP(11)!!!!
S!M_D_DQS_DP<12>!U5D1!DM75!@baseboard_fab2_lib.baseboard_fab2(sch_1):page26_i172@chpset_lib.skx_ext_b(chips)!SKX_EXT_B_BGA1-IC,TBD!!!F96!DDR3_DQS_DP(12)!!!!
S!M_D_DQS_DP<13>!U5D1!DW38!@baseboard_fab2_lib.baseboard_fab2(sch_1):page26_i172@chpset_lib.skx_ext_b(chips)!SKX_EXT_B_BGA1-IC,TBD!!!F96!DDR3_DQS_DP(13)!!!!
S!M_D_DQS_DP<14>!U5D1!DM35!@baseboard_fab2_lib.baseboard_fab2(sch_1):page26_i172@chpset_lib.skx_ext_b(chips)!SKX_EXT_B_BGA1-IC,TBD!!!F96!DDR3_DQS_DP(14)!!!!
S!M_D_DQS_DP<15>!U5D1!DP29!@baseboard_fab2_lib.baseboard_fab2(sch_1):page26_i172@chpset_lib.skx_ext_b(chips)!SKX_EXT_B_BGA1-IC,TBD!!!F96!DDR3_DQS_DP(15)!!!!
S!M_D_DQS_DP<16>!U5D1!DP23!@baseboard_fab2_lib.baseboard_fab2(sch_1):page26_i172@chpset_lib.skx_ext_b(chips)!SKX_EXT_B_BGA1-IC,TBD!!!F96!DDR3_DQS_DP(16)!!!!
S!M_D_DQS_DP<17>!U5D1!CY67!@baseboard_fab2_lib.baseboard_fab2(sch_1):page26_i172@chpset_lib.skx_ext_b(chips)!SKX_EXT_B_BGA1-IC,TBD!!!F96!DDR3_DQS_DP(17)!!!!
S!M_D_DQS_DP<1>!U5D1!DP85!@baseboard_fab2_lib.baseboard_fab2(sch_1):page26_i172@chpset_lib.skx_ext_b(chips)!SKX_EXT_B_BGA1-IC,TBD!!!F96!DDR3_DQS_DP(1)!!!!
S!M_D_DQS_DP<2>!U5D1!DM81!@baseboard_fab2_lib.baseboard_fab2(sch_1):page26_i172@chpset_lib.skx_ext_b(chips)!SKX_EXT_B_BGA1-IC,TBD!!!F96!DDR3_DQS_DP(2)!!!!
S!M_D_DQS_DP<3>!U5D1!DT75!@baseboard_fab2_lib.baseboard_fab2(sch_1):page26_i172@chpset_lib.skx_ext_b(chips)!SKX_EXT_B_BGA1-IC,TBD!!!F96!DDR3_DQS_DP(3)!!!!
S!M_D_DQS_DP<4>!U5D1!EC38!@baseboard_fab2_lib.baseboard_fab2(sch_1):page26_i172@chpset_lib.skx_ext_b(chips)!SKX_EXT_B_BGA1-IC,TBD!!!F96!DDR3_DQS_DP(4)!!!!
S!M_D_DQS_DP<5>!U5D1!DT35!@baseboard_fab2_lib.baseboard_fab2(sch_1):page26_i172@chpset_lib.skx_ext_b(chips)!SKX_EXT_B_BGA1-IC,TBD!!!F96!DDR3_DQS_DP(5)!!!!
S!M_D_DQS_DP<6>!U5D1!DT29!@baseboard_fab2_lib.baseboard_fab2(sch_1):page26_i172@chpset_lib.skx_ext_b(chips)!SKX_EXT_B_BGA1-IC,TBD!!!F96!DDR3_DQS_DP(6)!!!!
S!M_D_DQS_DP<7>!U5D1!DT23!@baseboard_fab2_lib.baseboard_fab2(sch_1):page26_i172@chpset_lib.skx_ext_b(chips)!SKX_EXT_B_BGA1-IC,TBD!!!F96!DDR3_DQS_DP(7)!!!!
S!M_D_DQS_DP<8>!U5D1!DD67!@baseboard_fab2_lib.baseboard_fab2(sch_1):page26_i172@chpset_lib.skx_ext_b(chips)!SKX_EXT_B_BGA1-IC,TBD!!!F96!DDR3_DQS_DP(8)!!!!
S!M_D_DQS_DP<9>!U5D1!CP85!@baseboard_fab2_lib.baseboard_fab2(sch_1):page26_i172@chpset_lib.skx_ext_b(chips)!SKX_EXT_B_BGA1-IC,TBD!!!F96!DDR3_DQS_DP(9)!!!!
S!M_D_ECC<0>!U5D1!DA68!@baseboard_fab2_lib.baseboard_fab2(sch_1):page26_i172@chpset_lib.skx_ext_b(chips)!SKX_EXT_B_BGA1-IC,TBD!!!F96!DDR3_ECC(0)!!!!
S!M_D_ECC<1>!U5D1!DE68!@baseboard_fab2_lib.baseboard_fab2(sch_1):page26_i172@chpset_lib.skx_ext_b(chips)!SKX_EXT_B_BGA1-IC,TBD!!!F96!DDR3_ECC(1)!!!!
S!M_D_ECC<2>!U5D1!DB65!@baseboard_fab2_lib.baseboard_fab2(sch_1):page26_i172@chpset_lib.skx_ext_b(chips)!SKX_EXT_B_BGA1-IC,TBD!!!F96!DDR3_ECC(2)!!!!
S!M_D_ECC<3>!U5D1!DD65!@baseboard_fab2_lib.baseboard_fab2(sch_1):page26_i172@chpset_lib.skx_ext_b(chips)!SKX_EXT_B_BGA1-IC,TBD!!!F96!DDR3_ECC(3)!!!!
S!M_D_ECC<4>!U5D1!DB69!@baseboard_fab2_lib.baseboard_fab2(sch_1):page26_i172@chpset_lib.skx_ext_b(chips)!SKX_EXT_B_BGA1-IC,TBD!!!F96!DDR3_ECC(4)!!!!
S!M_D_ECC<5>!U5D1!DD69!@baseboard_fab2_lib.baseboard_fab2(sch_1):page26_i172@chpset_lib.skx_ext_b(chips)!SKX_EXT_B_BGA1-IC,TBD!!!F96!DDR3_ECC(5)!!!!
S!M_D_ECC<6>!U5D1!DA66!@baseboard_fab2_lib.baseboard_fab2(sch_1):page26_i172@chpset_lib.skx_ext_b(chips)!SKX_EXT_B_BGA1-IC,TBD!!!F96!DDR3_ECC(6)!!!!
S!M_D_ECC<7>!U5D1!DE66!@baseboard_fab2_lib.baseboard_fab2(sch_1):page26_i172@chpset_lib.skx_ext_b(chips)!SKX_EXT_B_BGA1-IC,TBD!!!F96!DDR3_ECC(7)!!!!
S!M_D_MA<0>!U5D1!EB53!@baseboard_fab2_lib.baseboard_fab2(sch_1):page26_i172@chpset_lib.skx_ext_b(chips)!SKX_EXT_B_BGA1-IC,TBD!!!F96!DDR3_MA(0)!!!!
S!M_D_MA<10>!U5D1!DW54!@baseboard_fab2_lib.baseboard_fab2(sch_1):page26_i172@chpset_lib.skx_ext_b(chips)!SKX_EXT_B_BGA1-IC,TBD!!!F96!DDR3_MA(10)!!!!
S!M_D_MA<11>!U5D1!EB61!@baseboard_fab2_lib.baseboard_fab2(sch_1):page26_i172@chpset_lib.skx_ext_b(chips)!SKX_EXT_B_BGA1-IC,TBD!!!F96!DDR3_MA(11)!!!!
S!M_D_MA<12>!U5D1!DT63!@baseboard_fab2_lib.baseboard_fab2(sch_1):page26_i172@chpset_lib.skx_ext_b(chips)!SKX_EXT_B_BGA1-IC,TBD!!!F96!DDR3_MA(12)!!!!
S!M_D_MA<13>!U5D1!DW48!@baseboard_fab2_lib.baseboard_fab2(sch_1):page26_i172@chpset_lib.skx_ext_b(chips)!SKX_EXT_B_BGA1-IC,TBD!!!F96!DDR3_MA(13)!!!!
S!M_D_MA<14>!U5D1!ED51!@baseboard_fab2_lib.baseboard_fab2(sch_1):page26_i172@chpset_lib.skx_ext_b(chips)!SKX_EXT_B_BGA1-IC,TBD!!!F96!DDR3_MA(14)!!!!
S!M_D_MA<15>!U5D1!DV49!@baseboard_fab2_lib.baseboard_fab2(sch_1):page26_i172@chpset_lib.skx_ext_b(chips)!SKX_EXT_B_BGA1-IC,TBD!!!F96!DDR3_MA(15)!!!!
S!M_D_MA<16>!U5D1!EA52!@baseboard_fab2_lib.baseboard_fab2(sch_1):page26_i172@chpset_lib.skx_ext_b(chips)!SKX_EXT_B_BGA1-IC,TBD!!!F96!DDR3_MA(16)!!!!
S!M_D_MA<17>!U5D1!EA46!@baseboard_fab2_lib.baseboard_fab2(sch_1):page26_i172@chpset_lib.skx_ext_b(chips)!SKX_EXT_B_BGA1-IC,TBD!!!F96!DDR3_MA(17)!!!!
S!M_D_MA<1>!U5D1!ED57!@baseboard_fab2_lib.baseboard_fab2(sch_1):page26_i172@chpset_lib.skx_ext_b(chips)!SKX_EXT_B_BGA1-IC,TBD!!!F96!DDR3_MA(1)!!!!
S!M_D_MA<2>!U5D1!EE58!@baseboard_fab2_lib.baseboard_fab2(sch_1):page26_i172@chpset_lib.skx_ext_b(chips)!SKX_EXT_B_BGA1-IC,TBD!!!F96!DDR3_MA(2)!!!!
S!M_D_MA<3>!U5D1!EB57!@baseboard_fab2_lib.baseboard_fab2(sch_1):page26_i172@chpset_lib.skx_ext_b(chips)!SKX_EXT_B_BGA1-IC,TBD!!!F96!DDR3_MA(3)!!!!
S!M_D_MA<4>!U5D1!ED59!@baseboard_fab2_lib.baseboard_fab2(sch_1):page26_i172@chpset_lib.skx_ext_b(chips)!SKX_EXT_B_BGA1-IC,TBD!!!F96!DDR3_MA(4)!!!!
S!M_D_MA<5>!U5D1!EA58!@baseboard_fab2_lib.baseboard_fab2(sch_1):page26_i172@chpset_lib.skx_ext_b(chips)!SKX_EXT_B_BGA1-IC,TBD!!!F96!DDR3_MA(5)!!!!
S!M_D_MA<6>!U5D1!EE60!@baseboard_fab2_lib.baseboard_fab2(sch_1):page26_i172@chpset_lib.skx_ext_b(chips)!SKX_EXT_B_BGA1-IC,TBD!!!F96!DDR3_MA(6)!!!!
S!M_D_MA<7>!U5D1!EA60!@baseboard_fab2_lib.baseboard_fab2(sch_1):page26_i172@chpset_lib.skx_ext_b(chips)!SKX_EXT_B_BGA1-IC,TBD!!!F96!DDR3_MA(7)!!!!
S!M_D_MA<8>!U5D1!EB59!@baseboard_fab2_lib.baseboard_fab2(sch_1):page26_i172@chpset_lib.skx_ext_b(chips)!SKX_EXT_B_BGA1-IC,TBD!!!F96!DDR3_MA(8)!!!!
S!M_D_MA<9>!U5D1!EF61!@baseboard_fab2_lib.baseboard_fab2(sch_1):page26_i172@chpset_lib.skx_ext_b(chips)!SKX_EXT_B_BGA1-IC,TBD!!!F96!DDR3_MA(9)!!!!
S!M_D_ODT<0>!U5D1!EE50!@baseboard_fab2_lib.baseboard_fab2(sch_1):page26_i172@chpset_lib.skx_ext_b(chips)!SKX_EXT_B_BGA1-IC,TBD!!!F96!DDR3_ODT(0)!!!!
S!M_D_ODT<1>!U5D1!EE48!@baseboard_fab2_lib.baseboard_fab2(sch_1):page26_i172@chpset_lib.skx_ext_b(chips)!SKX_EXT_B_BGA1-IC,TBD!!!F96!DDR3_ODT(1)!!!!
S!M_D_ODT<2>!U5D1!EA50!@baseboard_fab2_lib.baseboard_fab2(sch_1):page26_i172@chpset_lib.skx_ext_b(chips)!SKX_EXT_B_BGA1-IC,TBD!!!F96!DDR3_ODT(2)!!!!
S!M_D_ODT<3>!U5D1!EA48!@baseboard_fab2_lib.baseboard_fab2(sch_1):page26_i172@chpset_lib.skx_ext_b(chips)!SKX_EXT_B_BGA1-IC,TBD!!!F96!DDR3_ODT(3)!!!!
S!M_D_PAR!U5D1!ED53!@baseboard_fab2_lib.baseboard_fab2(sch_1):page26_i172@chpset_lib.skx_ext_b(chips)!SKX_EXT_B_BGA1-IC,TBD!!!F96!DDR3_PAR!!!!
S!M_E_ACT_N!U5D1!DR62!@baseboard_fab2_lib.baseboard_fab2(sch_1):page27_i172@chpset_lib.skx_ext_b(chips)!SKX_EXT_B_BGA1-IC,TBD!!!F95!DDR4_ACT_N!!!!
S!M_E_ALERT_N!U5D1!DT61!@baseboard_fab2_lib.baseboard_fab2(sch_1):page27_i172@chpset_lib.skx_ext_b(chips)!SKX_EXT_B_BGA1-IC,TBD!!!F95!DDR4_ALERT_N!!!!
S!M_E_BA<0>!U5D1!DM53!@baseboard_fab2_lib.baseboard_fab2(sch_1):page27_i172@chpset_lib.skx_ext_b(chips)!SKX_EXT_B_BGA1-IC,TBD!!!F95!DDR4_BA(0)!!!!
S!M_E_BA<1>!U5D1!DV55!@baseboard_fab2_lib.baseboard_fab2(sch_1):page27_i172@chpset_lib.skx_ext_b(chips)!SKX_EXT_B_BGA1-IC,TBD!!!F95!DDR4_BA(1)!!!!
S!M_E_BG<0>!U5D1!DJ62!@baseboard_fab2_lib.baseboard_fab2(sch_1):page27_i172@chpset_lib.skx_ext_b(chips)!SKX_EXT_B_BGA1-IC,TBD!!!F95!DDR4_BG(0)!!!!
S!M_E_BG<1>!U5D1!DM61!@baseboard_fab2_lib.baseboard_fab2(sch_1):page27_i172@chpset_lib.skx_ext_b(chips)!SKX_EXT_B_BGA1-IC,TBD!!!F95!DDR4_BG(1)!!!!
S!M_E_C<2>!U5D1!DT47!@baseboard_fab2_lib.baseboard_fab2(sch_1):page27_i172@chpset_lib.skx_ext_b(chips)!SKX_EXT_B_BGA1-IC,TBD!!!F95!DDR4_CID(2)!!!!
S!M_E_CKE<0>!U5D1!DM63!@baseboard_fab2_lib.baseboard_fab2(sch_1):page27_i172@chpset_lib.skx_ext_b(chips)!SKX_EXT_B_BGA1-IC,TBD!!!F95!DDR4_CKE(0)!!!!
S!M_E_CKE<1>!U5D1!DN64!@baseboard_fab2_lib.baseboard_fab2(sch_1):page27_i172@chpset_lib.skx_ext_b(chips)!SKX_EXT_B_BGA1-IC,TBD!!!F95!DDR4_CKE(1)!!!!
S!M_E_CKE<2>!U5D1!DL64!@baseboard_fab2_lib.baseboard_fab2(sch_1):page27_i172@chpset_lib.skx_ext_b(chips)!SKX_EXT_B_BGA1-IC,TBD!!!F95!DDR4_CKE(2)!!!!
S!M_E_CKE<3>!U5D1!DR64!@baseboard_fab2_lib.baseboard_fab2(sch_1):page27_i172@chpset_lib.skx_ext_b(chips)!SKX_EXT_B_BGA1-IC,TBD!!!F95!DDR4_CKE(3)!!!!
S!M_E_CLK_DN<0>!U5D1!DM55!@baseboard_fab2_lib.baseboard_fab2(sch_1):page27_i172@chpset_lib.skx_ext_b(chips)!SKX_EXT_B_BGA1-IC,TBD!!!F95!DDR4_CLK_DN(0)!!!!
S!M_E_CLK_DN<2>!U5D1!DM57!@baseboard_fab2_lib.baseboard_fab2(sch_1):page27_i172@chpset_lib.skx_ext_b(chips)!SKX_EXT_B_BGA1-IC,TBD!!!F95!DDR4_CLK_DN(2)!!!!
S!M_E_CLK_DN<1>!U5D1!DR54!@baseboard_fab2_lib.baseboard_fab2(sch_1):page27_i172@chpset_lib.skx_ext_b(chips)!SKX_EXT_B_BGA1-IC,TBD!!!F95!DDR4_CLK_DN(1)!!!!
S!M_E_CLK_DN<3>!U5D1!DT57!@baseboard_fab2_lib.baseboard_fab2(sch_1):page27_i172@chpset_lib.skx_ext_b(chips)!SKX_EXT_B_BGA1-IC,TBD!!!F95!DDR4_CLK_DN(3)!!!!
S!M_E_CLK_DP<0>!U5D1!DN54!@baseboard_fab2_lib.baseboard_fab2(sch_1):page27_i172@chpset_lib.skx_ext_b(chips)!SKX_EXT_B_BGA1-IC,TBD!!!F95!DDR4_CLK_DP(0)!!!!
S!M_E_CLK_DP<2>!U5D1!DN56!@baseboard_fab2_lib.baseboard_fab2(sch_1):page27_i172@chpset_lib.skx_ext_b(chips)!SKX_EXT_B_BGA1-IC,TBD!!!F95!DDR4_CLK_DP(2)!!!!
S!M_E_CLK_DP<1>!U5D1!DT53!@baseboard_fab2_lib.baseboard_fab2(sch_1):page27_i172@chpset_lib.skx_ext_b(chips)!SKX_EXT_B_BGA1-IC,TBD!!!F95!DDR4_CLK_DP(1)!!!!
S!M_E_CLK_DP<3>!U5D1!DR56!@baseboard_fab2_lib.baseboard_fab2(sch_1):page27_i172@chpset_lib.skx_ext_b(chips)!SKX_EXT_B_BGA1-IC,TBD!!!F95!DDR4_CLK_DP(3)!!!!
S!M_E_CS_N<0>!U5D1!DV51!@baseboard_fab2_lib.baseboard_fab2(sch_1):page27_i172@chpset_lib.skx_ext_b(chips)!SKX_EXT_B_BGA1-IC,TBD!!!F95!DDR4_CS_N(0)!!!!
S!M_E_CS_N<1>!U5D1!DN50!@baseboard_fab2_lib.baseboard_fab2(sch_1):page27_i172@chpset_lib.skx_ext_b(chips)!SKX_EXT_B_BGA1-IC,TBD!!!F95!DDR4_CS_N(1)!!!!
S!M_E_CS_N<2>!U5D1!DR46!@baseboard_fab2_lib.baseboard_fab2(sch_1):page27_i172@chpset_lib.skx_ext_b(chips)!SKX_EXT_B_BGA1-IC,TBD!!!F95!DDR4_CS_N(2)!!!!
S!M_E_CS_N<3>!U5D1!DK47!@baseboard_fab2_lib.baseboard_fab2(sch_1):page27_i172@chpset_lib.skx_ext_b(chips)!SKX_EXT_B_BGA1-IC,TBD!!!F95!DDR4_CS_N(3)!!!!
S!M_E_CS_N<4>!U5D1!DW50!@baseboard_fab2_lib.baseboard_fab2(sch_1):page27_i172@chpset_lib.skx_ext_b(chips)!SKX_EXT_B_BGA1-IC,TBD!!!F95!DDR4_CS_N(4)!!!!
S!M_E_CS_N<5>!U5D1!DM49!@baseboard_fab2_lib.baseboard_fab2(sch_1):page27_i172@chpset_lib.skx_ext_b(chips)!SKX_EXT_B_BGA1-IC,TBD!!!F95!DDR4_CS_N(5)!!!!
S!M_E_CS_N<6>!U5D1!DT45!@baseboard_fab2_lib.baseboard_fab2(sch_1):page27_i172@chpset_lib.skx_ext_b(chips)!SKX_EXT_B_BGA1-IC,TBD!!!F95!DDR4_CS_N(6)!!!!
S!M_E_CS_N<7>!U5D1!DN46!@baseboard_fab2_lib.baseboard_fab2(sch_1):page27_i172@chpset_lib.skx_ext_b(chips)!SKX_EXT_B_BGA1-IC,TBD!!!F95!DDR4_CS_N(7)!!!!
S!M_E_DQ<0>!U5D1!CM79!@baseboard_fab2_lib.baseboard_fab2(sch_1):page27_i172@chpset_lib.skx_ext_b(chips)!SKX_EXT_B_BGA1-IC,TBD!!!F95!DDR4_DQ(0)!!!!
S!M_E_DQ<10>!U5D1!DE80!@baseboard_fab2_lib.baseboard_fab2(sch_1):page27_i172@chpset_lib.skx_ext_b(chips)!SKX_EXT_B_BGA1-IC,TBD!!!F95!DDR4_DQ(10)!!!!
S!M_E_DQ<11>!U5D1!DF81!@baseboard_fab2_lib.baseboard_fab2(sch_1):page27_i172@chpset_lib.skx_ext_b(chips)!SKX_EXT_B_BGA1-IC,TBD!!!F95!DDR4_DQ(11)!!!!
S!M_E_DQ<12>!U5D1!CY79!@baseboard_fab2_lib.baseboard_fab2(sch_1):page27_i172@chpset_lib.skx_ext_b(chips)!SKX_EXT_B_BGA1-IC,TBD!!!F95!DDR4_DQ(12)!!!!
S!M_E_DQ<13>!U5D1!CW80!@baseboard_fab2_lib.baseboard_fab2(sch_1):page27_i172@chpset_lib.skx_ext_b(chips)!SKX_EXT_B_BGA1-IC,TBD!!!F95!DDR4_DQ(13)!!!!
S!M_E_DQ<14>!U5D1!DC82!@baseboard_fab2_lib.baseboard_fab2(sch_1):page27_i172@chpset_lib.skx_ext_b(chips)!SKX_EXT_B_BGA1-IC,TBD!!!F95!DDR4_DQ(14)!!!!
S!M_E_DQ<15>!U5D1!DE82!@baseboard_fab2_lib.baseboard_fab2(sch_1):page27_i172@chpset_lib.skx_ext_b(chips)!SKX_EXT_B_BGA1-IC,TBD!!!F95!DDR4_DQ(15)!!!!
S!M_E_DQ<16>!U5D1!DW80!@baseboard_fab2_lib.baseboard_fab2(sch_1):page27_i172@chpset_lib.skx_ext_b(chips)!SKX_EXT_B_BGA1-IC,TBD!!!F95!DDR4_DQ(16)!!!!
S!M_E_DQ<17>!U5D1!EC80!@baseboard_fab2_lib.baseboard_fab2(sch_1):page27_i172@chpset_lib.skx_ext_b(chips)!SKX_EXT_B_BGA1-IC,TBD!!!F95!DDR4_DQ(17)!!!!
S!M_E_DQ<18>!U5D1!DY77!@baseboard_fab2_lib.baseboard_fab2(sch_1):page27_i172@chpset_lib.skx_ext_b(chips)!SKX_EXT_B_BGA1-IC,TBD!!!F95!DDR4_DQ(18)!!!!
S!M_E_DQ<19>!U5D1!EB77!@baseboard_fab2_lib.baseboard_fab2(sch_1):page27_i172@chpset_lib.skx_ext_b(chips)!SKX_EXT_B_BGA1-IC,TBD!!!F95!DDR4_DQ(19)!!!!
S!M_E_DQ<1>!U5D1!CK81!@baseboard_fab2_lib.baseboard_fab2(sch_1):page27_i172@chpset_lib.skx_ext_b(chips)!SKX_EXT_B_BGA1-IC,TBD!!!F95!DDR4_DQ(1)!!!!
S!M_E_DQ<20>!U5D1!DY81!@baseboard_fab2_lib.baseboard_fab2(sch_1):page27_i172@chpset_lib.skx_ext_b(chips)!SKX_EXT_B_BGA1-IC,TBD!!!F95!DDR4_DQ(20)!!!!
S!M_E_DQ<21>!U5D1!EB81!@baseboard_fab2_lib.baseboard_fab2(sch_1):page27_i172@chpset_lib.skx_ext_b(chips)!SKX_EXT_B_BGA1-IC,TBD!!!F95!DDR4_DQ(21)!!!!
S!M_E_DQ<22>!U5D1!DW78!@baseboard_fab2_lib.baseboard_fab2(sch_1):page27_i172@chpset_lib.skx_ext_b(chips)!SKX_EXT_B_BGA1-IC,TBD!!!F95!DDR4_DQ(22)!!!!
S!M_E_DQ<23>!U5D1!EC78!@baseboard_fab2_lib.baseboard_fab2(sch_1):page27_i172@chpset_lib.skx_ext_b(chips)!SKX_EXT_B_BGA1-IC,TBD!!!F95!DDR4_DQ(23)!!!!
S!M_E_DQ<24>!U5D1!ED75!@baseboard_fab2_lib.baseboard_fab2(sch_1):page27_i172@chpset_lib.skx_ext_b(chips)!SKX_EXT_B_BGA1-IC,TBD!!!F95!DDR4_DQ(24)!!!!
S!M_E_DQ<25>!U5D1!EE74!@baseboard_fab2_lib.baseboard_fab2(sch_1):page27_i172@chpset_lib.skx_ext_b(chips)!SKX_EXT_B_BGA1-IC,TBD!!!F95!DDR4_DQ(25)!!!!
S!M_E_DQ<26>!U5D1!EB71!@baseboard_fab2_lib.baseboard_fab2(sch_1):page27_i172@chpset_lib.skx_ext_b(chips)!SKX_EXT_B_BGA1-IC,TBD!!!F95!DDR4_DQ(26)!!!!
S!M_E_DQ<27>!U5D1!ED71!@baseboard_fab2_lib.baseboard_fab2(sch_1):page27_i172@chpset_lib.skx_ext_b(chips)!SKX_EXT_B_BGA1-IC,TBD!!!F95!DDR4_DQ(27)!!!!
S!M_E_DQ<28>!U5D1!EA74!@baseboard_fab2_lib.baseboard_fab2(sch_1):page27_i172@chpset_lib.skx_ext_b(chips)!SKX_EXT_B_BGA1-IC,TBD!!!F95!DDR4_DQ(28)!!!!
S!M_E_DQ<29>!U5D1!EB75!@baseboard_fab2_lib.baseboard_fab2(sch_1):page27_i172@chpset_lib.skx_ext_b(chips)!SKX_EXT_B_BGA1-IC,TBD!!!F95!DDR4_DQ(29)!!!!
S!M_E_DQ<2>!U5D1!CT81!@baseboard_fab2_lib.baseboard_fab2(sch_1):page27_i172@chpset_lib.skx_ext_b(chips)!SKX_EXT_B_BGA1-IC,TBD!!!F95!DDR4_DQ(2)!!!!
S!M_E_DQ<30>!U5D1!EA72!@baseboard_fab2_lib.baseboard_fab2(sch_1):page27_i172@chpset_lib.skx_ext_b(chips)!SKX_EXT_B_BGA1-IC,TBD!!!F95!DDR4_DQ(30)!!!!
S!M_E_DQ<31>!U5D1!EE72!@baseboard_fab2_lib.baseboard_fab2(sch_1):page27_i172@chpset_lib.skx_ext_b(chips)!SKX_EXT_B_BGA1-IC,TBD!!!F95!DDR4_DQ(31)!!!!
S!M_E_DQ<37>!U5D1!DN42!@baseboard_fab2_lib.baseboard_fab2(sch_1):page27_i172@chpset_lib.skx_ext_b(chips)!SKX_EXT_B_BGA1-IC,TBD!!!F95!DDR4_DQ(37)!!!!
S!M_E_DQ<36>!U5D1!DL42!@baseboard_fab2_lib.baseboard_fab2(sch_1):page27_i172@chpset_lib.skx_ext_b(chips)!SKX_EXT_B_BGA1-IC,TBD!!!F95!DDR4_DQ(36)!!!!
S!M_E_DQ<34>!U5D1!DP39!@baseboard_fab2_lib.baseboard_fab2(sch_1):page27_i172@chpset_lib.skx_ext_b(chips)!SKX_EXT_B_BGA1-IC,TBD!!!F95!DDR4_DQ(34)!!!!
S!M_E_DQ<35>!U5D1!DT39!@baseboard_fab2_lib.baseboard_fab2(sch_1):page27_i172@chpset_lib.skx_ext_b(chips)!SKX_EXT_B_BGA1-IC,TBD!!!F95!DDR4_DQ(35)!!!!
S!M_E_DQ<33>!U5D1!DW42!@baseboard_fab2_lib.baseboard_fab2(sch_1):page27_i172@chpset_lib.skx_ext_b(chips)!SKX_EXT_B_BGA1-IC,TBD!!!F95!DDR4_DQ(33)!!!!
S!M_E_DQ<32>!U5D1!DU42!@baseboard_fab2_lib.baseboard_fab2(sch_1):page27_i172@chpset_lib.skx_ext_b(chips)!SKX_EXT_B_BGA1-IC,TBD!!!F95!DDR4_DQ(32)!!!!
S!M_E_DQ<38>!U5D1!DN40!@baseboard_fab2_lib.baseboard_fab2(sch_1):page27_i172@chpset_lib.skx_ext_b(chips)!SKX_EXT_B_BGA1-IC,TBD!!!F95!DDR4_DQ(38)!!!!
S!M_E_DQ<39>!U5D1!DU40!@baseboard_fab2_lib.baseboard_fab2(sch_1):page27_i172@chpset_lib.skx_ext_b(chips)!SKX_EXT_B_BGA1-IC,TBD!!!F95!DDR4_DQ(39)!!!!
S!M_E_DQ<3>!U5D1!CR82!@baseboard_fab2_lib.baseboard_fab2(sch_1):page27_i172@chpset_lib.skx_ext_b(chips)!SKX_EXT_B_BGA1-IC,TBD!!!F95!DDR4_DQ(3)!!!!
S!M_E_DQ<40>!U5D1!EC34!@baseboard_fab2_lib.baseboard_fab2(sch_1):page27_i172@chpset_lib.skx_ext_b(chips)!SKX_EXT_B_BGA1-IC,TBD!!!F95!DDR4_DQ(40)!!!!
S!M_E_DQ<41>!U5D1!ED33!@baseboard_fab2_lib.baseboard_fab2(sch_1):page27_i172@chpset_lib.skx_ext_b(chips)!SKX_EXT_B_BGA1-IC,TBD!!!F95!DDR4_DQ(41)!!!!
S!M_E_DQ<42>!U5D1!EA30!@baseboard_fab2_lib.baseboard_fab2(sch_1):page27_i172@chpset_lib.skx_ext_b(chips)!SKX_EXT_B_BGA1-IC,TBD!!!F95!DDR4_DQ(42)!!!!
S!M_E_DQ<43>!U5D1!EC30!@baseboard_fab2_lib.baseboard_fab2(sch_1):page27_i172@chpset_lib.skx_ext_b(chips)!SKX_EXT_B_BGA1-IC,TBD!!!F95!DDR4_DQ(43)!!!!
S!M_E_DQ<44>!U5D1!DY33!@baseboard_fab2_lib.baseboard_fab2(sch_1):page27_i172@chpset_lib.skx_ext_b(chips)!SKX_EXT_B_BGA1-IC,TBD!!!F95!DDR4_DQ(44)!!!!
S!M_E_DQ<45>!U5D1!EA34!@baseboard_fab2_lib.baseboard_fab2(sch_1):page27_i172@chpset_lib.skx_ext_b(chips)!SKX_EXT_B_BGA1-IC,TBD!!!F95!DDR4_DQ(45)!!!!
S!M_E_DQ<46>!U5D1!DY31!@baseboard_fab2_lib.baseboard_fab2(sch_1):page27_i172@chpset_lib.skx_ext_b(chips)!SKX_EXT_B_BGA1-IC,TBD!!!F95!DDR4_DQ(46)!!!!
S!M_E_DQ<47>!U5D1!ED31!@baseboard_fab2_lib.baseboard_fab2(sch_1):page27_i172@chpset_lib.skx_ext_b(chips)!SKX_EXT_B_BGA1-IC,TBD!!!F95!DDR4_DQ(47)!!!!
S!M_E_DQ<48>!U5D1!EC28!@baseboard_fab2_lib.baseboard_fab2(sch_1):page27_i172@chpset_lib.skx_ext_b(chips)!SKX_EXT_B_BGA1-IC,TBD!!!F95!DDR4_DQ(48)!!!!
S!M_E_DQ<49>!U5D1!ED27!@baseboard_fab2_lib.baseboard_fab2(sch_1):page27_i172@chpset_lib.skx_ext_b(chips)!SKX_EXT_B_BGA1-IC,TBD!!!F95!DDR4_DQ(49)!!!!
S!M_E_DQ<4>!U5D1!CK79!@baseboard_fab2_lib.baseboard_fab2(sch_1):page27_i172@chpset_lib.skx_ext_b(chips)!SKX_EXT_B_BGA1-IC,TBD!!!F95!DDR4_DQ(4)!!!!
S!M_E_DQ<50>!U5D1!EA24!@baseboard_fab2_lib.baseboard_fab2(sch_1):page27_i172@chpset_lib.skx_ext_b(chips)!SKX_EXT_B_BGA1-IC,TBD!!!F95!DDR4_DQ(50)!!!!
S!M_E_DQ<51>!U5D1!EC24!@baseboard_fab2_lib.baseboard_fab2(sch_1):page27_i172@chpset_lib.skx_ext_b(chips)!SKX_EXT_B_BGA1-IC,TBD!!!F95!DDR4_DQ(51)!!!!
S!M_E_DQ<52>!U5D1!DY27!@baseboard_fab2_lib.baseboard_fab2(sch_1):page27_i172@chpset_lib.skx_ext_b(chips)!SKX_EXT_B_BGA1-IC,TBD!!!F95!DDR4_DQ(52)!!!!
S!M_E_DQ<53>!U5D1!EA28!@baseboard_fab2_lib.baseboard_fab2(sch_1):page27_i172@chpset_lib.skx_ext_b(chips)!SKX_EXT_B_BGA1-IC,TBD!!!F95!DDR4_DQ(53)!!!!
S!M_E_DQ<54>!U5D1!DY25!@baseboard_fab2_lib.baseboard_fab2(sch_1):page27_i172@chpset_lib.skx_ext_b(chips)!SKX_EXT_B_BGA1-IC,TBD!!!F95!DDR4_DQ(54)!!!!
S!M_E_DQ<55>!U5D1!ED25!@baseboard_fab2_lib.baseboard_fab2(sch_1):page27_i172@chpset_lib.skx_ext_b(chips)!SKX_EXT_B_BGA1-IC,TBD!!!F95!DDR4_DQ(55)!!!!
S!M_E_DQ<56>!U5D1!DF27!@baseboard_fab2_lib.baseboard_fab2(sch_1):page27_i172@chpset_lib.skx_ext_b(chips)!SKX_EXT_B_BGA1-IC,TBD!!!F95!DDR4_DQ(56)!!!!
S!M_E_DQ<57>!U5D1!DK27!@baseboard_fab2_lib.baseboard_fab2(sch_1):page27_i172@chpset_lib.skx_ext_b(chips)!SKX_EXT_B_BGA1-IC,TBD!!!F95!DDR4_DQ(57)!!!!
S!M_E_DQ<58>!U5D1!DD25!@baseboard_fab2_lib.baseboard_fab2(sch_1):page27_i172@chpset_lib.skx_ext_b(chips)!SKX_EXT_B_BGA1-IC,TBD!!!F95!DDR4_DQ(58)!!!!
S!M_E_DQ<59>!U5D1!DJ24!@baseboard_fab2_lib.baseboard_fab2(sch_1):page27_i172@chpset_lib.skx_ext_b(chips)!SKX_EXT_B_BGA1-IC,TBD!!!F95!DDR4_DQ(59)!!!!
S!M_E_DQ<5>!U5D1!CJ80!@baseboard_fab2_lib.baseboard_fab2(sch_1):page27_i172@chpset_lib.skx_ext_b(chips)!SKX_EXT_B_BGA1-IC,TBD!!!F95!DDR4_DQ(5)!!!!
S!M_E_DQ<60>!U5D1!DG28!@baseboard_fab2_lib.baseboard_fab2(sch_1):page27_i172@chpset_lib.skx_ext_b(chips)!SKX_EXT_B_BGA1-IC,TBD!!!F95!DDR4_DQ(60)!!!!
S!M_E_DQ<61>!U5D1!DJ28!@baseboard_fab2_lib.baseboard_fab2(sch_1):page27_i172@chpset_lib.skx_ext_b(chips)!SKX_EXT_B_BGA1-IC,TBD!!!F95!DDR4_DQ(61)!!!!
S!M_E_DQ<62>!U5D1!DF25!@baseboard_fab2_lib.baseboard_fab2(sch_1):page27_i172@chpset_lib.skx_ext_b(chips)!SKX_EXT_B_BGA1-IC,TBD!!!F95!DDR4_DQ(62)!!!!
S!M_E_DQ<63>!U5D1!DK25!@baseboard_fab2_lib.baseboard_fab2(sch_1):page27_i172@chpset_lib.skx_ext_b(chips)!SKX_EXT_B_BGA1-IC,TBD!!!F95!DDR4_DQ(63)!!!!
S!M_E_DQ<6>!U5D1!CR80!@baseboard_fab2_lib.baseboard_fab2(sch_1):page27_i172@chpset_lib.skx_ext_b(chips)!SKX_EXT_B_BGA1-IC,TBD!!!F95!DDR4_DQ(6)!!!!
S!M_E_DQ<7>!U5D1!CN82!@baseboard_fab2_lib.baseboard_fab2(sch_1):page27_i172@chpset_lib.skx_ext_b(chips)!SKX_EXT_B_BGA1-IC,TBD!!!F95!DDR4_DQ(7)!!!!
S!M_E_DQ<8>!U5D1!DB79!@baseboard_fab2_lib.baseboard_fab2(sch_1):page27_i172@chpset_lib.skx_ext_b(chips)!SKX_EXT_B_BGA1-IC,TBD!!!F95!DDR4_DQ(8)!!!!
S!M_E_DQ<9>!U5D1!CY81!@baseboard_fab2_lib.baseboard_fab2(sch_1):page27_i172@chpset_lib.skx_ext_b(chips)!SKX_EXT_B_BGA1-IC,TBD!!!F95!DDR4_DQ(9)!!!!
S!M_E_DQS_DN<0>!U5D1!CL82!@baseboard_fab2_lib.baseboard_fab2(sch_1):page27_i172@chpset_lib.skx_ext_b(chips)!SKX_EXT_B_BGA1-IC,TBD!!!F95!DDR4_DQS_DN(0)!!!!
S!M_E_DQS_DN<10>!U5D1!DC80!@baseboard_fab2_lib.baseboard_fab2(sch_1):page27_i172@chpset_lib.skx_ext_b(chips)!SKX_EXT_B_BGA1-IC,TBD!!!F95!DDR4_DQS_DN(10)!!!!
S!M_E_DQS_DN<11>!U5D1!DY79!@baseboard_fab2_lib.baseboard_fab2(sch_1):page27_i172@chpset_lib.skx_ext_b(chips)!SKX_EXT_B_BGA1-IC,TBD!!!F95!DDR4_DQS_DN(11)!!!!
S!M_E_DQS_DN<12>!U5D1!EB73!@baseboard_fab2_lib.baseboard_fab2(sch_1):page27_i172@chpset_lib.skx_ext_b(chips)!SKX_EXT_B_BGA1-IC,TBD!!!F95!DDR4_DQS_DN(12)!!!!
S!M_E_DQS_DN<13>!U5D1!DP41!@baseboard_fab2_lib.baseboard_fab2(sch_1):page27_i172@chpset_lib.skx_ext_b(chips)!SKX_EXT_B_BGA1-IC,TBD!!!F95!DDR4_DQS_DN(13)!!!!
S!M_E_DQS_DN<14>!U5D1!EA32!@baseboard_fab2_lib.baseboard_fab2(sch_1):page27_i172@chpset_lib.skx_ext_b(chips)!SKX_EXT_B_BGA1-IC,TBD!!!F95!DDR4_DQS_DN(14)!!!!
S!M_E_DQS_DN<15>!U5D1!EA26!@baseboard_fab2_lib.baseboard_fab2(sch_1):page27_i172@chpset_lib.skx_ext_b(chips)!SKX_EXT_B_BGA1-IC,TBD!!!F95!DDR4_DQS_DN(15)!!!!
S!M_E_DQS_DN<16>!U5D1!DG26!@baseboard_fab2_lib.baseboard_fab2(sch_1):page27_i172@chpset_lib.skx_ext_b(chips)!SKX_EXT_B_BGA1-IC,TBD!!!F95!DDR4_DQS_DN(16)!!!!
S!M_E_DQS_DN<17>!U5D1!DV67!@baseboard_fab2_lib.baseboard_fab2(sch_1):page27_i172@chpset_lib.skx_ext_b(chips)!SKX_EXT_B_BGA1-IC,TBD!!!F95!DDR4_DQS_DN(17)!!!!
S!M_E_DQS_DN<1>!U5D1!DA82!@baseboard_fab2_lib.baseboard_fab2(sch_1):page27_i172@chpset_lib.skx_ext_b(chips)!SKX_EXT_B_BGA1-IC,TBD!!!F95!DDR4_DQS_DN(1)!!!!
S!M_E_DQS_DN<2>!U5D1!ED79!@baseboard_fab2_lib.baseboard_fab2(sch_1):page27_i172@chpset_lib.skx_ext_b(chips)!SKX_EXT_B_BGA1-IC,TBD!!!F95!DDR4_DQS_DN(2)!!!!
S!M_E_DQS_DN<3>!U5D1!EF73!@baseboard_fab2_lib.baseboard_fab2(sch_1):page27_i172@chpset_lib.skx_ext_b(chips)!SKX_EXT_B_BGA1-IC,TBD!!!F95!DDR4_DQS_DN(3)!!!!
S!M_E_DQS_DN<4>!U5D1!DV41!@baseboard_fab2_lib.baseboard_fab2(sch_1):page27_i172@chpset_lib.skx_ext_b(chips)!SKX_EXT_B_BGA1-IC,TBD!!!F95!DDR4_DQS_DN(4)!!!!
S!M_E_DQS_DN<5>!U5D1!EE32!@baseboard_fab2_lib.baseboard_fab2(sch_1):page27_i172@chpset_lib.skx_ext_b(chips)!SKX_EXT_B_BGA1-IC,TBD!!!F95!DDR4_DQS_DN(5)!!!!
S!M_E_DQS_DN<6>!U5D1!EE26!@baseboard_fab2_lib.baseboard_fab2(sch_1):page27_i172@chpset_lib.skx_ext_b(chips)!SKX_EXT_B_BGA1-IC,TBD!!!F95!DDR4_DQS_DN(6)!!!!
S!M_E_DQS_DN<7>!U5D1!DL26!@baseboard_fab2_lib.baseboard_fab2(sch_1):page27_i172@chpset_lib.skx_ext_b(chips)!SKX_EXT_B_BGA1-IC,TBD!!!F95!DDR4_DQS_DN(7)!!!!
S!M_E_DQS_DN<8>!U5D1!EB67!@baseboard_fab2_lib.baseboard_fab2(sch_1):page27_i172@chpset_lib.skx_ext_b(chips)!SKX_EXT_B_BGA1-IC,TBD!!!F95!DDR4_DQS_DN(8)!!!!
S!M_E_DQS_DN<9>!U5D1!CN80!@baseboard_fab2_lib.baseboard_fab2(sch_1):page27_i172@chpset_lib.skx_ext_b(chips)!SKX_EXT_B_BGA1-IC,TBD!!!F95!DDR4_DQS_DN(9)!!!!
S!M_E_DQS_DP<0>!U5D1!CM81!@baseboard_fab2_lib.baseboard_fab2(sch_1):page27_i172@chpset_lib.skx_ext_b(chips)!SKX_EXT_B_BGA1-IC,TBD!!!F95!DDR4_DQS_DP(0)!!!!
S!M_E_DQS_DP<10>!U5D1!DD79!@baseboard_fab2_lib.baseboard_fab2(sch_1):page27_i172@chpset_lib.skx_ext_b(chips)!SKX_EXT_B_BGA1-IC,TBD!!!F95!DDR4_DQS_DP(10)!!!!
S!M_E_DQS_DP<11>!U5D1!DV79!@baseboard_fab2_lib.baseboard_fab2(sch_1):page27_i172@chpset_lib.skx_ext_b(chips)!SKX_EXT_B_BGA1-IC,TBD!!!F95!DDR4_DQS_DP(11)!!!!
S!M_E_DQS_DP<12>!U5D1!DY73!@baseboard_fab2_lib.baseboard_fab2(sch_1):page27_i172@chpset_lib.skx_ext_b(chips)!SKX_EXT_B_BGA1-IC,TBD!!!F95!DDR4_DQS_DP(12)!!!!
S!M_E_DQS_DP<13>!U5D1!DM41!@baseboard_fab2_lib.baseboard_fab2(sch_1):page27_i172@chpset_lib.skx_ext_b(chips)!SKX_EXT_B_BGA1-IC,TBD!!!F95!DDR4_DQS_DP(13)!!!!
S!M_E_DQS_DP<14>!U5D1!DW32!@baseboard_fab2_lib.baseboard_fab2(sch_1):page27_i172@chpset_lib.skx_ext_b(chips)!SKX_EXT_B_BGA1-IC,TBD!!!F95!DDR4_DQS_DP(14)!!!!
S!M_E_DQS_DP<15>!U5D1!DW26!@baseboard_fab2_lib.baseboard_fab2(sch_1):page27_i172@chpset_lib.skx_ext_b(chips)!SKX_EXT_B_BGA1-IC,TBD!!!F95!DDR4_DQS_DP(15)!!!!
S!M_E_DQS_DP<16>!U5D1!DE26!@baseboard_fab2_lib.baseboard_fab2(sch_1):page27_i172@chpset_lib.skx_ext_b(chips)!SKX_EXT_B_BGA1-IC,TBD!!!F95!DDR4_DQS_DP(16)!!!!
S!M_E_DQS_DP<17>!U5D1!DT67!@baseboard_fab2_lib.baseboard_fab2(sch_1):page27_i172@chpset_lib.skx_ext_b(chips)!SKX_EXT_B_BGA1-IC,TBD!!!F95!DDR4_DQS_DP(17)!!!!
S!M_E_DQS_DP<1>!U5D1!DB81!@baseboard_fab2_lib.baseboard_fab2(sch_1):page27_i172@chpset_lib.skx_ext_b(chips)!SKX_EXT_B_BGA1-IC,TBD!!!F95!DDR4_DQS_DP(1)!!!!
S!M_E_DQS_DP<2>!U5D1!EB79!@baseboard_fab2_lib.baseboard_fab2(sch_1):page27_i172@chpset_lib.skx_ext_b(chips)!SKX_EXT_B_BGA1-IC,TBD!!!F95!DDR4_DQS_DP(2)!!!!
S!M_E_DQS_DP<3>!U5D1!ED73!@baseboard_fab2_lib.baseboard_fab2(sch_1):page27_i172@chpset_lib.skx_ext_b(chips)!SKX_EXT_B_BGA1-IC,TBD!!!F95!DDR4_DQS_DP(3)!!!!
S!M_E_DQS_DP<4>!U5D1!DT41!@baseboard_fab2_lib.baseboard_fab2(sch_1):page27_i172@chpset_lib.skx_ext_b(chips)!SKX_EXT_B_BGA1-IC,TBD!!!F95!DDR4_DQS_DP(4)!!!!
S!M_E_DQS_DP<5>!U5D1!EC32!@baseboard_fab2_lib.baseboard_fab2(sch_1):page27_i172@chpset_lib.skx_ext_b(chips)!SKX_EXT_B_BGA1-IC,TBD!!!F95!DDR4_DQS_DP(5)!!!!
S!M_E_DQS_DP<6>!U5D1!EC26!@baseboard_fab2_lib.baseboard_fab2(sch_1):page27_i172@chpset_lib.skx_ext_b(chips)!SKX_EXT_B_BGA1-IC,TBD!!!F95!DDR4_DQS_DP(6)!!!!
S!M_E_DQS_DP<7>!U5D1!DJ26!@baseboard_fab2_lib.baseboard_fab2(sch_1):page27_i172@chpset_lib.skx_ext_b(chips)!SKX_EXT_B_BGA1-IC,TBD!!!F95!DDR4_DQS_DP(7)!!!!
S!M_E_DQS_DP<8>!U5D1!DY67!@baseboard_fab2_lib.baseboard_fab2(sch_1):page27_i172@chpset_lib.skx_ext_b(chips)!SKX_EXT_B_BGA1-IC,TBD!!!F95!DDR4_DQS_DP(8)!!!!
S!M_E_DQS_DP<9>!U5D1!CP79!@baseboard_fab2_lib.baseboard_fab2(sch_1):page27_i172@chpset_lib.skx_ext_b(chips)!SKX_EXT_B_BGA1-IC,TBD!!!F95!DDR4_DQS_DP(9)!!!!
S!M_E_ECC<0>!U5D1!DY69!@baseboard_fab2_lib.baseboard_fab2(sch_1):page27_i172@chpset_lib.skx_ext_b(chips)!SKX_EXT_B_BGA1-IC,TBD!!!F95!DDR4_ECC(0)!!!!
S!M_E_ECC<1>!U5D1!EA68!@baseboard_fab2_lib.baseboard_fab2(sch_1):page27_i172@chpset_lib.skx_ext_b(chips)!SKX_EXT_B_BGA1-IC,TBD!!!F95!DDR4_ECC(1)!!!!
S!M_E_ECC<2>!U5D1!DV65!@baseboard_fab2_lib.baseboard_fab2(sch_1):page27_i172@chpset_lib.skx_ext_b(chips)!SKX_EXT_B_BGA1-IC,TBD!!!F95!DDR4_ECC(2)!!!!
S!M_E_ECC<3>!U5D1!DY65!@baseboard_fab2_lib.baseboard_fab2(sch_1):page27_i172@chpset_lib.skx_ext_b(chips)!SKX_EXT_B_BGA1-IC,TBD!!!F95!DDR4_ECC(3)!!!!
S!M_E_ECC<4>!U5D1!DU68!@baseboard_fab2_lib.baseboard_fab2(sch_1):page27_i172@chpset_lib.skx_ext_b(chips)!SKX_EXT_B_BGA1-IC,TBD!!!F95!DDR4_ECC(4)!!!!
S!M_E_ECC<5>!U5D1!DV69!@baseboard_fab2_lib.baseboard_fab2(sch_1):page27_i172@chpset_lib.skx_ext_b(chips)!SKX_EXT_B_BGA1-IC,TBD!!!F95!DDR4_ECC(5)!!!!
S!M_E_ECC<6>!U5D1!DU66!@baseboard_fab2_lib.baseboard_fab2(sch_1):page27_i172@chpset_lib.skx_ext_b(chips)!SKX_EXT_B_BGA1-IC,TBD!!!F95!DDR4_ECC(6)!!!!
S!M_E_ECC<7>!U5D1!EA66!@baseboard_fab2_lib.baseboard_fab2(sch_1):page27_i172@chpset_lib.skx_ext_b(chips)!SKX_EXT_B_BGA1-IC,TBD!!!F95!DDR4_ECC(7)!!!!
S!M_E_MA<0>!U5D1!DW52!@baseboard_fab2_lib.baseboard_fab2(sch_1):page27_i172@chpset_lib.skx_ext_b(chips)!SKX_EXT_B_BGA1-IC,TBD!!!F95!DDR4_MA(0)!!!!
S!M_E_MA<10>!U5D1!DT55!@baseboard_fab2_lib.baseboard_fab2(sch_1):page27_i172@chpset_lib.skx_ext_b(chips)!SKX_EXT_B_BGA1-IC,TBD!!!F95!DDR4_MA(10)!!!!
S!M_E_MA<11>!U5D1!DR60!@baseboard_fab2_lib.baseboard_fab2(sch_1):page27_i172@chpset_lib.skx_ext_b(chips)!SKX_EXT_B_BGA1-IC,TBD!!!F95!DDR4_MA(11)!!!!
S!M_E_MA<12>!U5D1!DN60!@baseboard_fab2_lib.baseboard_fab2(sch_1):page27_i172@chpset_lib.skx_ext_b(chips)!SKX_EXT_B_BGA1-IC,TBD!!!F95!DDR4_MA(12)!!!!
S!M_E_MA<13>!U5D1!DT51!@baseboard_fab2_lib.baseboard_fab2(sch_1):page27_i172@chpset_lib.skx_ext_b(chips)!SKX_EXT_B_BGA1-IC,TBD!!!F95!DDR4_MA(13)!!!!
S!M_E_MA<14>!U5D1!DM51!@baseboard_fab2_lib.baseboard_fab2(sch_1):page27_i172@chpset_lib.skx_ext_b(chips)!SKX_EXT_B_BGA1-IC,TBD!!!F95!DDR4_MA(14)!!!!
S!M_E_MA<15>!U5D1!DR52!@baseboard_fab2_lib.baseboard_fab2(sch_1):page27_i172@chpset_lib.skx_ext_b(chips)!SKX_EXT_B_BGA1-IC,TBD!!!F95!DDR4_MA(15)!!!!
S!M_E_MA<16>!U5D1!DN52!@baseboard_fab2_lib.baseboard_fab2(sch_1):page27_i172@chpset_lib.skx_ext_b(chips)!SKX_EXT_B_BGA1-IC,TBD!!!F95!DDR4_MA(16)!!!!
S!M_E_MA<17>!U5D1!DR48!@baseboard_fab2_lib.baseboard_fab2(sch_1):page27_i172@chpset_lib.skx_ext_b(chips)!SKX_EXT_B_BGA1-IC,TBD!!!F95!DDR4_MA(17)!!!!
S!M_E_MA<1>!U5D1!DW58!@baseboard_fab2_lib.baseboard_fab2(sch_1):page27_i172@chpset_lib.skx_ext_b(chips)!SKX_EXT_B_BGA1-IC,TBD!!!F95!DDR4_MA(1)!!!!
S!M_E_MA<2>!U5D1!DV57!@baseboard_fab2_lib.baseboard_fab2(sch_1):page27_i172@chpset_lib.skx_ext_b(chips)!SKX_EXT_B_BGA1-IC,TBD!!!F95!DDR4_MA(2)!!!!
S!M_E_MA<3>!U5D1!DR58!@baseboard_fab2_lib.baseboard_fab2(sch_1):page27_i172@chpset_lib.skx_ext_b(chips)!SKX_EXT_B_BGA1-IC,TBD!!!F95!DDR4_MA(3)!!!!
S!M_E_MA<4>!U5D1!DT59!@baseboard_fab2_lib.baseboard_fab2(sch_1):page27_i172@chpset_lib.skx_ext_b(chips)!SKX_EXT_B_BGA1-IC,TBD!!!F95!DDR4_MA(4)!!!!
S!M_E_MA<5>!U5D1!DN58!@baseboard_fab2_lib.baseboard_fab2(sch_1):page27_i172@chpset_lib.skx_ext_b(chips)!SKX_EXT_B_BGA1-IC,TBD!!!F95!DDR4_MA(5)!!!!
S!M_E_MA<6>!U5D1!DM59!@baseboard_fab2_lib.baseboard_fab2(sch_1):page27_i172@chpset_lib.skx_ext_b(chips)!SKX_EXT_B_BGA1-IC,TBD!!!F95!DDR4_MA(6)!!!!
S!M_E_MA<7>!U5D1!DK61!@baseboard_fab2_lib.baseboard_fab2(sch_1):page27_i172@chpset_lib.skx_ext_b(chips)!SKX_EXT_B_BGA1-IC,TBD!!!F95!DDR4_MA(7)!!!!
S!M_E_MA<8>!U5D1!DJ60!@baseboard_fab2_lib.baseboard_fab2(sch_1):page27_i172@chpset_lib.skx_ext_b(chips)!SKX_EXT_B_BGA1-IC,TBD!!!F95!DDR4_MA(8)!!!!
S!M_E_MA<9>!U5D1!DV59!@baseboard_fab2_lib.baseboard_fab2(sch_1):page27_i172@chpset_lib.skx_ext_b(chips)!SKX_EXT_B_BGA1-IC,TBD!!!F95!DDR4_MA(9)!!!!
S!M_E_ODT<0>!U5D1!DR50!@baseboard_fab2_lib.baseboard_fab2(sch_1):page27_i172@chpset_lib.skx_ext_b(chips)!SKX_EXT_B_BGA1-IC,TBD!!!F95!DDR4_ODT(0)!!!!
S!M_E_ODT<1>!U5D1!DN48!@baseboard_fab2_lib.baseboard_fab2(sch_1):page27_i172@chpset_lib.skx_ext_b(chips)!SKX_EXT_B_BGA1-IC,TBD!!!F95!DDR4_ODT(1)!!!!
S!M_E_ODT<2>!U5D1!DT49!@baseboard_fab2_lib.baseboard_fab2(sch_1):page27_i172@chpset_lib.skx_ext_b(chips)!SKX_EXT_B_BGA1-IC,TBD!!!F95!DDR4_ODT(2)!!!!
S!M_E_ODT<3>!U5D1!DM47!@baseboard_fab2_lib.baseboard_fab2(sch_1):page27_i172@chpset_lib.skx_ext_b(chips)!SKX_EXT_B_BGA1-IC,TBD!!!F95!DDR4_ODT(3)!!!!
S!M_E_PAR!U5D1!DV53!@baseboard_fab2_lib.baseboard_fab2(sch_1):page27_i172@chpset_lib.skx_ext_b(chips)!SKX_EXT_B_BGA1-IC,TBD!!!F95!DDR4_PAR!!!!
S!M_F_ACT_N!U5D1!DC62!@baseboard_fab2_lib.baseboard_fab2(sch_1):page28_i172@chpset_lib.skx_ext_b(chips)!SKX_EXT_B_BGA1-IC,TBD!!!F94!DDR5_ACT_N!!!!
S!M_F_ALERT_N!U5D1!DD61!@baseboard_fab2_lib.baseboard_fab2(sch_1):page28_i172@chpset_lib.skx_ext_b(chips)!SKX_EXT_B_BGA1-IC,TBD!!!F94!DDR5_ALERT_N!!!!
S!M_F_BA<0>!U5D1!DJ52!@baseboard_fab2_lib.baseboard_fab2(sch_1):page28_i172@chpset_lib.skx_ext_b(chips)!SKX_EXT_B_BGA1-IC,TBD!!!F94!DDR5_BA(0)!!!!
S!M_F_BA<1>!U5D1!DC56!@baseboard_fab2_lib.baseboard_fab2(sch_1):page28_i172@chpset_lib.skx_ext_b(chips)!SKX_EXT_B_BGA1-IC,TBD!!!F94!DDR5_BA(1)!!!!
S!M_F_BG<0>!U5D1!DA62!@baseboard_fab2_lib.baseboard_fab2(sch_1):page28_i172@chpset_lib.skx_ext_b(chips)!SKX_EXT_B_BGA1-IC,TBD!!!F94!DDR5_BG(0)!!!!
S!M_F_BG<1>!U5D1!DF61!@baseboard_fab2_lib.baseboard_fab2(sch_1):page28_i172@chpset_lib.skx_ext_b(chips)!SKX_EXT_B_BGA1-IC,TBD!!!F94!DDR5_BG(1)!!!!
S!M_F_C<2>!U5D1!DF45!@baseboard_fab2_lib.baseboard_fab2(sch_1):page28_i172@chpset_lib.skx_ext_b(chips)!SKX_EXT_B_BGA1-IC,TBD!!!F94!DDR5_CID(2)!!!!
S!M_F_CKE<0>!U5D1!DG62!@baseboard_fab2_lib.baseboard_fab2(sch_1):page28_i172@chpset_lib.skx_ext_b(chips)!SKX_EXT_B_BGA1-IC,TBD!!!F94!DDR5_CKE(0)!!!!
S!M_F_CKE<1>!U5D1!DD63!@baseboard_fab2_lib.baseboard_fab2(sch_1):page28_i172@chpset_lib.skx_ext_b(chips)!SKX_EXT_B_BGA1-IC,TBD!!!F94!DDR5_CKE(1)!!!!
S!M_F_CKE<2>!U5D1!DK63!@baseboard_fab2_lib.baseboard_fab2(sch_1):page28_i172@chpset_lib.skx_ext_b(chips)!SKX_EXT_B_BGA1-IC,TBD!!!F94!DDR5_CKE(2)!!!!
S!M_F_CKE<3>!U5D1!DF63!@baseboard_fab2_lib.baseboard_fab2(sch_1):page28_i172@chpset_lib.skx_ext_b(chips)!SKX_EXT_B_BGA1-IC,TBD!!!F94!DDR5_CKE(3)!!!!
S!M_F_CLK_DN<0>!U5D1!DK55!@baseboard_fab2_lib.baseboard_fab2(sch_1):page28_i172@chpset_lib.skx_ext_b(chips)!SKX_EXT_B_BGA1-IC,TBD!!!F94!DDR5_CLK_DN(0)!!!!
S!M_F_CLK_DN<2>!U5D1!DK57!@baseboard_fab2_lib.baseboard_fab2(sch_1):page28_i172@chpset_lib.skx_ext_b(chips)!SKX_EXT_B_BGA1-IC,TBD!!!F94!DDR5_CLK_DN(2)!!!!
S!M_F_CLK_DN<1>!U5D1!DF55!@baseboard_fab2_lib.baseboard_fab2(sch_1):page28_i172@chpset_lib.skx_ext_b(chips)!SKX_EXT_B_BGA1-IC,TBD!!!F94!DDR5_CLK_DN(1)!!!!
S!M_F_CLK_DN<3>!U5D1!DF57!@baseboard_fab2_lib.baseboard_fab2(sch_1):page28_i172@chpset_lib.skx_ext_b(chips)!SKX_EXT_B_BGA1-IC,TBD!!!F94!DDR5_CLK_DN(3)!!!!
S!M_F_CLK_DP<0>!U5D1!DJ54!@baseboard_fab2_lib.baseboard_fab2(sch_1):page28_i172@chpset_lib.skx_ext_b(chips)!SKX_EXT_B_BGA1-IC,TBD!!!F94!DDR5_CLK_DP(0)!!!!
S!M_F_CLK_DP<2>!U5D1!DJ56!@baseboard_fab2_lib.baseboard_fab2(sch_1):page28_i172@chpset_lib.skx_ext_b(chips)!SKX_EXT_B_BGA1-IC,TBD!!!F94!DDR5_CLK_DP(2)!!!!
S!M_F_CLK_DP<1>!U5D1!DG54!@baseboard_fab2_lib.baseboard_fab2(sch_1):page28_i172@chpset_lib.skx_ext_b(chips)!SKX_EXT_B_BGA1-IC,TBD!!!F94!DDR5_CLK_DP(1)!!!!
S!M_F_CLK_DP<3>!U5D1!DG56!@baseboard_fab2_lib.baseboard_fab2(sch_1):page28_i172@chpset_lib.skx_ext_b(chips)!SKX_EXT_B_BGA1-IC,TBD!!!F94!DDR5_CLK_DP(3)!!!!
S!M_F_CS_N<0>!U5D1!DK51!@baseboard_fab2_lib.baseboard_fab2(sch_1):page28_i172@chpset_lib.skx_ext_b(chips)!SKX_EXT_B_BGA1-IC,TBD!!!F94!DDR5_CS_N(0)!!!!
S!M_F_CS_N<1>!U5D1!DF49!@baseboard_fab2_lib.baseboard_fab2(sch_1):page28_i172@chpset_lib.skx_ext_b(chips)!SKX_EXT_B_BGA1-IC,TBD!!!F94!DDR5_CS_N(1)!!!!
S!M_F_CS_N<2>!U5D1!DJ46!@baseboard_fab2_lib.baseboard_fab2(sch_1):page28_i172@chpset_lib.skx_ext_b(chips)!SKX_EXT_B_BGA1-IC,TBD!!!F94!DDR5_CS_N(2)!!!!
S!M_F_CS_N<3>!U5D1!DG46!@baseboard_fab2_lib.baseboard_fab2(sch_1):page28_i172@chpset_lib.skx_ext_b(chips)!SKX_EXT_B_BGA1-IC,TBD!!!F94!DDR5_CS_N(3)!!!!
S!M_F_CS_N<4>!U5D1!DF51!@baseboard_fab2_lib.baseboard_fab2(sch_1):page28_i172@chpset_lib.skx_ext_b(chips)!SKX_EXT_B_BGA1-IC,TBD!!!F94!DDR5_CS_N(4)!!!!
S!M_F_CS_N<5>!U5D1!DJ48!@baseboard_fab2_lib.baseboard_fab2(sch_1):page28_i172@chpset_lib.skx_ext_b(chips)!SKX_EXT_B_BGA1-IC,TBD!!!F94!DDR5_CS_N(5)!!!!
S!M_F_CS_N<6>!U5D1!DM45!@baseboard_fab2_lib.baseboard_fab2(sch_1):page28_i172@chpset_lib.skx_ext_b(chips)!SKX_EXT_B_BGA1-IC,TBD!!!F94!DDR5_CS_N(6)!!!!
S!M_F_CS_N<7>!U5D1!DK45!@baseboard_fab2_lib.baseboard_fab2(sch_1):page28_i172@chpset_lib.skx_ext_b(chips)!SKX_EXT_B_BGA1-IC,TBD!!!F94!DDR5_CS_N(7)!!!!
S!M_F_DQ<0>!U5D1!CR74!@baseboard_fab2_lib.baseboard_fab2(sch_1):page28_i172@chpset_lib.skx_ext_b(chips)!SKX_EXT_B_BGA1-IC,TBD!!!F94!DDR5_DQ(0)!!!!
S!M_F_DQ<10>!U5D1!DH75!@baseboard_fab2_lib.baseboard_fab2(sch_1):page28_i172@chpset_lib.skx_ext_b(chips)!SKX_EXT_B_BGA1-IC,TBD!!!F94!DDR5_DQ(10)!!!!
S!M_F_DQ<11>!U5D1!DJ76!@baseboard_fab2_lib.baseboard_fab2(sch_1):page28_i172@chpset_lib.skx_ext_b(chips)!SKX_EXT_B_BGA1-IC,TBD!!!F94!DDR5_DQ(11)!!!!
S!M_F_DQ<12>!U5D1!DC74!@baseboard_fab2_lib.baseboard_fab2(sch_1):page28_i172@chpset_lib.skx_ext_b(chips)!SKX_EXT_B_BGA1-IC,TBD!!!F94!DDR5_DQ(12)!!!!
S!M_F_DQ<13>!U5D1!DB75!@baseboard_fab2_lib.baseboard_fab2(sch_1):page28_i172@chpset_lib.skx_ext_b(chips)!SKX_EXT_B_BGA1-IC,TBD!!!F94!DDR5_DQ(13)!!!!
S!M_F_DQ<14>!U5D1!DF77!@baseboard_fab2_lib.baseboard_fab2(sch_1):page28_i172@chpset_lib.skx_ext_b(chips)!SKX_EXT_B_BGA1-IC,TBD!!!F94!DDR5_DQ(14)!!!!
S!M_F_DQ<15>!U5D1!DH77!@baseboard_fab2_lib.baseboard_fab2(sch_1):page28_i172@chpset_lib.skx_ext_b(chips)!SKX_EXT_B_BGA1-IC,TBD!!!F94!DDR5_DQ(15)!!!!
S!M_F_DQ<16>!U5D1!DG70!@baseboard_fab2_lib.baseboard_fab2(sch_1):page28_i172@chpset_lib.skx_ext_b(chips)!SKX_EXT_B_BGA1-IC,TBD!!!F94!DDR5_DQ(16)!!!!
S!M_F_DQ<17>!U5D1!DJ72!@baseboard_fab2_lib.baseboard_fab2(sch_1):page28_i172@chpset_lib.skx_ext_b(chips)!SKX_EXT_B_BGA1-IC,TBD!!!F94!DDR5_DQ(17)!!!!
S!M_F_DQ<18>!U5D1!DM69!@baseboard_fab2_lib.baseboard_fab2(sch_1):page28_i172@chpset_lib.skx_ext_b(chips)!SKX_EXT_B_BGA1-IC,TBD!!!F94!DDR5_DQ(18)!!!!
S!M_F_DQ<19>!U5D1!DN70!@baseboard_fab2_lib.baseboard_fab2(sch_1):page28_i172@chpset_lib.skx_ext_b(chips)!SKX_EXT_B_BGA1-IC,TBD!!!F94!DDR5_DQ(19)!!!!
S!M_F_DQ<1>!U5D1!CN76!@baseboard_fab2_lib.baseboard_fab2(sch_1):page28_i172@chpset_lib.skx_ext_b(chips)!SKX_EXT_B_BGA1-IC,TBD!!!F94!DDR5_DQ(1)!!!!
S!M_F_DQ<20>!U5D1!DF71!@baseboard_fab2_lib.baseboard_fab2(sch_1):page28_i172@chpset_lib.skx_ext_b(chips)!SKX_EXT_B_BGA1-IC,TBD!!!F94!DDR5_DQ(20)!!!!
S!M_F_DQ<21>!U5D1!DG72!@baseboard_fab2_lib.baseboard_fab2(sch_1):page28_i172@chpset_lib.skx_ext_b(chips)!SKX_EXT_B_BGA1-IC,TBD!!!F94!DDR5_DQ(21)!!!!
S!M_F_DQ<22>!U5D1!DK69!@baseboard_fab2_lib.baseboard_fab2(sch_1):page28_i172@chpset_lib.skx_ext_b(chips)!SKX_EXT_B_BGA1-IC,TBD!!!F94!DDR5_DQ(22)!!!!
S!M_F_DQ<23>!U5D1!DM71!@baseboard_fab2_lib.baseboard_fab2(sch_1):page28_i172@chpset_lib.skx_ext_b(chips)!SKX_EXT_B_BGA1-IC,TBD!!!F94!DDR5_DQ(23)!!!!
S!M_F_DQ<24>!U5D1!CN66!@baseboard_fab2_lib.baseboard_fab2(sch_1):page28_i172@chpset_lib.skx_ext_b(chips)!SKX_EXT_B_BGA1-IC,TBD!!!F94!DDR5_DQ(24)!!!!
S!M_F_DQ<25>!U5D1!CU66!@baseboard_fab2_lib.baseboard_fab2(sch_1):page28_i172@chpset_lib.skx_ext_b(chips)!SKX_EXT_B_BGA1-IC,TBD!!!F94!DDR5_DQ(25)!!!!
S!M_F_DQ<26>!U5D1!CP63!@baseboard_fab2_lib.baseboard_fab2(sch_1):page28_i172@chpset_lib.skx_ext_b(chips)!SKX_EXT_B_BGA1-IC,TBD!!!F94!DDR5_DQ(26)!!!!
S!M_F_DQ<27>!U5D1!CT63!@baseboard_fab2_lib.baseboard_fab2(sch_1):page28_i172@chpset_lib.skx_ext_b(chips)!SKX_EXT_B_BGA1-IC,TBD!!!F94!DDR5_DQ(27)!!!!
S!M_F_DQ<28>!U5D1!CP67!@baseboard_fab2_lib.baseboard_fab2(sch_1):page28_i172@chpset_lib.skx_ext_b(chips)!SKX_EXT_B_BGA1-IC,TBD!!!F94!DDR5_DQ(28)!!!!
S!M_F_DQ<29>!U5D1!CT67!@baseboard_fab2_lib.baseboard_fab2(sch_1):page28_i172@chpset_lib.skx_ext_b(chips)!SKX_EXT_B_BGA1-IC,TBD!!!F94!DDR5_DQ(29)!!!!
S!M_F_DQ<2>!U5D1!CW76!@baseboard_fab2_lib.baseboard_fab2(sch_1):page28_i172@chpset_lib.skx_ext_b(chips)!SKX_EXT_B_BGA1-IC,TBD!!!F94!DDR5_DQ(2)!!!!
S!M_F_DQ<30>!U5D1!CN64!@baseboard_fab2_lib.baseboard_fab2(sch_1):page28_i172@chpset_lib.skx_ext_b(chips)!SKX_EXT_B_BGA1-IC,TBD!!!F94!DDR5_DQ(30)!!!!
S!M_F_DQ<31>!U5D1!CU64!@baseboard_fab2_lib.baseboard_fab2(sch_1):page28_i172@chpset_lib.skx_ext_b(chips)!SKX_EXT_B_BGA1-IC,TBD!!!F94!DDR5_DQ(31)!!!!
S!M_F_DQ<36>!U5D1!DA42!@baseboard_fab2_lib.baseboard_fab2(sch_1):page28_i172@chpset_lib.skx_ext_b(chips)!SKX_EXT_B_BGA1-IC,TBD!!!F94!DDR5_DQ(36)!!!!
S!M_F_DQ<32>!U5D1!DD41!@baseboard_fab2_lib.baseboard_fab2(sch_1):page28_i172@chpset_lib.skx_ext_b(chips)!SKX_EXT_B_BGA1-IC,TBD!!!F94!DDR5_DQ(32)!!!!
S!M_F_DQ<34>!U5D1!DE38!@baseboard_fab2_lib.baseboard_fab2(sch_1):page28_i172@chpset_lib.skx_ext_b(chips)!SKX_EXT_B_BGA1-IC,TBD!!!F94!DDR5_DQ(34)!!!!
S!M_F_DQ<35>!U5D1!DG38!@baseboard_fab2_lib.baseboard_fab2(sch_1):page28_i172@chpset_lib.skx_ext_b(chips)!SKX_EXT_B_BGA1-IC,TBD!!!F94!DDR5_DQ(35)!!!!
S!M_F_DQ<33>!U5D1!DG42!@baseboard_fab2_lib.baseboard_fab2(sch_1):page28_i172@chpset_lib.skx_ext_b(chips)!SKX_EXT_B_BGA1-IC,TBD!!!F94!DDR5_DQ(33)!!!!
S!M_F_DQ<37>!U5D1!DE42!@baseboard_fab2_lib.baseboard_fab2(sch_1):page28_i172@chpset_lib.skx_ext_b(chips)!SKX_EXT_B_BGA1-IC,TBD!!!F94!DDR5_DQ(37)!!!!
S!M_F_DQ<38>!U5D1!DD39!@baseboard_fab2_lib.baseboard_fab2(sch_1):page28_i172@chpset_lib.skx_ext_b(chips)!SKX_EXT_B_BGA1-IC,TBD!!!F94!DDR5_DQ(38)!!!!
S!M_F_DQ<39>!U5D1!DH39!@baseboard_fab2_lib.baseboard_fab2(sch_1):page28_i172@chpset_lib.skx_ext_b(chips)!SKX_EXT_B_BGA1-IC,TBD!!!F94!DDR5_DQ(39)!!!!
S!M_F_DQ<3>!U5D1!CV77!@baseboard_fab2_lib.baseboard_fab2(sch_1):page28_i172@chpset_lib.skx_ext_b(chips)!SKX_EXT_B_BGA1-IC,TBD!!!F94!DDR5_DQ(3)!!!!
S!M_F_DQ<40>!U5D1!DF33!@baseboard_fab2_lib.baseboard_fab2(sch_1):page28_i172@chpset_lib.skx_ext_b(chips)!SKX_EXT_B_BGA1-IC,TBD!!!F94!DDR5_DQ(40)!!!!
S!M_F_DQ<41>!U5D1!DK33!@baseboard_fab2_lib.baseboard_fab2(sch_1):page28_i172@chpset_lib.skx_ext_b(chips)!SKX_EXT_B_BGA1-IC,TBD!!!F94!DDR5_DQ(41)!!!!
S!M_F_DQ<42>!U5D1!DG30!@baseboard_fab2_lib.baseboard_fab2(sch_1):page28_i172@chpset_lib.skx_ext_b(chips)!SKX_EXT_B_BGA1-IC,TBD!!!F94!DDR5_DQ(42)!!!!
S!M_F_DQ<43>!U5D1!DJ30!@baseboard_fab2_lib.baseboard_fab2(sch_1):page28_i172@chpset_lib.skx_ext_b(chips)!SKX_EXT_B_BGA1-IC,TBD!!!F94!DDR5_DQ(43)!!!!
S!M_F_DQ<44>!U5D1!DG34!@baseboard_fab2_lib.baseboard_fab2(sch_1):page28_i172@chpset_lib.skx_ext_b(chips)!SKX_EXT_B_BGA1-IC,TBD!!!F94!DDR5_DQ(44)!!!!
S!M_F_DQ<45>!U5D1!DJ34!@baseboard_fab2_lib.baseboard_fab2(sch_1):page28_i172@chpset_lib.skx_ext_b(chips)!SKX_EXT_B_BGA1-IC,TBD!!!F94!DDR5_DQ(45)!!!!
S!M_F_DQ<46>!U5D1!DF31!@baseboard_fab2_lib.baseboard_fab2(sch_1):page28_i172@chpset_lib.skx_ext_b(chips)!SKX_EXT_B_BGA1-IC,TBD!!!F94!DDR5_DQ(46)!!!!
S!M_F_DQ<47>!U5D1!DK31!@baseboard_fab2_lib.baseboard_fab2(sch_1):page28_i172@chpset_lib.skx_ext_b(chips)!SKX_EXT_B_BGA1-IC,TBD!!!F94!DDR5_DQ(47)!!!!
S!M_F_DQ<48>!U5D1!CW36!@baseboard_fab2_lib.baseboard_fab2(sch_1):page28_i172@chpset_lib.skx_ext_b(chips)!SKX_EXT_B_BGA1-IC,TBD!!!F94!DDR5_DQ(48)!!!!
S!M_F_DQ<49>!U5D1!DC36!@baseboard_fab2_lib.baseboard_fab2(sch_1):page28_i172@chpset_lib.skx_ext_b(chips)!SKX_EXT_B_BGA1-IC,TBD!!!F94!DDR5_DQ(49)!!!!
S!M_F_DQ<4>!U5D1!CN74!@baseboard_fab2_lib.baseboard_fab2(sch_1):page28_i172@chpset_lib.skx_ext_b(chips)!SKX_EXT_B_BGA1-IC,TBD!!!F94!DDR5_DQ(4)!!!!
S!M_F_DQ<50>!U5D1!CY33!@baseboard_fab2_lib.baseboard_fab2(sch_1):page28_i172@chpset_lib.skx_ext_b(chips)!SKX_EXT_B_BGA1-IC,TBD!!!F94!DDR5_DQ(50)!!!!
S!M_F_DQ<51>!U5D1!DB33!@baseboard_fab2_lib.baseboard_fab2(sch_1):page28_i172@chpset_lib.skx_ext_b(chips)!SKX_EXT_B_BGA1-IC,TBD!!!F94!DDR5_DQ(51)!!!!
S!M_F_DQ<52>!U5D1!CY37!@baseboard_fab2_lib.baseboard_fab2(sch_1):page28_i172@chpset_lib.skx_ext_b(chips)!SKX_EXT_B_BGA1-IC,TBD!!!F94!DDR5_DQ(52)!!!!
S!M_F_DQ<53>!U5D1!DB37!@baseboard_fab2_lib.baseboard_fab2(sch_1):page28_i172@chpset_lib.skx_ext_b(chips)!SKX_EXT_B_BGA1-IC,TBD!!!F94!DDR5_DQ(53)!!!!
S!M_F_DQ<54>!U5D1!CW34!@baseboard_fab2_lib.baseboard_fab2(sch_1):page28_i172@chpset_lib.skx_ext_b(chips)!SKX_EXT_B_BGA1-IC,TBD!!!F94!DDR5_DQ(54)!!!!
S!M_F_DQ<55>!U5D1!DC34!@baseboard_fab2_lib.baseboard_fab2(sch_1):page28_i172@chpset_lib.skx_ext_b(chips)!SKX_EXT_B_BGA1-IC,TBD!!!F94!DDR5_DQ(55)!!!!
S!M_F_DQ<56>!U5D1!CW30!@baseboard_fab2_lib.baseboard_fab2(sch_1):page28_i172@chpset_lib.skx_ext_b(chips)!SKX_EXT_B_BGA1-IC,TBD!!!F94!DDR5_DQ(56)!!!!
S!M_F_DQ<57>!U5D1!DC30!@baseboard_fab2_lib.baseboard_fab2(sch_1):page28_i172@chpset_lib.skx_ext_b(chips)!SKX_EXT_B_BGA1-IC,TBD!!!F94!DDR5_DQ(57)!!!!
S!M_F_DQ<58>!U5D1!CY27!@baseboard_fab2_lib.baseboard_fab2(sch_1):page28_i172@chpset_lib.skx_ext_b(chips)!SKX_EXT_B_BGA1-IC,TBD!!!F94!DDR5_DQ(58)!!!!
S!M_F_DQ<59>!U5D1!DB27!@baseboard_fab2_lib.baseboard_fab2(sch_1):page28_i172@chpset_lib.skx_ext_b(chips)!SKX_EXT_B_BGA1-IC,TBD!!!F94!DDR5_DQ(59)!!!!
S!M_F_DQ<5>!U5D1!CM75!@baseboard_fab2_lib.baseboard_fab2(sch_1):page28_i172@chpset_lib.skx_ext_b(chips)!SKX_EXT_B_BGA1-IC,TBD!!!F94!DDR5_DQ(5)!!!!
S!M_F_DQ<60>!U5D1!CY31!@baseboard_fab2_lib.baseboard_fab2(sch_1):page28_i172@chpset_lib.skx_ext_b(chips)!SKX_EXT_B_BGA1-IC,TBD!!!F94!DDR5_DQ(60)!!!!
S!M_F_DQ<61>!U5D1!DB31!@baseboard_fab2_lib.baseboard_fab2(sch_1):page28_i172@chpset_lib.skx_ext_b(chips)!SKX_EXT_B_BGA1-IC,TBD!!!F94!DDR5_DQ(61)!!!!
S!M_F_DQ<62>!U5D1!CW28!@baseboard_fab2_lib.baseboard_fab2(sch_1):page28_i172@chpset_lib.skx_ext_b(chips)!SKX_EXT_B_BGA1-IC,TBD!!!F94!DDR5_DQ(62)!!!!
S!M_F_DQ<63>!U5D1!DC28!@baseboard_fab2_lib.baseboard_fab2(sch_1):page28_i172@chpset_lib.skx_ext_b(chips)!SKX_EXT_B_BGA1-IC,TBD!!!F94!DDR5_DQ(63)!!!!
S!M_F_DQ<6>!U5D1!CV75!@baseboard_fab2_lib.baseboard_fab2(sch_1):page28_i172@chpset_lib.skx_ext_b(chips)!SKX_EXT_B_BGA1-IC,TBD!!!F94!DDR5_DQ(6)!!!!
S!M_F_DQ<7>!U5D1!CT77!@baseboard_fab2_lib.baseboard_fab2(sch_1):page28_i172@chpset_lib.skx_ext_b(chips)!SKX_EXT_B_BGA1-IC,TBD!!!F94!DDR5_DQ(7)!!!!
S!M_F_DQ<8>!U5D1!DE74!@baseboard_fab2_lib.baseboard_fab2(sch_1):page28_i172@chpset_lib.skx_ext_b(chips)!SKX_EXT_B_BGA1-IC,TBD!!!F94!DDR5_DQ(8)!!!!
S!M_F_DQ<9>!U5D1!DC76!@baseboard_fab2_lib.baseboard_fab2(sch_1):page28_i172@chpset_lib.skx_ext_b(chips)!SKX_EXT_B_BGA1-IC,TBD!!!F94!DDR5_DQ(9)!!!!
S!M_F_DQS_DN<0>!U5D1!CP77!@baseboard_fab2_lib.baseboard_fab2(sch_1):page28_i172@chpset_lib.skx_ext_b(chips)!SKX_EXT_B_BGA1-IC,TBD!!!F94!DDR5_DQS_DN(0)!!!!
S!M_F_DQS_DN<10>!U5D1!DF75!@baseboard_fab2_lib.baseboard_fab2(sch_1):page28_i172@chpset_lib.skx_ext_b(chips)!SKX_EXT_B_BGA1-IC,TBD!!!F94!DDR5_DQS_DN(10)!!!!
S!M_F_DQS_DN<11>!U5D1!DJ70!@baseboard_fab2_lib.baseboard_fab2(sch_1):page28_i172@chpset_lib.skx_ext_b(chips)!SKX_EXT_B_BGA1-IC,TBD!!!F94!DDR5_DQS_DN(11)!!!!
S!M_F_DQS_DN<12>!U5D1!CP65!@baseboard_fab2_lib.baseboard_fab2(sch_1):page28_i172@chpset_lib.skx_ext_b(chips)!SKX_EXT_B_BGA1-IC,TBD!!!F94!DDR5_DQS_DN(12)!!!!
S!M_F_DQS_DN<13>!U5D1!DE40!@baseboard_fab2_lib.baseboard_fab2(sch_1):page28_i172@chpset_lib.skx_ext_b(chips)!SKX_EXT_B_BGA1-IC,TBD!!!F94!DDR5_DQS_DN(13)!!!!
S!M_F_DQS_DN<14>!U5D1!DG32!@baseboard_fab2_lib.baseboard_fab2(sch_1):page28_i172@chpset_lib.skx_ext_b(chips)!SKX_EXT_B_BGA1-IC,TBD!!!F94!DDR5_DQS_DN(14)!!!!
S!M_F_DQS_DN<15>!U5D1!CY35!@baseboard_fab2_lib.baseboard_fab2(sch_1):page28_i172@chpset_lib.skx_ext_b(chips)!SKX_EXT_B_BGA1-IC,TBD!!!F94!DDR5_DQS_DN(15)!!!!
S!M_F_DQS_DN<16>!U5D1!CY29!@baseboard_fab2_lib.baseboard_fab2(sch_1):page28_i172@chpset_lib.skx_ext_b(chips)!SKX_EXT_B_BGA1-IC,TBD!!!F94!DDR5_DQS_DN(16)!!!!
S!M_F_DQS_DN<17>!U5D1!CJ70!@baseboard_fab2_lib.baseboard_fab2(sch_1):page28_i172@chpset_lib.skx_ext_b(chips)!SKX_EXT_B_BGA1-IC,TBD!!!F94!DDR5_DQS_DN(17)!!!!
S!M_F_DQS_DN<1>!U5D1!DD77!@baseboard_fab2_lib.baseboard_fab2(sch_1):page28_i172@chpset_lib.skx_ext_b(chips)!SKX_EXT_B_BGA1-IC,TBD!!!F94!DDR5_DQS_DN(1)!!!!
S!M_F_DQS_DN<2>!U5D1!DL72!@baseboard_fab2_lib.baseboard_fab2(sch_1):page28_i172@chpset_lib.skx_ext_b(chips)!SKX_EXT_B_BGA1-IC,TBD!!!F94!DDR5_DQS_DN(2)!!!!
S!M_F_DQS_DN<3>!U5D1!CV65!@baseboard_fab2_lib.baseboard_fab2(sch_1):page28_i172@chpset_lib.skx_ext_b(chips)!SKX_EXT_B_BGA1-IC,TBD!!!F94!DDR5_DQS_DN(3)!!!!
S!M_F_DQS_DN<4>!U5D1!DG40!@baseboard_fab2_lib.baseboard_fab2(sch_1):page28_i172@chpset_lib.skx_ext_b(chips)!SKX_EXT_B_BGA1-IC,TBD!!!F94!DDR5_DQS_DN(4)!!!!
S!M_F_DQS_DN<5>!U5D1!DL32!@baseboard_fab2_lib.baseboard_fab2(sch_1):page28_i172@chpset_lib.skx_ext_b(chips)!SKX_EXT_B_BGA1-IC,TBD!!!F94!DDR5_DQS_DN(5)!!!!
S!M_F_DQS_DN<6>!U5D1!DD35!@baseboard_fab2_lib.baseboard_fab2(sch_1):page28_i172@chpset_lib.skx_ext_b(chips)!SKX_EXT_B_BGA1-IC,TBD!!!F94!DDR5_DQS_DN(6)!!!!
S!M_F_DQS_DN<7>!U5D1!DD29!@baseboard_fab2_lib.baseboard_fab2(sch_1):page28_i172@chpset_lib.skx_ext_b(chips)!SKX_EXT_B_BGA1-IC,TBD!!!F94!DDR5_DQS_DN(7)!!!!
S!M_F_DQS_DN<8>!U5D1!CN70!@baseboard_fab2_lib.baseboard_fab2(sch_1):page28_i172@chpset_lib.skx_ext_b(chips)!SKX_EXT_B_BGA1-IC,TBD!!!F94!DDR5_DQS_DN(8)!!!!
S!M_F_DQS_DN<9>!U5D1!CT75!@baseboard_fab2_lib.baseboard_fab2(sch_1):page28_i172@chpset_lib.skx_ext_b(chips)!SKX_EXT_B_BGA1-IC,TBD!!!F94!DDR5_DQS_DN(9)!!!!
S!M_F_DQS_DP<0>!U5D1!CR76!@baseboard_fab2_lib.baseboard_fab2(sch_1):page28_i172@chpset_lib.skx_ext_b(chips)!SKX_EXT_B_BGA1-IC,TBD!!!F94!DDR5_DQS_DP(0)!!!!
S!M_F_DQS_DP<10>!U5D1!DG74!@baseboard_fab2_lib.baseboard_fab2(sch_1):page28_i172@chpset_lib.skx_ext_b(chips)!SKX_EXT_B_BGA1-IC,TBD!!!F94!DDR5_DQS_DP(10)!!!!
S!M_F_DQS_DP<11>!U5D1!DH69!@baseboard_fab2_lib.baseboard_fab2(sch_1):page28_i172@chpset_lib.skx_ext_b(chips)!SKX_EXT_B_BGA1-IC,TBD!!!F94!DDR5_DQS_DP(11)!!!!
S!M_F_DQS_DP<12>!U5D1!CM65!@baseboard_fab2_lib.baseboard_fab2(sch_1):page28_i172@chpset_lib.skx_ext_b(chips)!SKX_EXT_B_BGA1-IC,TBD!!!F94!DDR5_DQS_DP(12)!!!!
S!M_F_DQS_DP<13>!U5D1!DC40!@baseboard_fab2_lib.baseboard_fab2(sch_1):page28_i172@chpset_lib.skx_ext_b(chips)!SKX_EXT_B_BGA1-IC,TBD!!!F94!DDR5_DQS_DP(13)!!!!
S!M_F_DQS_DP<14>!U5D1!DE32!@baseboard_fab2_lib.baseboard_fab2(sch_1):page28_i172@chpset_lib.skx_ext_b(chips)!SKX_EXT_B_BGA1-IC,TBD!!!F94!DDR5_DQS_DP(14)!!!!
S!M_F_DQS_DP<15>!U5D1!CV35!@baseboard_fab2_lib.baseboard_fab2(sch_1):page28_i172@chpset_lib.skx_ext_b(chips)!SKX_EXT_B_BGA1-IC,TBD!!!F94!DDR5_DQS_DP(15)!!!!
S!M_F_DQS_DP<16>!U5D1!CV29!@baseboard_fab2_lib.baseboard_fab2(sch_1):page28_i172@chpset_lib.skx_ext_b(chips)!SKX_EXT_B_BGA1-IC,TBD!!!F94!DDR5_DQS_DP(16)!!!!
S!M_F_DQS_DP<17>!U5D1!CG70!@baseboard_fab2_lib.baseboard_fab2(sch_1):page28_i172@chpset_lib.skx_ext_b(chips)!SKX_EXT_B_BGA1-IC,TBD!!!F94!DDR5_DQS_DP(17)!!!!
S!M_F_DQS_DP<1>!U5D1!DE76!@baseboard_fab2_lib.baseboard_fab2(sch_1):page28_i172@chpset_lib.skx_ext_b(chips)!SKX_EXT_B_BGA1-IC,TBD!!!F94!DDR5_DQS_DP(1)!!!!
S!M_F_DQS_DP<2>!U5D1!DK71!@baseboard_fab2_lib.baseboard_fab2(sch_1):page28_i172@chpset_lib.skx_ext_b(chips)!SKX_EXT_B_BGA1-IC,TBD!!!F94!DDR5_DQS_DP(2)!!!!
S!M_F_DQS_DP<3>!U5D1!CT65!@baseboard_fab2_lib.baseboard_fab2(sch_1):page28_i172@chpset_lib.skx_ext_b(chips)!SKX_EXT_B_BGA1-IC,TBD!!!F94!DDR5_DQS_DP(3)!!!!
S!M_F_DQS_DP<4>!U5D1!DJ40!@baseboard_fab2_lib.baseboard_fab2(sch_1):page28_i172@chpset_lib.skx_ext_b(chips)!SKX_EXT_B_BGA1-IC,TBD!!!F94!DDR5_DQS_DP(4)!!!!
S!M_F_DQS_DP<5>!U5D1!DJ32!@baseboard_fab2_lib.baseboard_fab2(sch_1):page28_i172@chpset_lib.skx_ext_b(chips)!SKX_EXT_B_BGA1-IC,TBD!!!F94!DDR5_DQS_DP(5)!!!!
S!M_F_DQS_DP<6>!U5D1!DB35!@baseboard_fab2_lib.baseboard_fab2(sch_1):page28_i172@chpset_lib.skx_ext_b(chips)!SKX_EXT_B_BGA1-IC,TBD!!!F94!DDR5_DQS_DP(6)!!!!
S!M_F_DQS_DP<7>!U5D1!DB29!@baseboard_fab2_lib.baseboard_fab2(sch_1):page28_i172@chpset_lib.skx_ext_b(chips)!SKX_EXT_B_BGA1-IC,TBD!!!F94!DDR5_DQS_DP(7)!!!!
S!M_F_DQS_DP<8>!U5D1!CL70!@baseboard_fab2_lib.baseboard_fab2(sch_1):page28_i172@chpset_lib.skx_ext_b(chips)!SKX_EXT_B_BGA1-IC,TBD!!!F94!DDR5_DQS_DP(8)!!!!
S!M_F_DQS_DP<9>!U5D1!CU74!@baseboard_fab2_lib.baseboard_fab2(sch_1):page28_i172@chpset_lib.skx_ext_b(chips)!SKX_EXT_B_BGA1-IC,TBD!!!F94!DDR5_DQS_DP(9)!!!!
S!M_F_ECC<0>!U5D1!CH71!@baseboard_fab2_lib.baseboard_fab2(sch_1):page28_i172@chpset_lib.skx_ext_b(chips)!SKX_EXT_B_BGA1-IC,TBD!!!F94!DDR5_ECC(0)!!!!
S!M_F_ECC<1>!U5D1!CM71!@baseboard_fab2_lib.baseboard_fab2(sch_1):page28_i172@chpset_lib.skx_ext_b(chips)!SKX_EXT_B_BGA1-IC,TBD!!!F94!DDR5_ECC(1)!!!!
S!M_F_ECC<2>!U5D1!CJ68!@baseboard_fab2_lib.baseboard_fab2(sch_1):page28_i172@chpset_lib.skx_ext_b(chips)!SKX_EXT_B_BGA1-IC,TBD!!!F94!DDR5_ECC(2)!!!!
S!M_F_ECC<3>!U5D1!CL68!@baseboard_fab2_lib.baseboard_fab2(sch_1):page28_i172@chpset_lib.skx_ext_b(chips)!SKX_EXT_B_BGA1-IC,TBD!!!F94!DDR5_ECC(3)!!!!
S!M_F_ECC<4>!U5D1!CJ72!@baseboard_fab2_lib.baseboard_fab2(sch_1):page28_i172@chpset_lib.skx_ext_b(chips)!SKX_EXT_B_BGA1-IC,TBD!!!F94!DDR5_ECC(4)!!!!
S!M_F_ECC<5>!U5D1!CL72!@baseboard_fab2_lib.baseboard_fab2(sch_1):page28_i172@chpset_lib.skx_ext_b(chips)!SKX_EXT_B_BGA1-IC,TBD!!!F94!DDR5_ECC(5)!!!!
S!M_F_ECC<6>!U5D1!CH69!@baseboard_fab2_lib.baseboard_fab2(sch_1):page28_i172@chpset_lib.skx_ext_b(chips)!SKX_EXT_B_BGA1-IC,TBD!!!F94!DDR5_ECC(6)!!!!
S!M_F_ECC<7>!U5D1!CM69!@baseboard_fab2_lib.baseboard_fab2(sch_1):page28_i172@chpset_lib.skx_ext_b(chips)!SKX_EXT_B_BGA1-IC,TBD!!!F94!DDR5_ECC(7)!!!!
S!M_F_MA<0>!U5D1!DF53!@baseboard_fab2_lib.baseboard_fab2(sch_1):page28_i172@chpset_lib.skx_ext_b(chips)!SKX_EXT_B_BGA1-IC,TBD!!!F94!DDR5_MA(0)!!!!
S!M_F_MA<10>!U5D1!DD55!@baseboard_fab2_lib.baseboard_fab2(sch_1):page28_i172@chpset_lib.skx_ext_b(chips)!SKX_EXT_B_BGA1-IC,TBD!!!F94!DDR5_MA(10)!!!!
S!M_F_MA<11>!U5D1!DA60!@baseboard_fab2_lib.baseboard_fab2(sch_1):page28_i172@chpset_lib.skx_ext_b(chips)!SKX_EXT_B_BGA1-IC,TBD!!!F94!DDR5_MA(11)!!!!
S!M_F_MA<12>!U5D1!DG60!@baseboard_fab2_lib.baseboard_fab2(sch_1):page28_i172@chpset_lib.skx_ext_b(chips)!SKX_EXT_B_BGA1-IC,TBD!!!F94!DDR5_MA(12)!!!!
S!M_F_MA<13>!U5D1!DD53!@baseboard_fab2_lib.baseboard_fab2(sch_1):page28_i172@chpset_lib.skx_ext_b(chips)!SKX_EXT_B_BGA1-IC,TBD!!!F94!DDR5_MA(13)!!!!
S!M_F_MA<14>!U5D1!DJ50!@baseboard_fab2_lib.baseboard_fab2(sch_1):page28_i172@chpset_lib.skx_ext_b(chips)!SKX_EXT_B_BGA1-IC,TBD!!!F94!DDR5_MA(14)!!!!
S!M_F_MA<15>!U5D1!DC54!@baseboard_fab2_lib.baseboard_fab2(sch_1):page28_i172@chpset_lib.skx_ext_b(chips)!SKX_EXT_B_BGA1-IC,TBD!!!F94!DDR5_MA(15)!!!!
S!M_F_MA<16>!U5D1!DG52!@baseboard_fab2_lib.baseboard_fab2(sch_1):page28_i172@chpset_lib.skx_ext_b(chips)!SKX_EXT_B_BGA1-IC,TBD!!!F94!DDR5_MA(16)!!!!
S!M_F_MA<17>!U5D1!DE46!@baseboard_fab2_lib.baseboard_fab2(sch_1):page28_i172@chpset_lib.skx_ext_b(chips)!SKX_EXT_B_BGA1-IC,TBD!!!F94!DDR5_MA(17)!!!!
S!M_F_MA<1>!U5D1!DC58!@baseboard_fab2_lib.baseboard_fab2(sch_1):page28_i172@chpset_lib.skx_ext_b(chips)!SKX_EXT_B_BGA1-IC,TBD!!!F94!DDR5_MA(1)!!!!
S!M_F_MA<2>!U5D1!DD57!@baseboard_fab2_lib.baseboard_fab2(sch_1):page28_i172@chpset_lib.skx_ext_b(chips)!SKX_EXT_B_BGA1-IC,TBD!!!F94!DDR5_MA(2)!!!!
S!M_F_MA<3>!U5D1!DG58!@baseboard_fab2_lib.baseboard_fab2(sch_1):page28_i172@chpset_lib.skx_ext_b(chips)!SKX_EXT_B_BGA1-IC,TBD!!!F94!DDR5_MA(3)!!!!
S!M_F_MA<4>!U5D1!DJ58!@baseboard_fab2_lib.baseboard_fab2(sch_1):page28_i172@chpset_lib.skx_ext_b(chips)!SKX_EXT_B_BGA1-IC,TBD!!!F94!DDR5_MA(4)!!!!
S!M_F_MA<5>!U5D1!DF59!@baseboard_fab2_lib.baseboard_fab2(sch_1):page28_i172@chpset_lib.skx_ext_b(chips)!SKX_EXT_B_BGA1-IC,TBD!!!F94!DDR5_MA(5)!!!!
S!M_F_MA<6>!U5D1!DK59!@baseboard_fab2_lib.baseboard_fab2(sch_1):page28_i172@chpset_lib.skx_ext_b(chips)!SKX_EXT_B_BGA1-IC,TBD!!!F94!DDR5_MA(6)!!!!
S!M_F_MA<7>!U5D1!DC60!@baseboard_fab2_lib.baseboard_fab2(sch_1):page28_i172@chpset_lib.skx_ext_b(chips)!SKX_EXT_B_BGA1-IC,TBD!!!F94!DDR5_MA(7)!!!!
S!M_F_MA<8>!U5D1!DD59!@baseboard_fab2_lib.baseboard_fab2(sch_1):page28_i172@chpset_lib.skx_ext_b(chips)!SKX_EXT_B_BGA1-IC,TBD!!!F94!DDR5_MA(8)!!!!
S!M_F_MA<9>!U5D1!DA58!@baseboard_fab2_lib.baseboard_fab2(sch_1):page28_i172@chpset_lib.skx_ext_b(chips)!SKX_EXT_B_BGA1-IC,TBD!!!F94!DDR5_MA(9)!!!!
S!M_F_ODT<0>!U5D1!DG50!@baseboard_fab2_lib.baseboard_fab2(sch_1):page28_i172@chpset_lib.skx_ext_b(chips)!SKX_EXT_B_BGA1-IC,TBD!!!F94!DDR5_ODT(0)!!!!
S!M_F_ODT<1>!U5D1!DG48!@baseboard_fab2_lib.baseboard_fab2(sch_1):page28_i172@chpset_lib.skx_ext_b(chips)!SKX_EXT_B_BGA1-IC,TBD!!!F94!DDR5_ODT(1)!!!!
S!M_F_ODT<2>!U5D1!DK49!@baseboard_fab2_lib.baseboard_fab2(sch_1):page28_i172@chpset_lib.skx_ext_b(chips)!SKX_EXT_B_BGA1-IC,TBD!!!F94!DDR5_ODT(2)!!!!
S!M_F_ODT<3>!U5D1!DF47!@baseboard_fab2_lib.baseboard_fab2(sch_1):page28_i172@chpset_lib.skx_ext_b(chips)!SKX_EXT_B_BGA1-IC,TBD!!!F94!DDR5_ODT(3)!!!!
S!M_F_PAR!U5D1!DK53!@baseboard_fab2_lib.baseboard_fab2(sch_1):page28_i172@chpset_lib.skx_ext_b(chips)!SKX_EXT_B_BGA1-IC,TBD!!!F94!DDR5_PAR!!!!
S!SMB_HFI0_CPU0_LVC2_SCL!U5D1!BN22!@baseboard_fab2_lib.baseboard_fab2(sch_1):page29_i61@chpset_lib.skx_ext_b(chips)!SKX_EXT_B_BGA1-IC,TBD!!!F93!CD_HFI0_I2CCLK!!!!
S!SMB_HFI0_CPU0_LVC2_SDA!U5D1!BP23!@baseboard_fab2_lib.baseboard_fab2(sch_1):page29_i61@chpset_lib.skx_ext_b(chips)!SKX_EXT_B_BGA1-IC,TBD!!!F93!CD_HFI0_I2CDAT!!!!
S!IRQ_HFI0_CPU0_LVT2_N!U5D1!BP19!@baseboard_fab2_lib.baseboard_fab2(sch_1):page29_i61@chpset_lib.skx_ext_b(chips)!SKX_EXT_B_BGA1-IC,TBD!!!F93!CD_HFI0_INT_N!!!!
S!LED_HFI0_CPU0_N!U5D1!BK21!@baseboard_fab2_lib.baseboard_fab2(sch_1):page29_i61@chpset_lib.skx_ext_b(chips)!SKX_EXT_B_BGA1-IC,TBD!!!F93!CD_HFI0_LED_N!!!!
S!FM_MODPRST_HFI0_CPU0_LVT2_N!U5D1!BR20!@baseboard_fab2_lib.baseboard_fab2(sch_1):page29_i61@chpset_lib.skx_ext_b(chips)!SKX_EXT_B_BGA1-IC,TBD!!!F93!CD_HFI0_MODPRST_N!!!!
S!RST_HFI0_CPU0_LVT2_N!U5D1!BN24!@baseboard_fab2_lib.baseboard_fab2(sch_1):page29_i61@chpset_lib.skx_ext_b(chips)!SKX_EXT_B_BGA1-IC,TBD!!!F93!CD_HFI0_RESET_N!!!!
S!SMB_HFI1_CPU0_LVC2_SCL!U5D1!BJ22!@baseboard_fab2_lib.baseboard_fab2(sch_1):page29_i61@chpset_lib.skx_ext_b(chips)!SKX_EXT_B_BGA1-IC,TBD!!!F93!CD_HFI1_I2CCLK!!!!
S!SMB_HFI1_CPU0_LVC2_SDA!U5D1!BH23!@baseboard_fab2_lib.baseboard_fab2(sch_1):page29_i61@chpset_lib.skx_ext_b(chips)!SKX_EXT_B_BGA1-IC,TBD!!!F93!CD_HFI1_I2CDAT!!!!
S!IRQ_HFI1_CPU0_LVT2_N!U5D1!BM21!@baseboard_fab2_lib.baseboard_fab2(sch_1):page29_i61@chpset_lib.skx_ext_b(chips)!SKX_EXT_B_BGA1-IC,TBD!!!F93!CD_HFI1_INT_N!!!!
S!LED_HFI1_CPU0_N!U5D1!BM23!@baseboard_fab2_lib.baseboard_fab2(sch_1):page29_i61@chpset_lib.skx_ext_b(chips)!SKX_EXT_B_BGA1-IC,TBD!!!F93!CD_HFI1_LED_N!!!!
S!FM_MODPRST_HFI1_CPU0_LVT2_N!U5D1!BT19!@baseboard_fab2_lib.baseboard_fab2(sch_1):page29_i61@chpset_lib.skx_ext_b(chips)!SKX_EXT_B_BGA1-IC,TBD!!!F93!CD_HFI1_MODPRST_N!!!!
S!RST_HFI1_CPU0_LVT2_N!U5D1!BK23!@baseboard_fab2_lib.baseboard_fab2(sch_1):page29_i61@chpset_lib.skx_ext_b(chips)!SKX_EXT_B_BGA1-IC,TBD!!!F93!CD_HFI1_RESET_N!!!!
S!CLK_156M_OSC_CPU0_HFI_DN!U5D1!BE16!@baseboard_fab2_lib.baseboard_fab2(sch_1):page29_i61@chpset_lib.skx_ext_b(chips)!SKX_EXT_B_BGA1-IC,TBD!!!F93!CD_HFI_REFCLK_DN!!!!
S!CLK_156M_OSC_CPU0_HFI_DP!U5D1!BG16!@baseboard_fab2_lib.baseboard_fab2(sch_1):page29_i61@chpset_lib.skx_ext_b(chips)!SKX_EXT_B_BGA1-IC,TBD!!!F93!CD_HFI_REFCLK_DP!!!!
S!CLK_100M_CPU0_PE_REFCLK_DN!U5D1!BU24!@baseboard_fab2_lib.baseboard_fab2(sch_1):page29_i61@chpset_lib.skx_ext_b(chips)!SKX_EXT_B_BGA1-IC,TBD!!!F93!CD_PE_REFCLK_DN!!!!
S!CLK_100M_CPU0_PE_REFCLK_DP!U5D1!BW24!@baseboard_fab2_lib.baseboard_fab2(sch_1):page29_i61@chpset_lib.skx_ext_b(chips)!SKX_EXT_B_BGA1-IC,TBD!!!F93!CD_PE_REFCLK_DP!!!!
S!RST_CD_CPU0_POR_N!U5D1!CF25!@baseboard_fab2_lib.baseboard_fab2(sch_1):page29_i61@chpset_lib.skx_ext_b(chips)!SKX_EXT_B_BGA1-IC,TBD!!!F93!CD_POR_N!!!!
S!JTAG_MCP_TCK!U5D1!CB23!@baseboard_fab2_lib.baseboard_fab2(sch_1):page29_i61@chpset_lib.skx_ext_b(chips)!SKX_EXT_B_BGA1-IC,TBD!!!F93!CD_TCLK!!!!
S!JTAG_MCP_CPU0_TDI!U5D1!BY21!@baseboard_fab2_lib.baseboard_fab2(sch_1):page29_i61@chpset_lib.skx_ext_b(chips)!SKX_EXT_B_BGA1-IC,TBD!!!F93!CD_TDI!!!!
S!JTAG_MCP_CPU0_TDO!U5D1!CC22!@baseboard_fab2_lib.baseboard_fab2(sch_1):page29_i61@chpset_lib.skx_ext_b(chips)!SKX_EXT_B_BGA1-IC,TBD!!!F93!CD_TDO!!!!
S!JTAG_MCP_TMS!U5D1!CE24!@baseboard_fab2_lib.baseboard_fab2(sch_1):page29_i61@chpset_lib.skx_ext_b(chips)!SKX_EXT_B_BGA1-IC,TBD!!!F93!CD_TMS!!!!
S!JTAG_MCP_TRST_N!U5D1!CD23!@baseboard_fab2_lib.baseboard_fab2(sch_1):page29_i61@chpset_lib.skx_ext_b(chips)!SKX_EXT_B_BGA1-IC,TBD!!!F93!CD_TRST_N!!!!
S!DMI_CPU0_PCH_RX_C_DN<0>!U5D1!CK9!@baseboard_fab2_lib.baseboard_fab2(sch_1):page29_i61@chpset_lib.skx_ext_b(chips)!SKX_EXT_B_BGA1-IC,TBD!!!F93!DMI_RX_DN(0)!!!!
S!DMI_CPU0_PCH_RX_C_DN<1>!U5D1!CM11!@baseboard_fab2_lib.baseboard_fab2(sch_1):page29_i61@chpset_lib.skx_ext_b(chips)!SKX_EXT_B_BGA1-IC,TBD!!!F93!DMI_RX_DN(1)!!!!
S!DMI_CPU0_PCH_RX_C_DN<2>!U5D1!CR12!@baseboard_fab2_lib.baseboard_fab2(sch_1):page29_i61@chpset_lib.skx_ext_b(chips)!SKX_EXT_B_BGA1-IC,TBD!!!F93!DMI_RX_DN(2)!!!!
S!DMI_CPU0_PCH_RX_C_DN<3>!U5D1!CT11!@baseboard_fab2_lib.baseboard_fab2(sch_1):page29_i61@chpset_lib.skx_ext_b(chips)!SKX_EXT_B_BGA1-IC,TBD!!!F93!DMI_RX_DN(3)!!!!
S!DMI_CPU0_PCH_RX_C_DP<0>!U5D1!CL10!@baseboard_fab2_lib.baseboard_fab2(sch_1):page29_i61@chpset_lib.skx_ext_b(chips)!SKX_EXT_B_BGA1-IC,TBD!!!F93!DMI_RX_DP(0)!!!!
S!DMI_CPU0_PCH_RX_C_DP<1>!U5D1!CN10!@baseboard_fab2_lib.baseboard_fab2(sch_1):page29_i61@chpset_lib.skx_ext_b(chips)!SKX_EXT_B_BGA1-IC,TBD!!!F93!DMI_RX_DP(1)!!!!
S!DMI_CPU0_PCH_RX_C_DP<2>!U5D1!CP11!@baseboard_fab2_lib.baseboard_fab2(sch_1):page29_i61@chpset_lib.skx_ext_b(chips)!SKX_EXT_B_BGA1-IC,TBD!!!F93!DMI_RX_DP(2)!!!!
S!DMI_CPU0_PCH_RX_C_DP<3>!U5D1!CV11!@baseboard_fab2_lib.baseboard_fab2(sch_1):page29_i61@chpset_lib.skx_ext_b(chips)!SKX_EXT_B_BGA1-IC,TBD!!!F93!DMI_RX_DP(3)!!!!
S!DMI_CPU0_PCH_TX_DN<0>!U5D1!CG4!@baseboard_fab2_lib.baseboard_fab2(sch_1):page29_i61@chpset_lib.skx_ext_b(chips)!SKX_EXT_B_BGA1-IC,TBD!!!F93!DMI_TX_DN(0)!!!!
S!DMI_CPU0_PCH_TX_DN<1>!U5D1!CJ4!@baseboard_fab2_lib.baseboard_fab2(sch_1):page29_i61@chpset_lib.skx_ext_b(chips)!SKX_EXT_B_BGA1-IC,TBD!!!F93!DMI_TX_DN(1)!!!!
S!DMI_CPU0_PCH_TX_DN<2>!U5D1!CN4!@baseboard_fab2_lib.baseboard_fab2(sch_1):page29_i61@chpset_lib.skx_ext_b(chips)!SKX_EXT_B_BGA1-IC,TBD!!!F93!DMI_TX_DN(2)!!!!
S!DMI_CPU0_PCH_TX_DN<3>!U5D1!CP5!@baseboard_fab2_lib.baseboard_fab2(sch_1):page29_i61@chpset_lib.skx_ext_b(chips)!SKX_EXT_B_BGA1-IC,TBD!!!F93!DMI_TX_DN(3)!!!!
S!DMI_CPU0_PCH_TX_DP<0>!U5D1!CH5!@baseboard_fab2_lib.baseboard_fab2(sch_1):page29_i61@chpset_lib.skx_ext_b(chips)!SKX_EXT_B_BGA1-IC,TBD!!!F93!DMI_TX_DP(0)!!!!
S!DMI_CPU0_PCH_TX_DP<1>!U5D1!CL4!@baseboard_fab2_lib.baseboard_fab2(sch_1):page29_i61@chpset_lib.skx_ext_b(chips)!SKX_EXT_B_BGA1-IC,TBD!!!F93!DMI_TX_DP(1)!!!!
S!DMI_CPU0_PCH_TX_DP<2>!U5D1!CM3!@baseboard_fab2_lib.baseboard_fab2(sch_1):page29_i61@chpset_lib.skx_ext_b(chips)!SKX_EXT_B_BGA1-IC,TBD!!!F93!DMI_TX_DP(2)!!!!
S!DMI_CPU0_PCH_TX_DP<3>!U5D1!CR4!@baseboard_fab2_lib.baseboard_fab2(sch_1):page29_i61@chpset_lib.skx_ext_b(chips)!SKX_EXT_B_BGA1-IC,TBD!!!F93!DMI_TX_DP(3)!!!!
S!CLK_322M_OSC_CPU0_RC_DN!U5D1!AL26!@baseboard_fab2_lib.baseboard_fab2(sch_1):page22_i204@chpset_lib.skx_ext_b(chips)!SKX_EXT_B_BGA1-IC,TBD!!!F100!RSVD(213)!!!!
S!CLK_322M_OSC_CPU0_RC_DP!U5D1!AK27!@baseboard_fab2_lib.baseboard_fab2(sch_1):page22_i204@chpset_lib.skx_ext_b(chips)!SKX_EXT_B_BGA1-IC,TBD!!!F100!RSVD(220)!!!!
S!TP_CPU0_RSVD_242!U5D1!AF53!@baseboard_fab2_lib.baseboard_fab2(sch_1):page22_i204@chpset_lib.skx_ext_b(chips)!SKX_EXT_B_BGA1-IC,TBD!!!F100!RSVD(242)!!!!
S!TP_CPU0_RSVD_237!U5D1!AG52!@baseboard_fab2_lib.baseboard_fab2(sch_1):page22_i204@chpset_lib.skx_ext_b(chips)!SKX_EXT_B_BGA1-IC,TBD!!!F100!RSVD(237)!!!!
S!TP_CPU0_RSVD_236!U5D1!AG54!@baseboard_fab2_lib.baseboard_fab2(sch_1):page22_i204@chpset_lib.skx_ext_b(chips)!SKX_EXT_B_BGA1-IC,TBD!!!F100!RSVD(236)!!!!
S!TP_CPU0_RSVD_231!U5D1!AH55!@baseboard_fab2_lib.baseboard_fab2(sch_1):page22_i204@chpset_lib.skx_ext_b(chips)!SKX_EXT_B_BGA1-IC,TBD!!!F100!RSVD(231)!!!!
S!TP_CPU0_RSVD_235!U5D1!AG56!@baseboard_fab2_lib.baseboard_fab2(sch_1):page22_i204@chpset_lib.skx_ext_b(chips)!SKX_EXT_B_BGA1-IC,TBD!!!F100!RSVD(235)!!!!
S!TP_CPU0_RSVD_226!U5D1!AJ56!@baseboard_fab2_lib.baseboard_fab2(sch_1):page22_i204@chpset_lib.skx_ext_b(chips)!SKX_EXT_B_BGA1-IC,TBD!!!F100!RSVD(226)!!!!
S!TP_CPU0_RSVD_219!U5D1!AK57!@baseboard_fab2_lib.baseboard_fab2(sch_1):page22_i204@chpset_lib.skx_ext_b(chips)!SKX_EXT_B_BGA1-IC,TBD!!!F100!RSVD(219)!!!!
S!TP_CPU0_RSVD_248!U5D1!AE52!@baseboard_fab2_lib.baseboard_fab2(sch_1):page22_i204@chpset_lib.skx_ext_b(chips)!SKX_EXT_B_BGA1-IC,TBD!!!F100!RSVD(248)!!!!
S!TP_CPU0_RSVD_250!U5D1!AE48!@baseboard_fab2_lib.baseboard_fab2(sch_1):page22_i204@chpset_lib.skx_ext_b(chips)!SKX_EXT_B_BGA1-IC,TBD!!!F100!RSVD(250)!!!!
S!TP_CPU0_RSVD_239!U5D1!AG48!@baseboard_fab2_lib.baseboard_fab2(sch_1):page22_i204@chpset_lib.skx_ext_b(chips)!SKX_EXT_B_BGA1-IC,TBD!!!F100!RSVD(239)!!!!
S!TP_CPU0_RSVD_244!U5D1!AF49!@baseboard_fab2_lib.baseboard_fab2(sch_1):page22_i204@chpset_lib.skx_ext_b(chips)!SKX_EXT_B_BGA1-IC,TBD!!!F100!RSVD(244)!!!!
S!TP_CPU0_RSVD_253!U5D1!AD49!@baseboard_fab2_lib.baseboard_fab2(sch_1):page22_i204@chpset_lib.skx_ext_b(chips)!SKX_EXT_B_BGA1-IC,TBD!!!F100!RSVD(253)!!!!
S!TP_CPU0_RSVD_249!U5D1!AE50!@baseboard_fab2_lib.baseboard_fab2(sch_1):page22_i204@chpset_lib.skx_ext_b(chips)!SKX_EXT_B_BGA1-IC,TBD!!!F100!RSVD(249)!!!!
S!TP_CPU0_RSVD_238!U5D1!AG50!@baseboard_fab2_lib.baseboard_fab2(sch_1):page22_i204@chpset_lib.skx_ext_b(chips)!SKX_EXT_B_BGA1-IC,TBD!!!F100!RSVD(238)!!!!
S!TP_CPU0_RSVD_243!U5D1!AF51!@baseboard_fab2_lib.baseboard_fab2(sch_1):page22_i204@chpset_lib.skx_ext_b(chips)!SKX_EXT_B_BGA1-IC,TBD!!!F100!RSVD(243)!!!!
S!TP_CPU0_RSVD_252!U5D1!AD51!@baseboard_fab2_lib.baseboard_fab2(sch_1):page22_i204@chpset_lib.skx_ext_b(chips)!SKX_EXT_B_BGA1-IC,TBD!!!F100!RSVD(252)!!!!
S!CLK_100M_CPU0_RC_REFCLK0_DN!U5D1!AP27!@baseboard_fab2_lib.baseboard_fab2(sch_1):page22_i204@chpset_lib.skx_ext_b(chips)!SKX_EXT_B_BGA1-IC,TBD!!!F100!RSVD(195)!!!!
S!PVCCIO_CPU0!U5D1!AR28!@baseboard_fab2_lib.baseboard_fab2(sch_1):page38_i34@chpset_lib.skx_ext_b(chips)!SKX_EXT_B_BGA1-IC,TBD!!!F81!VCCIO(104)!!!!
S!P3E_CPU0_PE1_SS_RXN<0>!U5D1!CW8!@baseboard_fab2_lib.baseboard_fab2(sch_1):page30_i84@chpset_lib.skx_ext_b(chips)!SKX_EXT_B_BGA1-IC,TBD!!!F92!PE1_RX_DN(0)!!!!
S!P3E_CPU0_PE1_PCH_RXN<10>!U5D1!DT11!@baseboard_fab2_lib.baseboard_fab2(sch_1):page30_i84@chpset_lib.skx_ext_b(chips)!SKX_EXT_B_BGA1-IC,TBD!!!F92!PE1_RX_DN(10)!!!!
S!P3E_CPU0_PE1_PCH_RXN<11>!U5D1!DT13!@baseboard_fab2_lib.baseboard_fab2(sch_1):page30_i84@chpset_lib.skx_ext_b(chips)!SKX_EXT_B_BGA1-IC,TBD!!!F92!PE1_RX_DN(11)!!!!
S!P3E_CPU0_PE1_PCH_RXN<12>!U5D1!DV13!@baseboard_fab2_lib.baseboard_fab2(sch_1):page30_i84@chpset_lib.skx_ext_b(chips)!SKX_EXT_B_BGA1-IC,TBD!!!F92!PE1_RX_DN(12)!!!!
S!P3E_CPU0_PE1_PCH_RXN<13>!U5D1!DW14!@baseboard_fab2_lib.baseboard_fab2(sch_1):page30_i84@chpset_lib.skx_ext_b(chips)!SKX_EXT_B_BGA1-IC,TBD!!!F92!PE1_RX_DN(13)!!!!
S!P3E_CPU0_PE1_PCH_RXN<14>!U5D1!DY15!@baseboard_fab2_lib.baseboard_fab2(sch_1):page30_i84@chpset_lib.skx_ext_b(chips)!SKX_EXT_B_BGA1-IC,TBD!!!F92!PE1_RX_DN(14)!!!!
S!P3E_CPU0_PE1_PCH_RXN<15>!U5D1!DU16!@baseboard_fab2_lib.baseboard_fab2(sch_1):page30_i84@chpset_lib.skx_ext_b(chips)!SKX_EXT_B_BGA1-IC,TBD!!!F92!PE1_RX_DN(15)!!!!
S!P3E_CPU0_PE1_SS_RXN<1>!U5D1!DA8!@baseboard_fab2_lib.baseboard_fab2(sch_1):page30_i84@chpset_lib.skx_ext_b(chips)!SKX_EXT_B_BGA1-IC,TBD!!!F92!PE1_RX_DN(1)!!!!
S!P3E_CPU0_PE1_SS_RXN<2>!U5D1!DC8!@baseboard_fab2_lib.baseboard_fab2(sch_1):page30_i84@chpset_lib.skx_ext_b(chips)!SKX_EXT_B_BGA1-IC,TBD!!!F92!PE1_RX_DN(2)!!!!
S!P3E_CPU0_PE1_SS_RXN<3>!U5D1!DC10!@baseboard_fab2_lib.baseboard_fab2(sch_1):page30_i84@chpset_lib.skx_ext_b(chips)!SKX_EXT_B_BGA1-IC,TBD!!!F92!PE1_RX_DN(3)!!!!
S!P3E_CPU0_PE1_SS_RXN<4>!U5D1!DE10!@baseboard_fab2_lib.baseboard_fab2(sch_1):page30_i84@chpset_lib.skx_ext_b(chips)!SKX_EXT_B_BGA1-IC,TBD!!!F92!PE1_RX_DN(4)!!!!
S!P3E_CPU0_PE1_SS_RXN<5>!U5D1!DH9!@baseboard_fab2_lib.baseboard_fab2(sch_1):page30_i84@chpset_lib.skx_ext_b(chips)!SKX_EXT_B_BGA1-IC,TBD!!!F92!PE1_RX_DN(5)!!!!
S!P3E_CPU0_PE1_SS_RXN<6>!U5D1!DK9!@baseboard_fab2_lib.baseboard_fab2(sch_1):page30_i84@chpset_lib.skx_ext_b(chips)!SKX_EXT_B_BGA1-IC,TBD!!!F92!PE1_RX_DN(6)!!!!
S!P3E_CPU0_PE1_SS_RXN<7>!U5D1!DM9!@baseboard_fab2_lib.baseboard_fab2(sch_1):page30_i84@chpset_lib.skx_ext_b(chips)!SKX_EXT_B_BGA1-IC,TBD!!!F92!PE1_RX_DN(7)!!!!
S!P3E_CPU0_PE1_PCH_RXN<8>!U5D1!DM11!@baseboard_fab2_lib.baseboard_fab2(sch_1):page30_i84@chpset_lib.skx_ext_b(chips)!SKX_EXT_B_BGA1-IC,TBD!!!F92!PE1_RX_DN(8)!!!!
S!P3E_CPU0_PE1_PCH_RXN<9>!U5D1!DP11!@baseboard_fab2_lib.baseboard_fab2(sch_1):page30_i84@chpset_lib.skx_ext_b(chips)!SKX_EXT_B_BGA1-IC,TBD!!!F92!PE1_RX_DN(9)!!!!
S!P3E_CPU0_PE1_SS_RXP<0>!U5D1!CU8!@baseboard_fab2_lib.baseboard_fab2(sch_1):page30_i84@chpset_lib.skx_ext_b(chips)!SKX_EXT_B_BGA1-IC,TBD!!!F92!PE1_RX_DP(0)!!!!
S!P3E_CPU0_PE1_PCH_RXP<10>!U5D1!DR12!@baseboard_fab2_lib.baseboard_fab2(sch_1):page30_i84@chpset_lib.skx_ext_b(chips)!SKX_EXT_B_BGA1-IC,TBD!!!F92!PE1_RX_DP(10)!!!!
S!P3E_CPU0_PE1_PCH_RXP<11>!U5D1!DP13!@baseboard_fab2_lib.baseboard_fab2(sch_1):page30_i84@chpset_lib.skx_ext_b(chips)!SKX_EXT_B_BGA1-IC,TBD!!!F92!PE1_RX_DP(11)!!!!
S!P3E_CPU0_PE1_PCH_RXP<12>!U5D1!DU12!@baseboard_fab2_lib.baseboard_fab2(sch_1):page30_i84@chpset_lib.skx_ext_b(chips)!SKX_EXT_B_BGA1-IC,TBD!!!F92!PE1_RX_DP(12)!!!!
S!P3E_CPU0_PE1_PCH_RXP<13>!U5D1!DY13!@baseboard_fab2_lib.baseboard_fab2(sch_1):page30_i84@chpset_lib.skx_ext_b(chips)!SKX_EXT_B_BGA1-IC,TBD!!!F92!PE1_RX_DP(13)!!!!
S!P3E_CPU0_PE1_PCH_RXP<14>!U5D1!DV15!@baseboard_fab2_lib.baseboard_fab2(sch_1):page30_i84@chpset_lib.skx_ext_b(chips)!SKX_EXT_B_BGA1-IC,TBD!!!F92!PE1_RX_DP(14)!!!!
S!P3E_CPU0_PE1_PCH_RXP<15>!U5D1!DT15!@baseboard_fab2_lib.baseboard_fab2(sch_1):page30_i84@chpset_lib.skx_ext_b(chips)!SKX_EXT_B_BGA1-IC,TBD!!!F92!PE1_RX_DP(15)!!!!
S!P3E_CPU0_PE1_SS_RXP<1>!U5D1!CY7!@baseboard_fab2_lib.baseboard_fab2(sch_1):page30_i84@chpset_lib.skx_ext_b(chips)!SKX_EXT_B_BGA1-IC,TBD!!!F92!PE1_RX_DP(1)!!!!
S!P3E_CPU0_PE1_SS_RXP<2>!U5D1!DB9!@baseboard_fab2_lib.baseboard_fab2(sch_1):page30_i84@chpset_lib.skx_ext_b(chips)!SKX_EXT_B_BGA1-IC,TBD!!!F92!PE1_RX_DP(2)!!!!
S!P3E_CPU0_PE1_SS_RXP<3>!U5D1!DA10!@baseboard_fab2_lib.baseboard_fab2(sch_1):page30_i84@chpset_lib.skx_ext_b(chips)!SKX_EXT_B_BGA1-IC,TBD!!!F92!PE1_RX_DP(3)!!!!
S!P3E_CPU0_PE1_SS_RXP<4>!U5D1!DD9!@baseboard_fab2_lib.baseboard_fab2(sch_1):page30_i84@chpset_lib.skx_ext_b(chips)!SKX_EXT_B_BGA1-IC,TBD!!!F92!PE1_RX_DP(4)!!!!
S!P3E_CPU0_PE1_SS_RXP<5>!U5D1!DF9!@baseboard_fab2_lib.baseboard_fab2(sch_1):page30_i84@chpset_lib.skx_ext_b(chips)!SKX_EXT_B_BGA1-IC,TBD!!!F92!PE1_RX_DP(5)!!!!
S!P3E_CPU0_PE1_SS_RXP<6>!U5D1!DJ8!@baseboard_fab2_lib.baseboard_fab2(sch_1):page30_i84@chpset_lib.skx_ext_b(chips)!SKX_EXT_B_BGA1-IC,TBD!!!F92!PE1_RX_DP(6)!!!!
S!P3E_CPU0_PE1_SS_RXP<7>!U5D1!DL10!@baseboard_fab2_lib.baseboard_fab2(sch_1):page30_i84@chpset_lib.skx_ext_b(chips)!SKX_EXT_B_BGA1-IC,TBD!!!F92!PE1_RX_DP(7)!!!!
S!P3E_CPU0_PE1_PCH_RXP<8>!U5D1!DK11!@baseboard_fab2_lib.baseboard_fab2(sch_1):page30_i84@chpset_lib.skx_ext_b(chips)!SKX_EXT_B_BGA1-IC,TBD!!!F92!PE1_RX_DP(8)!!!!
S!P3E_CPU0_PE1_PCH_RXP<9>!U5D1!DN10!@baseboard_fab2_lib.baseboard_fab2(sch_1):page30_i84@chpset_lib.skx_ext_b(chips)!SKX_EXT_B_BGA1-IC,TBD!!!F92!PE1_RX_DP(9)!!!!
S!P3E_CPU0_PE1_SS_TXN<0>!U5D1!DA2!@baseboard_fab2_lib.baseboard_fab2(sch_1):page30_i84@chpset_lib.skx_ext_b(chips)!SKX_EXT_B_BGA1-IC,TBD!!!F92!PE1_TX_DN(0)!!!!
S!P3E_CPU0_PE1_PCH_TXN<10>!U5D1!DW4!@baseboard_fab2_lib.baseboard_fab2(sch_1):page30_i84@chpset_lib.skx_ext_b(chips)!SKX_EXT_B_BGA1-IC,TBD!!!F92!PE1_TX_DN(10)!!!!
S!P3E_CPU0_PE1_PCH_TXN<11>!U5D1!DU6!@baseboard_fab2_lib.baseboard_fab2(sch_1):page30_i84@chpset_lib.skx_ext_b(chips)!SKX_EXT_B_BGA1-IC,TBD!!!F92!PE1_TX_DN(11)!!!!
S!P3E_CPU0_PE1_PCH_TXN<12>!U5D1!DV7!@baseboard_fab2_lib.baseboard_fab2(sch_1):page30_i84@chpset_lib.skx_ext_b(chips)!SKX_EXT_B_BGA1-IC,TBD!!!F92!PE1_TX_DN(12)!!!!
S!P3E_CPU0_PE1_PCH_TXN<13>!U5D1!DY7!@baseboard_fab2_lib.baseboard_fab2(sch_1):page30_i84@chpset_lib.skx_ext_b(chips)!SKX_EXT_B_BGA1-IC,TBD!!!F92!PE1_TX_DN(13)!!!!
S!P3E_CPU0_PE1_PCH_TXN<14>!U5D1!EA8!@baseboard_fab2_lib.baseboard_fab2(sch_1):page30_i84@chpset_lib.skx_ext_b(chips)!SKX_EXT_B_BGA1-IC,TBD!!!F92!PE1_TX_DN(14)!!!!
S!P3E_CPU0_PE1_PCH_TXN<15>!U5D1!ED9!@baseboard_fab2_lib.baseboard_fab2(sch_1):page30_i84@chpset_lib.skx_ext_b(chips)!SKX_EXT_B_BGA1-IC,TBD!!!F92!PE1_TX_DN(15)!!!!
S!P3E_CPU0_PE1_SS_TXN<1>!U5D1!DC2!@baseboard_fab2_lib.baseboard_fab2(sch_1):page30_i84@chpset_lib.skx_ext_b(chips)!SKX_EXT_B_BGA1-IC,TBD!!!F92!PE1_TX_DN(1)!!!!
S!P3E_CPU0_PE1_SS_TXN<2>!U5D1!DE2!@baseboard_fab2_lib.baseboard_fab2(sch_1):page30_i84@chpset_lib.skx_ext_b(chips)!SKX_EXT_B_BGA1-IC,TBD!!!F92!PE1_TX_DN(2)!!!!
S!P3E_CPU0_PE1_SS_TXN<3>!U5D1!DE4!@baseboard_fab2_lib.baseboard_fab2(sch_1):page30_i84@chpset_lib.skx_ext_b(chips)!SKX_EXT_B_BGA1-IC,TBD!!!F92!PE1_TX_DN(3)!!!!
S!P3E_CPU0_PE1_SS_TXN<4>!U5D1!DG4!@baseboard_fab2_lib.baseboard_fab2(sch_1):page30_i84@chpset_lib.skx_ext_b(chips)!SKX_EXT_B_BGA1-IC,TBD!!!F92!PE1_TX_DN(4)!!!!
S!P3E_CPU0_PE1_SS_TXN<5>!U5D1!DK3!@baseboard_fab2_lib.baseboard_fab2(sch_1):page30_i84@chpset_lib.skx_ext_b(chips)!SKX_EXT_B_BGA1-IC,TBD!!!F92!PE1_TX_DN(5)!!!!
S!P3E_CPU0_PE1_SS_TXN<6>!U5D1!DM3!@baseboard_fab2_lib.baseboard_fab2(sch_1):page30_i84@chpset_lib.skx_ext_b(chips)!SKX_EXT_B_BGA1-IC,TBD!!!F92!PE1_TX_DN(6)!!!!
S!P3E_CPU0_PE1_SS_TXN<7>!U5D1!DN4!@baseboard_fab2_lib.baseboard_fab2(sch_1):page30_i84@chpset_lib.skx_ext_b(chips)!SKX_EXT_B_BGA1-IC,TBD!!!F92!PE1_TX_DN(7)!!!!
S!P3E_CPU0_PE1_PCH_TXN<8>!U5D1!DT5!@baseboard_fab2_lib.baseboard_fab2(sch_1):page30_i84@chpset_lib.skx_ext_b(chips)!SKX_EXT_B_BGA1-IC,TBD!!!F92!PE1_TX_DN(8)!!!!
S!P3E_CPU0_PE1_PCH_TXN<9>!U5D1!DV3!@baseboard_fab2_lib.baseboard_fab2(sch_1):page30_i84@chpset_lib.skx_ext_b(chips)!SKX_EXT_B_BGA1-IC,TBD!!!F92!PE1_TX_DN(9)!!!!
S!P3E_CPU0_PE1_SS_TXP<0>!U5D1!CW2!@baseboard_fab2_lib.baseboard_fab2(sch_1):page30_i84@chpset_lib.skx_ext_b(chips)!SKX_EXT_B_BGA1-IC,TBD!!!F92!PE1_TX_DP(0)!!!!
S!P3E_CPU0_PE1_PCH_TXP<10>!U5D1!DU4!@baseboard_fab2_lib.baseboard_fab2(sch_1):page30_i84@chpset_lib.skx_ext_b(chips)!SKX_EXT_B_BGA1-IC,TBD!!!F92!PE1_TX_DP(10)!!!!
S!P3E_CPU0_PE1_PCH_TXP<11>!U5D1!DV5!@baseboard_fab2_lib.baseboard_fab2(sch_1):page30_i84@chpset_lib.skx_ext_b(chips)!SKX_EXT_B_BGA1-IC,TBD!!!F92!PE1_TX_DP(11)!!!!
S!P3E_CPU0_PE1_PCH_TXP<12>!U5D1!DT7!@baseboard_fab2_lib.baseboard_fab2(sch_1):page30_i84@chpset_lib.skx_ext_b(chips)!SKX_EXT_B_BGA1-IC,TBD!!!F92!PE1_TX_DP(12)!!!!
S!P3E_CPU0_PE1_PCH_TXP<13>!U5D1!DW6!@baseboard_fab2_lib.baseboard_fab2(sch_1):page30_i84@chpset_lib.skx_ext_b(chips)!SKX_EXT_B_BGA1-IC,TBD!!!F92!PE1_TX_DP(13)!!!!
S!P3E_CPU0_PE1_PCH_TXP<14>!U5D1!EB7!@baseboard_fab2_lib.baseboard_fab2(sch_1):page30_i84@chpset_lib.skx_ext_b(chips)!SKX_EXT_B_BGA1-IC,TBD!!!F92!PE1_TX_DP(14)!!!!
S!P3E_CPU0_PE1_PCH_TXP<15>!U5D1!EC8!@baseboard_fab2_lib.baseboard_fab2(sch_1):page30_i84@chpset_lib.skx_ext_b(chips)!SKX_EXT_B_BGA1-IC,TBD!!!F92!PE1_TX_DP(15)!!!!
S!P3E_CPU0_PE1_SS_TXP<1>!U5D1!DB1!@baseboard_fab2_lib.baseboard_fab2(sch_1):page30_i84@chpset_lib.skx_ext_b(chips)!SKX_EXT_B_BGA1-IC,TBD!!!F92!PE1_TX_DP(1)!!!!
S!P3E_CPU0_PE1_SS_TXP<2>!U5D1!DD3!@baseboard_fab2_lib.baseboard_fab2(sch_1):page30_i84@chpset_lib.skx_ext_b(chips)!SKX_EXT_B_BGA1-IC,TBD!!!F92!PE1_TX_DP(2)!!!!
S!P3E_CPU0_PE1_SS_TXP<3>!U5D1!DC4!@baseboard_fab2_lib.baseboard_fab2(sch_1):page30_i84@chpset_lib.skx_ext_b(chips)!SKX_EXT_B_BGA1-IC,TBD!!!F92!PE1_TX_DP(3)!!!!
S!P3E_CPU0_PE1_SS_TXP<4>!U5D1!DF3!@baseboard_fab2_lib.baseboard_fab2(sch_1):page30_i84@chpset_lib.skx_ext_b(chips)!SKX_EXT_B_BGA1-IC,TBD!!!F92!PE1_TX_DP(4)!!!!
S!P3E_CPU0_PE1_SS_TXP<5>!U5D1!DH3!@baseboard_fab2_lib.baseboard_fab2(sch_1):page30_i84@chpset_lib.skx_ext_b(chips)!SKX_EXT_B_BGA1-IC,TBD!!!F92!PE1_TX_DP(5)!!!!
S!P3E_CPU0_PE1_SS_TXP<6>!U5D1!DL2!@baseboard_fab2_lib.baseboard_fab2(sch_1):page30_i84@chpset_lib.skx_ext_b(chips)!SKX_EXT_B_BGA1-IC,TBD!!!F92!PE1_TX_DP(6)!!!!
S!P3E_CPU0_PE1_SS_TXP<7>!U5D1!DP3!@baseboard_fab2_lib.baseboard_fab2(sch_1):page30_i84@chpset_lib.skx_ext_b(chips)!SKX_EXT_B_BGA1-IC,TBD!!!F92!PE1_TX_DP(7)!!!!
S!P3E_CPU0_PE1_PCH_TXP<8>!U5D1!DR4!@baseboard_fab2_lib.baseboard_fab2(sch_1):page30_i84@chpset_lib.skx_ext_b(chips)!SKX_EXT_B_BGA1-IC,TBD!!!F92!PE1_TX_DP(8)!!!!
S!P3E_CPU0_PE1_PCH_TXP<9>!U5D1!DU2!@baseboard_fab2_lib.baseboard_fab2(sch_1):page30_i84@chpset_lib.skx_ext_b(chips)!SKX_EXT_B_BGA1-IC,TBD!!!F92!PE1_TX_DP(9)!!!!
S!P3E_CPU0_PE2_SS_RXN<0>!U5D1!CT9!@baseboard_fab2_lib.baseboard_fab2(sch_1):page31_i106@chpset_lib.skx_ext_b(chips)!SKX_EXT_B_BGA1-IC,TBD!!!F91!PE2_RX_DN(0)!!!!
S!P3E_CPU0_PE2_SS_RXN<10>!U5D1!BV7!@baseboard_fab2_lib.baseboard_fab2(sch_1):page31_i106@chpset_lib.skx_ext_b(chips)!SKX_EXT_B_BGA1-IC,TBD!!!F91!PE2_RX_DN(10)!!!!
S!P3E_CPU0_PE2_SS_RXN<11>!U5D1!BT7!@baseboard_fab2_lib.baseboard_fab2(sch_1):page31_i106@chpset_lib.skx_ext_b(chips)!SKX_EXT_B_BGA1-IC,TBD!!!F91!PE2_RX_DN(11)!!!!
S!P3E_CPU0_PE2_SS_RXN<12>!U5D1!BR8!@baseboard_fab2_lib.baseboard_fab2(sch_1):page31_i106@chpset_lib.skx_ext_b(chips)!SKX_EXT_B_BGA1-IC,TBD!!!F91!PE2_RX_DN(12)!!!!
S!P3E_CPU0_PE2_SS_RXN<13>!U5D1!BN8!@baseboard_fab2_lib.baseboard_fab2(sch_1):page31_i106@chpset_lib.skx_ext_b(chips)!SKX_EXT_B_BGA1-IC,TBD!!!F91!PE2_RX_DN(13)!!!!
S!P3E_CPU0_PE2_SS_RXN<14>!U5D1!BL8!@baseboard_fab2_lib.baseboard_fab2(sch_1):page31_i106@chpset_lib.skx_ext_b(chips)!SKX_EXT_B_BGA1-IC,TBD!!!F91!PE2_RX_DN(14)!!!!
S!P3E_CPU0_PE2_SS_RXN<15>!U5D1!BK9!@baseboard_fab2_lib.baseboard_fab2(sch_1):page31_i106@chpset_lib.skx_ext_b(chips)!SKX_EXT_B_BGA1-IC,TBD!!!F91!PE2_RX_DN(15)!!!!
S!P3E_CPU0_PE2_SS_RXN<1>!U5D1!CP9!@baseboard_fab2_lib.baseboard_fab2(sch_1):page31_i106@chpset_lib.skx_ext_b(chips)!SKX_EXT_B_BGA1-IC,TBD!!!F91!PE2_RX_DN(1)!!!!
S!P3E_CPU0_PE2_SS_RXN<2>!U5D1!CP7!@baseboard_fab2_lib.baseboard_fab2(sch_1):page31_i106@chpset_lib.skx_ext_b(chips)!SKX_EXT_B_BGA1-IC,TBD!!!F91!PE2_RX_DN(2)!!!!
S!P3E_CPU0_PE2_SS_RXN<3>!U5D1!CM7!@baseboard_fab2_lib.baseboard_fab2(sch_1):page31_i106@chpset_lib.skx_ext_b(chips)!SKX_EXT_B_BGA1-IC,TBD!!!F91!PE2_RX_DN(3)!!!!
S!P3E_CPU0_PE2_SS_RXN<4>!U5D1!CK7!@baseboard_fab2_lib.baseboard_fab2(sch_1):page31_i106@chpset_lib.skx_ext_b(chips)!SKX_EXT_B_BGA1-IC,TBD!!!F91!PE2_RX_DN(4)!!!!
S!P3E_CPU0_PE2_SS_RXN<5>!U5D1!CG8!@baseboard_fab2_lib.baseboard_fab2(sch_1):page31_i106@chpset_lib.skx_ext_b(chips)!SKX_EXT_B_BGA1-IC,TBD!!!F91!PE2_RX_DN(5)!!!!
S!P3E_CPU0_PE2_SS_RXN<6>!U5D1!CE6!@baseboard_fab2_lib.baseboard_fab2(sch_1):page31_i106@chpset_lib.skx_ext_b(chips)!SKX_EXT_B_BGA1-IC,TBD!!!F91!PE2_RX_DN(6)!!!!
S!P3E_CPU0_PE2_SS_RXN<7>!U5D1!CE8!@baseboard_fab2_lib.baseboard_fab2(sch_1):page31_i106@chpset_lib.skx_ext_b(chips)!SKX_EXT_B_BGA1-IC,TBD!!!F91!PE2_RX_DN(7)!!!!
S!P3E_CPU0_PE2_SS_RXN<8>!U5D1!BY9!@baseboard_fab2_lib.baseboard_fab2(sch_1):page31_i106@chpset_lib.skx_ext_b(chips)!SKX_EXT_B_BGA1-IC,TBD!!!F91!PE2_RX_DN(8)!!!!
S!P3E_CPU0_PE2_SS_RXN<9>!U5D1!BY7!@baseboard_fab2_lib.baseboard_fab2(sch_1):page31_i106@chpset_lib.skx_ext_b(chips)!SKX_EXT_B_BGA1-IC,TBD!!!F91!PE2_RX_DN(9)!!!!
S!P3E_CPU0_PE2_SS_RXP<0>!U5D1!CR8!@baseboard_fab2_lib.baseboard_fab2(sch_1):page31_i106@chpset_lib.skx_ext_b(chips)!SKX_EXT_B_BGA1-IC,TBD!!!F91!PE2_RX_DP(0)!!!!
S!P3E_CPU0_PE2_SS_RXP<10>!U5D1!BU6!@baseboard_fab2_lib.baseboard_fab2(sch_1):page31_i106@chpset_lib.skx_ext_b(chips)!SKX_EXT_B_BGA1-IC,TBD!!!F91!PE2_RX_DP(10)!!!!
S!P3E_CPU0_PE2_SS_RXP<11>!U5D1!BP7!@baseboard_fab2_lib.baseboard_fab2(sch_1):page31_i106@chpset_lib.skx_ext_b(chips)!SKX_EXT_B_BGA1-IC,TBD!!!F91!PE2_RX_DP(11)!!!!
S!P3E_CPU0_PE2_SS_RXP<12>!U5D1!BP9!@baseboard_fab2_lib.baseboard_fab2(sch_1):page31_i106@chpset_lib.skx_ext_b(chips)!SKX_EXT_B_BGA1-IC,TBD!!!F91!PE2_RX_DP(12)!!!!
S!P3E_CPU0_PE2_SS_RXP<13>!U5D1!BM7!@baseboard_fab2_lib.baseboard_fab2(sch_1):page31_i106@chpset_lib.skx_ext_b(chips)!SKX_EXT_B_BGA1-IC,TBD!!!F91!PE2_RX_DP(13)!!!!
S!P3E_CPU0_PE2_SS_RXP<14>!U5D1!BJ8!@baseboard_fab2_lib.baseboard_fab2(sch_1):page31_i106@chpset_lib.skx_ext_b(chips)!SKX_EXT_B_BGA1-IC,TBD!!!F91!PE2_RX_DP(14)!!!!
S!P3E_CPU0_PE2_SS_RXP<15>!U5D1!BJ10!@baseboard_fab2_lib.baseboard_fab2(sch_1):page31_i106@chpset_lib.skx_ext_b(chips)!SKX_EXT_B_BGA1-IC,TBD!!!F91!PE2_RX_DP(15)!!!!
S!P3E_CPU0_PE2_SS_RXP<1>!U5D1!CM9!@baseboard_fab2_lib.baseboard_fab2(sch_1):page31_i106@chpset_lib.skx_ext_b(chips)!SKX_EXT_B_BGA1-IC,TBD!!!F91!PE2_RX_DP(1)!!!!
S!P3E_CPU0_PE2_SS_RXP<2>!U5D1!CN8!@baseboard_fab2_lib.baseboard_fab2(sch_1):page31_i106@chpset_lib.skx_ext_b(chips)!SKX_EXT_B_BGA1-IC,TBD!!!F91!PE2_RX_DP(2)!!!!
S!P3E_CPU0_PE2_SS_RXP<3>!U5D1!CL6!@baseboard_fab2_lib.baseboard_fab2(sch_1):page31_i106@chpset_lib.skx_ext_b(chips)!SKX_EXT_B_BGA1-IC,TBD!!!F91!PE2_RX_DP(3)!!!!
S!P3E_CPU0_PE2_SS_RXP<4>!U5D1!CH7!@baseboard_fab2_lib.baseboard_fab2(sch_1):page31_i106@chpset_lib.skx_ext_b(chips)!SKX_EXT_B_BGA1-IC,TBD!!!F91!PE2_RX_DP(4)!!!!
S!P3E_CPU0_PE2_SS_RXP<5>!U5D1!CF7!@baseboard_fab2_lib.baseboard_fab2(sch_1):page31_i106@chpset_lib.skx_ext_b(chips)!SKX_EXT_B_BGA1-IC,TBD!!!F91!PE2_RX_DP(5)!!!!
S!P3E_CPU0_PE2_SS_RXP<6>!U5D1!CD7!@baseboard_fab2_lib.baseboard_fab2(sch_1):page31_i106@chpset_lib.skx_ext_b(chips)!SKX_EXT_B_BGA1-IC,TBD!!!F91!PE2_RX_DP(6)!!!!
S!P3E_CPU0_PE2_SS_RXP<7>!U5D1!CC8!@baseboard_fab2_lib.baseboard_fab2(sch_1):page31_i106@chpset_lib.skx_ext_b(chips)!SKX_EXT_B_BGA1-IC,TBD!!!F91!PE2_RX_DP(7)!!!!
S!P3E_CPU0_PE2_SS_RXP<8>!U5D1!BV9!@baseboard_fab2_lib.baseboard_fab2(sch_1):page31_i106@chpset_lib.skx_ext_b(chips)!SKX_EXT_B_BGA1-IC,TBD!!!F91!PE2_RX_DP(8)!!!!
S!P3E_CPU0_PE2_SS_RXP<9>!U5D1!BW8!@baseboard_fab2_lib.baseboard_fab2(sch_1):page31_i106@chpset_lib.skx_ext_b(chips)!SKX_EXT_B_BGA1-IC,TBD!!!F91!PE2_RX_DP(9)!!!!
S!P3E_CPU0_PE2_SS_TXN<0>!U5D1!CY3!@baseboard_fab2_lib.baseboard_fab2(sch_1):page31_i106@chpset_lib.skx_ext_b(chips)!SKX_EXT_B_BGA1-IC,TBD!!!F91!PE2_TX_DN(0)!!!!
S!P3E_CPU0_PE2_SS_TXN<10>!U5D1!CA4!@baseboard_fab2_lib.baseboard_fab2(sch_1):page31_i106@chpset_lib.skx_ext_b(chips)!SKX_EXT_B_BGA1-IC,TBD!!!F91!PE2_TX_DN(10)!!!!
S!P3E_CPU0_PE2_SS_TXN<11>!U5D1!BW4!@baseboard_fab2_lib.baseboard_fab2(sch_1):page31_i106@chpset_lib.skx_ext_b(chips)!SKX_EXT_B_BGA1-IC,TBD!!!F91!PE2_TX_DN(11)!!!!
S!P3E_CPU0_PE2_SS_TXN<12>!U5D1!BU4!@baseboard_fab2_lib.baseboard_fab2(sch_1):page31_i106@chpset_lib.skx_ext_b(chips)!SKX_EXT_B_BGA1-IC,TBD!!!F91!PE2_TX_DN(12)!!!!
S!P3E_CPU0_PE2_SS_TXN<13>!U5D1!BP5!@baseboard_fab2_lib.baseboard_fab2(sch_1):page31_i106@chpset_lib.skx_ext_b(chips)!SKX_EXT_B_BGA1-IC,TBD!!!F91!PE2_TX_DN(13)!!!!
S!P3E_CPU0_PE2_SS_TXN<14>!U5D1!BL4!@baseboard_fab2_lib.baseboard_fab2(sch_1):page31_i106@chpset_lib.skx_ext_b(chips)!SKX_EXT_B_BGA1-IC,TBD!!!F91!PE2_TX_DN(14)!!!!
S!P3E_CPU0_PE2_SS_TXN<15>!U5D1!BM5!@baseboard_fab2_lib.baseboard_fab2(sch_1):page31_i106@chpset_lib.skx_ext_b(chips)!SKX_EXT_B_BGA1-IC,TBD!!!F91!PE2_TX_DN(15)!!!!
S!P3E_CPU0_PE2_SS_TXN<1>!U5D1!CV3!@baseboard_fab2_lib.baseboard_fab2(sch_1):page31_i106@chpset_lib.skx_ext_b(chips)!SKX_EXT_B_BGA1-IC,TBD!!!F91!PE2_TX_DN(1)!!!!
S!P3E_CPU0_PE2_SS_TXN<2>!U5D1!CT1!@baseboard_fab2_lib.baseboard_fab2(sch_1):page31_i106@chpset_lib.skx_ext_b(chips)!SKX_EXT_B_BGA1-IC,TBD!!!F91!PE2_TX_DN(2)!!!!
S!P3E_CPU0_PE2_SS_TXN<3>!U5D1!CT3!@baseboard_fab2_lib.baseboard_fab2(sch_1):page31_i106@chpset_lib.skx_ext_b(chips)!SKX_EXT_B_BGA1-IC,TBD!!!F91!PE2_TX_DN(3)!!!!
S!P3E_CPU0_PE2_SS_TXN<4>!U5D1!CM1!@baseboard_fab2_lib.baseboard_fab2(sch_1):page31_i106@chpset_lib.skx_ext_b(chips)!SKX_EXT_B_BGA1-IC,TBD!!!F91!PE2_TX_DN(4)!!!!
S!P3E_CPU0_PE2_SS_TXN<5>!U5D1!CL2!@baseboard_fab2_lib.baseboard_fab2(sch_1):page31_i106@chpset_lib.skx_ext_b(chips)!SKX_EXT_B_BGA1-IC,TBD!!!F91!PE2_TX_DN(5)!!!!
S!P3E_CPU0_PE2_SS_TXN<6>!U5D1!CG2!@baseboard_fab2_lib.baseboard_fab2(sch_1):page31_i106@chpset_lib.skx_ext_b(chips)!SKX_EXT_B_BGA1-IC,TBD!!!F91!PE2_TX_DN(6)!!!!
S!P3E_CPU0_PE2_SS_TXN<7>!U5D1!CF3!@baseboard_fab2_lib.baseboard_fab2(sch_1):page31_i106@chpset_lib.skx_ext_b(chips)!SKX_EXT_B_BGA1-IC,TBD!!!F91!PE2_TX_DN(7)!!!!
S!P3E_CPU0_PE2_SS_TXN<8>!U5D1!CC2!@baseboard_fab2_lib.baseboard_fab2(sch_1):page31_i106@chpset_lib.skx_ext_b(chips)!SKX_EXT_B_BGA1-IC,TBD!!!F91!PE2_TX_DN(8)!!!!
S!P3E_CPU0_PE2_SS_TXN<9>!U5D1!CB3!@baseboard_fab2_lib.baseboard_fab2(sch_1):page31_i106@chpset_lib.skx_ext_b(chips)!SKX_EXT_B_BGA1-IC,TBD!!!F91!PE2_TX_DN(9)!!!!
S!P3E_CPU0_PE2_SS_TXP<0>!U5D1!CW4!@baseboard_fab2_lib.baseboard_fab2(sch_1):page31_i106@chpset_lib.skx_ext_b(chips)!SKX_EXT_B_BGA1-IC,TBD!!!F91!PE2_TX_DP(0)!!!!
S!P3E_CPU0_PE2_SS_TXP<10>!U5D1!BY5!@baseboard_fab2_lib.baseboard_fab2(sch_1):page31_i106@chpset_lib.skx_ext_b(chips)!SKX_EXT_B_BGA1-IC,TBD!!!F91!PE2_TX_DP(10)!!!!
S!P3E_CPU0_PE2_SS_TXP<11>!U5D1!BV3!@baseboard_fab2_lib.baseboard_fab2(sch_1):page31_i106@chpset_lib.skx_ext_b(chips)!SKX_EXT_B_BGA1-IC,TBD!!!F91!PE2_TX_DP(11)!!!!
S!P3E_CPU0_PE2_SS_TXP<12>!U5D1!BR4!@baseboard_fab2_lib.baseboard_fab2(sch_1):page31_i106@chpset_lib.skx_ext_b(chips)!SKX_EXT_B_BGA1-IC,TBD!!!F91!PE2_TX_DP(12)!!!!
S!P3E_CPU0_PE2_SS_TXP<13>!U5D1!BN4!@baseboard_fab2_lib.baseboard_fab2(sch_1):page31_i106@chpset_lib.skx_ext_b(chips)!SKX_EXT_B_BGA1-IC,TBD!!!F91!PE2_TX_DP(13)!!!!
S!P3E_CPU0_PE2_SS_TXP<14>!U5D1!BM3!@baseboard_fab2_lib.baseboard_fab2(sch_1):page31_i106@chpset_lib.skx_ext_b(chips)!SKX_EXT_B_BGA1-IC,TBD!!!F91!PE2_TX_DP(14)!!!!
S!P3E_CPU0_PE2_SS_TXP<15>!U5D1!BK5!@baseboard_fab2_lib.baseboard_fab2(sch_1):page31_i106@chpset_lib.skx_ext_b(chips)!SKX_EXT_B_BGA1-IC,TBD!!!F91!PE2_TX_DP(15)!!!!
S!P3E_CPU0_PE2_SS_TXP<1>!U5D1!CU2!@baseboard_fab2_lib.baseboard_fab2(sch_1):page31_i106@chpset_lib.skx_ext_b(chips)!SKX_EXT_B_BGA1-IC,TBD!!!F91!PE2_TX_DP(1)!!!!
S!P3E_CPU0_PE2_SS_TXP<2>!U5D1!CR2!@baseboard_fab2_lib.baseboard_fab2(sch_1):page31_i106@chpset_lib.skx_ext_b(chips)!SKX_EXT_B_BGA1-IC,TBD!!!F91!PE2_TX_DP(2)!!!!
S!P3E_CPU0_PE2_SS_TXP<3>!U5D1!CP3!@baseboard_fab2_lib.baseboard_fab2(sch_1):page31_i106@chpset_lib.skx_ext_b(chips)!SKX_EXT_B_BGA1-IC,TBD!!!F91!PE2_TX_DP(3)!!!!
S!P3E_CPU0_PE2_SS_TXP<4>!U5D1!CK1!@baseboard_fab2_lib.baseboard_fab2(sch_1):page31_i106@chpset_lib.skx_ext_b(chips)!SKX_EXT_B_BGA1-IC,TBD!!!F91!PE2_TX_DP(4)!!!!
S!P3E_CPU0_PE2_SS_TXP<5>!U5D1!CK3!@baseboard_fab2_lib.baseboard_fab2(sch_1):page31_i106@chpset_lib.skx_ext_b(chips)!SKX_EXT_B_BGA1-IC,TBD!!!F91!PE2_TX_DP(5)!!!!
S!P3E_CPU0_PE2_SS_TXP<6>!U5D1!CE2!@baseboard_fab2_lib.baseboard_fab2(sch_1):page31_i106@chpset_lib.skx_ext_b(chips)!SKX_EXT_B_BGA1-IC,TBD!!!F91!PE2_TX_DP(6)!!!!
S!P3E_CPU0_PE2_SS_TXP<7>!U5D1!CE4!@baseboard_fab2_lib.baseboard_fab2(sch_1):page31_i106@chpset_lib.skx_ext_b(chips)!SKX_EXT_B_BGA1-IC,TBD!!!F91!PE2_TX_DP(7)!!!!
S!P3E_CPU0_PE2_SS_TXP<8>!U5D1!CD3!@baseboard_fab2_lib.baseboard_fab2(sch_1):page31_i106@chpset_lib.skx_ext_b(chips)!SKX_EXT_B_BGA1-IC,TBD!!!F91!PE2_TX_DP(8)!!!!
S!P3E_CPU0_PE2_SS_TXP<9>!U5D1!BY3!@baseboard_fab2_lib.baseboard_fab2(sch_1):page31_i106@chpset_lib.skx_ext_b(chips)!SKX_EXT_B_BGA1-IC,TBD!!!F91!PE2_TX_DP(9)!!!!
S!P3E_CPU0_PE3_OCP_RXN<0>!U5D1!EA18!@baseboard_fab2_lib.baseboard_fab2(sch_1):page32_i89@chpset_lib.skx_ext_b(chips)!SKX_EXT_B_BGA1-IC,TBD!!!F90!PE3_RX_DN(0)!!!!
S!P3E_CPU0_PE3_OCP_RXN<10>!U5D1!DG12!@baseboard_fab2_lib.baseboard_fab2(sch_1):page32_i89@chpset_lib.skx_ext_b(chips)!SKX_EXT_B_BGA1-IC,TBD!!!F90!PE3_RX_DN(10)!!!!
S!P3E_CPU0_PE3_OCP_RXN<11>!U5D1!DG10!@baseboard_fab2_lib.baseboard_fab2(sch_1):page32_i89@chpset_lib.skx_ext_b(chips)!SKX_EXT_B_BGA1-IC,TBD!!!F90!PE3_RX_DN(11)!!!!
S!P3E_CPU0_PE3_OCP_RXN<12>!U5D1!DD13!@baseboard_fab2_lib.baseboard_fab2(sch_1):page32_i89@chpset_lib.skx_ext_b(chips)!SKX_EXT_B_BGA1-IC,TBD!!!F90!PE3_RX_DN(12)!!!!
S!P3E_CPU0_PE3_OCP_RXN<13>!U5D1!DB11!@baseboard_fab2_lib.baseboard_fab2(sch_1):page32_i89@chpset_lib.skx_ext_b(chips)!SKX_EXT_B_BGA1-IC,TBD!!!F90!PE3_RX_DN(13)!!!!
S!P3E_CPU0_PE3_OCP_RXN<14>!U5D1!CY11!@baseboard_fab2_lib.baseboard_fab2(sch_1):page32_i89@chpset_lib.skx_ext_b(chips)!SKX_EXT_B_BGA1-IC,TBD!!!F90!PE3_RX_DN(14)!!!!
S!P3E_CPU0_PE3_OCP_RXN<15>!U5D1!CV9!@baseboard_fab2_lib.baseboard_fab2(sch_1):page32_i89@chpset_lib.skx_ext_b(chips)!SKX_EXT_B_BGA1-IC,TBD!!!F90!PE3_RX_DN(15)!!!!
S!P3E_CPU0_PE3_OCP_RXN<1>!U5D1!DW18!@baseboard_fab2_lib.baseboard_fab2(sch_1):page32_i89@chpset_lib.skx_ext_b(chips)!SKX_EXT_B_BGA1-IC,TBD!!!F90!PE3_RX_DN(1)!!!!
S!P3E_CPU0_PE3_OCP_RXN<2>!U5D1!DW16!@baseboard_fab2_lib.baseboard_fab2(sch_1):page32_i89@chpset_lib.skx_ext_b(chips)!SKX_EXT_B_BGA1-IC,TBD!!!F90!PE3_RX_DN(2)!!!!
S!P3E_CPU0_PE3_OCP_RXN<3>!U5D1!DT19!@baseboard_fab2_lib.baseboard_fab2(sch_1):page32_i89@chpset_lib.skx_ext_b(chips)!SKX_EXT_B_BGA1-IC,TBD!!!F90!PE3_RX_DN(3)!!!!
S!P3E_CPU0_PE3_OCP_RXN<4>!U5D1!DR16!@baseboard_fab2_lib.baseboard_fab2(sch_1):page32_i89@chpset_lib.skx_ext_b(chips)!SKX_EXT_B_BGA1-IC,TBD!!!F90!PE3_RX_DN(4)!!!!
S!P3E_CPU0_PE3_OCP_RXN<5>!U5D1!DR14!@baseboard_fab2_lib.baseboard_fab2(sch_1):page32_i89@chpset_lib.skx_ext_b(chips)!SKX_EXT_B_BGA1-IC,TBD!!!F90!PE3_RX_DN(5)!!!!
S!P3E_CPU0_PE3_OCP_RXN<6>!U5D1!DN14!@baseboard_fab2_lib.baseboard_fab2(sch_1):page32_i89@chpset_lib.skx_ext_b(chips)!SKX_EXT_B_BGA1-IC,TBD!!!F90!PE3_RX_DN(6)!!!!
S!P3E_CPU0_PE3_OCP_RXN<7>!U5D1!DL14!@baseboard_fab2_lib.baseboard_fab2(sch_1):page32_i89@chpset_lib.skx_ext_b(chips)!SKX_EXT_B_BGA1-IC,TBD!!!F90!PE3_RX_DN(7)!!!!
S!P3E_CPU0_PE3_OCP_RXN<8>!U5D1!DL12!@baseboard_fab2_lib.baseboard_fab2(sch_1):page32_i89@chpset_lib.skx_ext_b(chips)!SKX_EXT_B_BGA1-IC,TBD!!!F90!PE3_RX_DN(8)!!!!
S!P3E_CPU0_PE3_OCP_RXN<9>!U5D1!DJ12!@baseboard_fab2_lib.baseboard_fab2(sch_1):page32_i89@chpset_lib.skx_ext_b(chips)!SKX_EXT_B_BGA1-IC,TBD!!!F90!PE3_RX_DN(9)!!!!
S!P3E_CPU0_PE3_OCP_RXP<0>!U5D1!DY17!@baseboard_fab2_lib.baseboard_fab2(sch_1):page32_i89@chpset_lib.skx_ext_b(chips)!SKX_EXT_B_BGA1-IC,TBD!!!F90!PE3_RX_DP(0)!!!!
S!P3E_CPU0_PE3_OCP_RXP<10>!U5D1!DE12!@baseboard_fab2_lib.baseboard_fab2(sch_1):page32_i89@chpset_lib.skx_ext_b(chips)!SKX_EXT_B_BGA1-IC,TBD!!!F90!PE3_RX_DP(10)!!!!
S!P3E_CPU0_PE3_OCP_RXP<11>!U5D1!DF11!@baseboard_fab2_lib.baseboard_fab2(sch_1):page32_i89@chpset_lib.skx_ext_b(chips)!SKX_EXT_B_BGA1-IC,TBD!!!F90!PE3_RX_DP(11)!!!!
S!P3E_CPU0_PE3_OCP_RXP<12>!U5D1!DC12!@baseboard_fab2_lib.baseboard_fab2(sch_1):page32_i89@chpset_lib.skx_ext_b(chips)!SKX_EXT_B_BGA1-IC,TBD!!!F90!PE3_RX_DP(12)!!!!
S!P3E_CPU0_PE3_OCP_RXP<13>!U5D1!DA12!@baseboard_fab2_lib.baseboard_fab2(sch_1):page32_i89@chpset_lib.skx_ext_b(chips)!SKX_EXT_B_BGA1-IC,TBD!!!F90!PE3_RX_DP(13)!!!!
S!P3E_CPU0_PE3_OCP_RXP<14>!U5D1!CW10!@baseboard_fab2_lib.baseboard_fab2(sch_1):page32_i89@chpset_lib.skx_ext_b(chips)!SKX_EXT_B_BGA1-IC,TBD!!!F90!PE3_RX_DP(14)!!!!
S!P3E_CPU0_PE3_OCP_RXP<15>!U5D1!CU10!@baseboard_fab2_lib.baseboard_fab2(sch_1):page32_i89@chpset_lib.skx_ext_b(chips)!SKX_EXT_B_BGA1-IC,TBD!!!F90!PE3_RX_DP(15)!!!!
S!P3E_CPU0_PE3_OCP_RXP<1>!U5D1!DU18!@baseboard_fab2_lib.baseboard_fab2(sch_1):page32_i89@chpset_lib.skx_ext_b(chips)!SKX_EXT_B_BGA1-IC,TBD!!!F90!PE3_RX_DP(1)!!!!
S!P3E_CPU0_PE3_OCP_RXP<2>!U5D1!DV17!@baseboard_fab2_lib.baseboard_fab2(sch_1):page32_i89@chpset_lib.skx_ext_b(chips)!SKX_EXT_B_BGA1-IC,TBD!!!F90!PE3_RX_DP(2)!!!!
S!P3E_CPU0_PE3_OCP_RXP<3>!U5D1!DR18!@baseboard_fab2_lib.baseboard_fab2(sch_1):page32_i89@chpset_lib.skx_ext_b(chips)!SKX_EXT_B_BGA1-IC,TBD!!!F90!PE3_RX_DP(3)!!!!
S!P3E_CPU0_PE3_OCP_RXP<4>!U5D1!DN16!@baseboard_fab2_lib.baseboard_fab2(sch_1):page32_i89@chpset_lib.skx_ext_b(chips)!SKX_EXT_B_BGA1-IC,TBD!!!F90!PE3_RX_DP(4)!!!!
S!P3E_CPU0_PE3_OCP_RXP<5>!U5D1!DP15!@baseboard_fab2_lib.baseboard_fab2(sch_1):page32_i89@chpset_lib.skx_ext_b(chips)!SKX_EXT_B_BGA1-IC,TBD!!!F90!PE3_RX_DP(5)!!!!
S!P3E_CPU0_PE3_OCP_RXP<6>!U5D1!DM13!@baseboard_fab2_lib.baseboard_fab2(sch_1):page32_i89@chpset_lib.skx_ext_b(chips)!SKX_EXT_B_BGA1-IC,TBD!!!F90!PE3_RX_DP(6)!!!!
S!P3E_CPU0_PE3_OCP_RXP<7>!U5D1!DJ14!@baseboard_fab2_lib.baseboard_fab2(sch_1):page32_i89@chpset_lib.skx_ext_b(chips)!SKX_EXT_B_BGA1-IC,TBD!!!F90!PE3_RX_DP(7)!!!!
S!P3E_CPU0_PE3_OCP_RXP<8>!U5D1!DK13!@baseboard_fab2_lib.baseboard_fab2(sch_1):page32_i89@chpset_lib.skx_ext_b(chips)!SKX_EXT_B_BGA1-IC,TBD!!!F90!PE3_RX_DP(8)!!!!
S!P3E_CPU0_PE3_OCP_RXP<9>!U5D1!DH11!@baseboard_fab2_lib.baseboard_fab2(sch_1):page32_i89@chpset_lib.skx_ext_b(chips)!SKX_EXT_B_BGA1-IC,TBD!!!F90!PE3_RX_DP(9)!!!!
S!P3E_CPU0_PE3_OCP_TXN<0>!U5D1!EE14!@baseboard_fab2_lib.baseboard_fab2(sch_1):page32_i89@chpset_lib.skx_ext_b(chips)!SKX_EXT_B_BGA1-IC,TBD!!!F90!PE3_TX_DN(0)!!!!
S!P3E_CPU0_PE3_OCP_TXN<10>!U5D1!DL6!@baseboard_fab2_lib.baseboard_fab2(sch_1):page32_i89@chpset_lib.skx_ext_b(chips)!SKX_EXT_B_BGA1-IC,TBD!!!F90!PE3_TX_DN(10)!!!!
S!P3E_CPU0_PE3_OCP_TXN<11>!U5D1!DJ4!@baseboard_fab2_lib.baseboard_fab2(sch_1):page32_i89@chpset_lib.skx_ext_b(chips)!SKX_EXT_B_BGA1-IC,TBD!!!F90!PE3_TX_DN(11)!!!!
S!P3E_CPU0_PE3_OCP_TXN<12>!U5D1!DJ6!@baseboard_fab2_lib.baseboard_fab2(sch_1):page32_i89@chpset_lib.skx_ext_b(chips)!SKX_EXT_B_BGA1-IC,TBD!!!F90!PE3_TX_DN(12)!!!!
S!P3E_CPU0_PE3_OCP_TXN<13>!U5D1!DD5!@baseboard_fab2_lib.baseboard_fab2(sch_1):page32_i89@chpset_lib.skx_ext_b(chips)!SKX_EXT_B_BGA1-IC,TBD!!!F90!PE3_TX_DN(13)!!!!
S!P3E_CPU0_PE3_OCP_TXN<14>!U5D1!DB5!@baseboard_fab2_lib.baseboard_fab2(sch_1):page32_i89@chpset_lib.skx_ext_b(chips)!SKX_EXT_B_BGA1-IC,TBD!!!F90!PE3_TX_DN(14)!!!!
S!P3E_CPU0_PE3_OCP_TXN<15>!U5D1!CY5!@baseboard_fab2_lib.baseboard_fab2(sch_1):page32_i89@chpset_lib.skx_ext_b(chips)!SKX_EXT_B_BGA1-IC,TBD!!!F90!PE3_TX_DN(15)!!!!
S!P3E_CPU0_PE3_OCP_TXN<1>!U5D1!EE12!@baseboard_fab2_lib.baseboard_fab2(sch_1):page32_i89@chpset_lib.skx_ext_b(chips)!SKX_EXT_B_BGA1-IC,TBD!!!F90!PE3_TX_DN(1)!!!!
S!P3E_CPU0_PE3_OCP_TXN<2>!U5D1!EC12!@baseboard_fab2_lib.baseboard_fab2(sch_1):page32_i89@chpset_lib.skx_ext_b(chips)!SKX_EXT_B_BGA1-IC,TBD!!!F90!PE3_TX_DN(2)!!!!
S!P3E_CPU0_PE3_OCP_TXN<3>!U5D1!DY11!@baseboard_fab2_lib.baseboard_fab2(sch_1):page32_i89@chpset_lib.skx_ext_b(chips)!SKX_EXT_B_BGA1-IC,TBD!!!F90!PE3_TX_DN(3)!!!!
S!P3E_CPU0_PE3_OCP_TXN<4>!U5D1!EB9!@baseboard_fab2_lib.baseboard_fab2(sch_1):page32_i89@chpset_lib.skx_ext_b(chips)!SKX_EXT_B_BGA1-IC,TBD!!!F90!PE3_TX_DN(4)!!!!
S!P3E_CPU0_PE3_OCP_TXN<5>!U5D1!DW10!@baseboard_fab2_lib.baseboard_fab2(sch_1):page32_i89@chpset_lib.skx_ext_b(chips)!SKX_EXT_B_BGA1-IC,TBD!!!F90!PE3_TX_DN(5)!!!!
S!P3E_CPU0_PE3_OCP_TXN<6>!U5D1!DU8!@baseboard_fab2_lib.baseboard_fab2(sch_1):page32_i89@chpset_lib.skx_ext_b(chips)!SKX_EXT_B_BGA1-IC,TBD!!!F90!PE3_TX_DN(6)!!!!
S!P3E_CPU0_PE3_OCP_TXN<7>!U5D1!DR8!@baseboard_fab2_lib.baseboard_fab2(sch_1):page32_i89@chpset_lib.skx_ext_b(chips)!SKX_EXT_B_BGA1-IC,TBD!!!F90!PE3_TX_DN(7)!!!!
S!P3E_CPU0_PE3_OCP_TXN<8>!U5D1!DM7!@baseboard_fab2_lib.baseboard_fab2(sch_1):page32_i89@chpset_lib.skx_ext_b(chips)!SKX_EXT_B_BGA1-IC,TBD!!!F90!PE3_TX_DN(8)!!!!
S!P3E_CPU0_PE3_OCP_TXN<9>!U5D1!DP5!@baseboard_fab2_lib.baseboard_fab2(sch_1):page32_i89@chpset_lib.skx_ext_b(chips)!SKX_EXT_B_BGA1-IC,TBD!!!F90!PE3_TX_DN(9)!!!!
S!P3E_CPU0_PE3_OCP_TXP<0>!U5D1!EC14!@baseboard_fab2_lib.baseboard_fab2(sch_1):page32_i89@chpset_lib.skx_ext_b(chips)!SKX_EXT_B_BGA1-IC,TBD!!!F90!PE3_TX_DP(0)!!!!
S!P3E_CPU0_PE3_OCP_TXP<10>!U5D1!DK5!@baseboard_fab2_lib.baseboard_fab2(sch_1):page32_i89@chpset_lib.skx_ext_b(chips)!SKX_EXT_B_BGA1-IC,TBD!!!F90!PE3_TX_DP(10)!!!!
S!P3E_CPU0_PE3_OCP_TXP<11>!U5D1!DH5!@baseboard_fab2_lib.baseboard_fab2(sch_1):page32_i89@chpset_lib.skx_ext_b(chips)!SKX_EXT_B_BGA1-IC,TBD!!!F90!PE3_TX_DP(11)!!!!
S!P3E_CPU0_PE3_OCP_TXP<12>!U5D1!DG6!@baseboard_fab2_lib.baseboard_fab2(sch_1):page32_i89@chpset_lib.skx_ext_b(chips)!SKX_EXT_B_BGA1-IC,TBD!!!F90!PE3_TX_DP(12)!!!!
S!P3E_CPU0_PE3_OCP_TXP<13>!U5D1!DC6!@baseboard_fab2_lib.baseboard_fab2(sch_1):page32_i89@chpset_lib.skx_ext_b(chips)!SKX_EXT_B_BGA1-IC,TBD!!!F90!PE3_TX_DP(13)!!!!
S!P3E_CPU0_PE3_OCP_TXP<14>!U5D1!DA4!@baseboard_fab2_lib.baseboard_fab2(sch_1):page32_i89@chpset_lib.skx_ext_b(chips)!SKX_EXT_B_BGA1-IC,TBD!!!F90!PE3_TX_DP(14)!!!!
S!P3E_CPU0_PE3_OCP_TXP<15>!U5D1!CV5!@baseboard_fab2_lib.baseboard_fab2(sch_1):page32_i89@chpset_lib.skx_ext_b(chips)!SKX_EXT_B_BGA1-IC,TBD!!!F90!PE3_TX_DP(15)!!!!
S!P3E_CPU0_PE3_OCP_TXP<1>!U5D1!ED13!@baseboard_fab2_lib.baseboard_fab2(sch_1):page32_i89@chpset_lib.skx_ext_b(chips)!SKX_EXT_B_BGA1-IC,TBD!!!F90!PE3_TX_DP(1)!!!!
S!P3E_CPU0_PE3_OCP_TXP<2>!U5D1!EB11!@baseboard_fab2_lib.baseboard_fab2(sch_1):page32_i89@chpset_lib.skx_ext_b(chips)!SKX_EXT_B_BGA1-IC,TBD!!!F90!PE3_TX_DP(2)!!!!
S!P3E_CPU0_PE3_OCP_TXP<3>!U5D1!EA10!@baseboard_fab2_lib.baseboard_fab2(sch_1):page32_i89@chpset_lib.skx_ext_b(chips)!SKX_EXT_B_BGA1-IC,TBD!!!F90!PE3_TX_DP(3)!!!!
S!P3E_CPU0_PE3_OCP_TXP<4>!U5D1!DY9!@baseboard_fab2_lib.baseboard_fab2(sch_1):page32_i89@chpset_lib.skx_ext_b(chips)!SKX_EXT_B_BGA1-IC,TBD!!!F90!PE3_TX_DP(4)!!!!
S!P3E_CPU0_PE3_OCP_TXP<5>!U5D1!DV9!@baseboard_fab2_lib.baseboard_fab2(sch_1):page32_i89@chpset_lib.skx_ext_b(chips)!SKX_EXT_B_BGA1-IC,TBD!!!F90!PE3_TX_DP(5)!!!!
S!P3E_CPU0_PE3_OCP_TXP<6>!U5D1!DT9!@baseboard_fab2_lib.baseboard_fab2(sch_1):page32_i89@chpset_lib.skx_ext_b(chips)!SKX_EXT_B_BGA1-IC,TBD!!!F90!PE3_TX_DP(6)!!!!
S!P3E_CPU0_PE3_OCP_TXP<7>!U5D1!DP7!@baseboard_fab2_lib.baseboard_fab2(sch_1):page32_i89@chpset_lib.skx_ext_b(chips)!SKX_EXT_B_BGA1-IC,TBD!!!F90!PE3_TX_DP(7)!!!!
S!P3E_CPU0_PE3_OCP_TXP<8>!U5D1!DN6!@baseboard_fab2_lib.baseboard_fab2(sch_1):page32_i89@chpset_lib.skx_ext_b(chips)!SKX_EXT_B_BGA1-IC,TBD!!!F90!PE3_TX_DP(8)!!!!
S!P3E_CPU0_PE3_OCP_TXP<9>!U5D1!DM5!@baseboard_fab2_lib.baseboard_fab2(sch_1):page32_i89@chpset_lib.skx_ext_b(chips)!SKX_EXT_B_BGA1-IC,TBD!!!F90!PE3_TX_DP(9)!!!!
S!UPI_CPU1_CPU0_P0P0_DN<19>!U5D1!AC10!@baseboard_fab2_lib.baseboard_fab2(sch_1):page33_i86@chpset_lib.skx_ext_b(chips)!SKX_EXT_B_BGA1-IC,TBD!!!F89!UPI0_RX_DN(0)!!!!
S!UPI_CPU1_CPU0_P0P0_DN<9>!U5D1!AP7!@baseboard_fab2_lib.baseboard_fab2(sch_1):page33_i86@chpset_lib.skx_ext_b(chips)!SKX_EXT_B_BGA1-IC,TBD!!!F89!UPI0_RX_DN(10)!!!!
S!UPI_CPU1_CPU0_P0P0_DN<8>!U5D1!AR8!@baseboard_fab2_lib.baseboard_fab2(sch_1):page33_i86@chpset_lib.skx_ext_b(chips)!SKX_EXT_B_BGA1-IC,TBD!!!F89!UPI0_RX_DN(11)!!!!
S!UPI_CPU1_CPU0_P0P0_DN<7>!U5D1!AU10!@baseboard_fab2_lib.baseboard_fab2(sch_1):page33_i86@chpset_lib.skx_ext_b(chips)!SKX_EXT_B_BGA1-IC,TBD!!!F89!UPI0_RX_DN(12)!!!!
S!UPI_CPU1_CPU0_P0P0_DN<6>!U5D1!BA8!@baseboard_fab2_lib.baseboard_fab2(sch_1):page33_i86@chpset_lib.skx_ext_b(chips)!SKX_EXT_B_BGA1-IC,TBD!!!F89!UPI0_RX_DN(13)!!!!
S!UPI_CPU1_CPU0_P0P0_DN<5>!U5D1!BC6!@baseboard_fab2_lib.baseboard_fab2(sch_1):page33_i86@chpset_lib.skx_ext_b(chips)!SKX_EXT_B_BGA1-IC,TBD!!!F89!UPI0_RX_DN(14)!!!!
S!UPI_CPU1_CPU0_P0P0_DN<4>!U5D1!BD7!@baseboard_fab2_lib.baseboard_fab2(sch_1):page33_i86@chpset_lib.skx_ext_b(chips)!SKX_EXT_B_BGA1-IC,TBD!!!F89!UPI0_RX_DN(15)!!!!
S!UPI_CPU1_CPU0_P0P0_DN<3>!U5D1!AW8!@baseboard_fab2_lib.baseboard_fab2(sch_1):page33_i86@chpset_lib.skx_ext_b(chips)!SKX_EXT_B_BGA1-IC,TBD!!!F89!UPI0_RX_DN(16)!!!!
S!UPI_CPU1_CPU0_P0P0_DN<2>!U5D1!AY9!@baseboard_fab2_lib.baseboard_fab2(sch_1):page33_i86@chpset_lib.skx_ext_b(chips)!SKX_EXT_B_BGA1-IC,TBD!!!F89!UPI0_RX_DN(17)!!!!
S!UPI_CPU1_CPU0_P0P0_DN<1>!U5D1!BD9!@baseboard_fab2_lib.baseboard_fab2(sch_1):page33_i86@chpset_lib.skx_ext_b(chips)!SKX_EXT_B_BGA1-IC,TBD!!!F89!UPI0_RX_DN(18)!!!!
S!UPI_CPU1_CPU0_P0P0_DN<0>!U5D1!BB11!@baseboard_fab2_lib.baseboard_fab2(sch_1):page33_i86@chpset_lib.skx_ext_b(chips)!SKX_EXT_B_BGA1-IC,TBD!!!F89!UPI0_RX_DN(19)!!!!
S!UPI_CPU1_CPU0_P0P0_DN<18>!U5D1!AA8!@baseboard_fab2_lib.baseboard_fab2(sch_1):page33_i86@chpset_lib.skx_ext_b(chips)!SKX_EXT_B_BGA1-IC,TBD!!!F89!UPI0_RX_DN(1)!!!!
S!UPI_CPU1_CPU0_P0P0_DN<17>!U5D1!AB7!@baseboard_fab2_lib.baseboard_fab2(sch_1):page33_i86@chpset_lib.skx_ext_b(chips)!SKX_EXT_B_BGA1-IC,TBD!!!F89!UPI0_RX_DN(2)!!!!
S!UPI_CPU1_CPU0_P0P0_DN<16>!U5D1!AD5!@baseboard_fab2_lib.baseboard_fab2(sch_1):page33_i86@chpset_lib.skx_ext_b(chips)!SKX_EXT_B_BGA1-IC,TBD!!!F89!UPI0_RX_DN(3)!!!!
S!UPI_CPU1_CPU0_P0P0_DN<15>!U5D1!AE6!@baseboard_fab2_lib.baseboard_fab2(sch_1):page33_i86@chpset_lib.skx_ext_b(chips)!SKX_EXT_B_BGA1-IC,TBD!!!F89!UPI0_RX_DN(4)!!!!
S!UPI_CPU1_CPU0_P0P0_DN<14>!U5D1!AG8!@baseboard_fab2_lib.baseboard_fab2(sch_1):page33_i86@chpset_lib.skx_ext_b(chips)!SKX_EXT_B_BGA1-IC,TBD!!!F89!UPI0_RX_DN(5)!!!!
S!UPI_CPU1_CPU0_P0P0_DN<13>!U5D1!AJ6!@baseboard_fab2_lib.baseboard_fab2(sch_1):page33_i86@chpset_lib.skx_ext_b(chips)!SKX_EXT_B_BGA1-IC,TBD!!!F89!UPI0_RX_DN(6)!!!!
S!UPI_CPU1_CPU0_P0P0_DN<12>!U5D1!AL6!@baseboard_fab2_lib.baseboard_fab2(sch_1):page33_i86@chpset_lib.skx_ext_b(chips)!SKX_EXT_B_BGA1-IC,TBD!!!F89!UPI0_RX_DN(7)!!!!
S!UPI_CPU1_CPU0_P0P0_DN<11>!U5D1!AK7!@baseboard_fab2_lib.baseboard_fab2(sch_1):page33_i86@chpset_lib.skx_ext_b(chips)!SKX_EXT_B_BGA1-IC,TBD!!!F89!UPI0_RX_DN(8)!!!!
S!UPI_CPU1_CPU0_P0P0_DN<10>!U5D1!AM9!@baseboard_fab2_lib.baseboard_fab2(sch_1):page33_i86@chpset_lib.skx_ext_b(chips)!SKX_EXT_B_BGA1-IC,TBD!!!F89!UPI0_RX_DN(9)!!!!
S!UPI_CPU1_CPU0_P0P0_DP<19>!U5D1!AB9!@baseboard_fab2_lib.baseboard_fab2(sch_1):page33_i86@chpset_lib.skx_ext_b(chips)!SKX_EXT_B_BGA1-IC,TBD!!!F89!UPI0_RX_DP(0)!!!!
S!UPI_CPU1_CPU0_P0P0_DP<9>!U5D1!AN8!@baseboard_fab2_lib.baseboard_fab2(sch_1):page33_i86@chpset_lib.skx_ext_b(chips)!SKX_EXT_B_BGA1-IC,TBD!!!F89!UPI0_RX_DP(10)!!!!
S!UPI_CPU1_CPU0_P0P0_DP<8>!U5D1!AU8!@baseboard_fab2_lib.baseboard_fab2(sch_1):page33_i86@chpset_lib.skx_ext_b(chips)!SKX_EXT_B_BGA1-IC,TBD!!!F89!UPI0_RX_DP(11)!!!!
S!UPI_CPU1_CPU0_P0P0_DP<7>!U5D1!AT9!@baseboard_fab2_lib.baseboard_fab2(sch_1):page33_i86@chpset_lib.skx_ext_b(chips)!SKX_EXT_B_BGA1-IC,TBD!!!F89!UPI0_RX_DP(12)!!!!
S!UPI_CPU1_CPU0_P0P0_DP<6>!U5D1!AY7!@baseboard_fab2_lib.baseboard_fab2(sch_1):page33_i86@chpset_lib.skx_ext_b(chips)!SKX_EXT_B_BGA1-IC,TBD!!!F89!UPI0_RX_DP(13)!!!!
S!UPI_CPU1_CPU0_P0P0_DP<5>!U5D1!BB7!@baseboard_fab2_lib.baseboard_fab2(sch_1):page33_i86@chpset_lib.skx_ext_b(chips)!SKX_EXT_B_BGA1-IC,TBD!!!F89!UPI0_RX_DP(14)!!!!
S!UPI_CPU1_CPU0_P0P0_DP<4>!U5D1!BF7!@baseboard_fab2_lib.baseboard_fab2(sch_1):page33_i86@chpset_lib.skx_ext_b(chips)!SKX_EXT_B_BGA1-IC,TBD!!!F89!UPI0_RX_DP(15)!!!!
S!UPI_CPU1_CPU0_P0P0_DP<3>!U5D1!AV9!@baseboard_fab2_lib.baseboard_fab2(sch_1):page33_i86@chpset_lib.skx_ext_b(chips)!SKX_EXT_B_BGA1-IC,TBD!!!F89!UPI0_RX_DP(16)!!!!
S!UPI_CPU1_CPU0_P0P0_DP<2>!U5D1!BB9!@baseboard_fab2_lib.baseboard_fab2(sch_1):page33_i86@chpset_lib.skx_ext_b(chips)!SKX_EXT_B_BGA1-IC,TBD!!!F89!UPI0_RX_DP(17)!!!!
S!UPI_CPU1_CPU0_P0P0_DP<1>!U5D1!BC10!@baseboard_fab2_lib.baseboard_fab2(sch_1):page33_i86@chpset_lib.skx_ext_b(chips)!SKX_EXT_B_BGA1-IC,TBD!!!F89!UPI0_RX_DP(18)!!!!
S!UPI_CPU1_CPU0_P0P0_DP<0>!U5D1!BA10!@baseboard_fab2_lib.baseboard_fab2(sch_1):page33_i86@chpset_lib.skx_ext_b(chips)!SKX_EXT_B_BGA1-IC,TBD!!!F89!UPI0_RX_DP(19)!!!!
S!UPI_CPU1_CPU0_P0P0_DP<18>!U5D1!AC8!@baseboard_fab2_lib.baseboard_fab2(sch_1):page33_i86@chpset_lib.skx_ext_b(chips)!SKX_EXT_B_BGA1-IC,TBD!!!F89!UPI0_RX_DP(1)!!!!
S!UPI_CPU1_CPU0_P0P0_DP<17>!U5D1!AA6!@baseboard_fab2_lib.baseboard_fab2(sch_1):page33_i86@chpset_lib.skx_ext_b(chips)!SKX_EXT_B_BGA1-IC,TBD!!!F89!UPI0_RX_DP(2)!!!!
S!UPI_CPU1_CPU0_P0P0_DP<16>!U5D1!AC6!@baseboard_fab2_lib.baseboard_fab2(sch_1):page33_i86@chpset_lib.skx_ext_b(chips)!SKX_EXT_B_BGA1-IC,TBD!!!F89!UPI0_RX_DP(3)!!!!
S!UPI_CPU1_CPU0_P0P0_DP<15>!U5D1!AG6!@baseboard_fab2_lib.baseboard_fab2(sch_1):page33_i86@chpset_lib.skx_ext_b(chips)!SKX_EXT_B_BGA1-IC,TBD!!!F89!UPI0_RX_DP(4)!!!!
S!UPI_CPU1_CPU0_P0P0_DP<14>!U5D1!AF7!@baseboard_fab2_lib.baseboard_fab2(sch_1):page33_i86@chpset_lib.skx_ext_b(chips)!SKX_EXT_B_BGA1-IC,TBD!!!F89!UPI0_RX_DP(5)!!!!
S!UPI_CPU1_CPU0_P0P0_DP<13>!U5D1!AH7!@baseboard_fab2_lib.baseboard_fab2(sch_1):page33_i86@chpset_lib.skx_ext_b(chips)!SKX_EXT_B_BGA1-IC,TBD!!!F89!UPI0_RX_DP(6)!!!!
S!UPI_CPU1_CPU0_P0P0_DP<12>!U5D1!AK5!@baseboard_fab2_lib.baseboard_fab2(sch_1):page33_i86@chpset_lib.skx_ext_b(chips)!SKX_EXT_B_BGA1-IC,TBD!!!F89!UPI0_RX_DP(7)!!!!
S!UPI_CPU1_CPU0_P0P0_DP<11>!U5D1!AM7!@baseboard_fab2_lib.baseboard_fab2(sch_1):page33_i86@chpset_lib.skx_ext_b(chips)!SKX_EXT_B_BGA1-IC,TBD!!!F89!UPI0_RX_DP(8)!!!!
S!UPI_CPU1_CPU0_P0P0_DP<10>!U5D1!AL8!@baseboard_fab2_lib.baseboard_fab2(sch_1):page33_i86@chpset_lib.skx_ext_b(chips)!SKX_EXT_B_BGA1-IC,TBD!!!F89!UPI0_RX_DP(9)!!!!
S!UPI_CPU0_CPU1_P0P0_DN<19>!U5D1!N2!@baseboard_fab2_lib.baseboard_fab2(sch_1):page33_i86@chpset_lib.skx_ext_b(chips)!SKX_EXT_B_BGA1-IC,TBD!!!F89!UPI0_TX_DN(0)!!!!
S!UPI_CPU0_CPU1_P0P0_DN<9>!U5D1!AM3!@baseboard_fab2_lib.baseboard_fab2(sch_1):page33_i86@chpset_lib.skx_ext_b(chips)!SKX_EXT_B_BGA1-IC,TBD!!!F89!UPI0_TX_DN(10)!!!!
S!UPI_CPU0_CPU1_P0P0_DN<8>!U5D1!AN4!@baseboard_fab2_lib.baseboard_fab2(sch_1):page33_i86@chpset_lib.skx_ext_b(chips)!SKX_EXT_B_BGA1-IC,TBD!!!F89!UPI0_TX_DN(11)!!!!
S!UPI_CPU0_CPU1_P0P0_DN<7>!U5D1!AT1!@baseboard_fab2_lib.baseboard_fab2(sch_1):page33_i86@chpset_lib.skx_ext_b(chips)!SKX_EXT_B_BGA1-IC,TBD!!!F89!UPI0_TX_DN(12)!!!!
S!UPI_CPU0_CPU1_P0P0_DN<6>!U5D1!AT3!@baseboard_fab2_lib.baseboard_fab2(sch_1):page33_i86@chpset_lib.skx_ext_b(chips)!SKX_EXT_B_BGA1-IC,TBD!!!F89!UPI0_TX_DN(13)!!!!
S!UPI_CPU0_CPU1_P0P0_DN<5>!U5D1!AU4!@baseboard_fab2_lib.baseboard_fab2(sch_1):page33_i86@chpset_lib.skx_ext_b(chips)!SKX_EXT_B_BGA1-IC,TBD!!!F89!UPI0_TX_DN(14)!!!!
S!UPI_CPU0_CPU1_P0P0_DN<4>!U5D1!AV5!@baseboard_fab2_lib.baseboard_fab2(sch_1):page33_i86@chpset_lib.skx_ext_b(chips)!SKX_EXT_B_BGA1-IC,TBD!!!F89!UPI0_TX_DN(15)!!!!
S!UPI_CPU0_CPU1_P0P0_DN<3>!U5D1!BA4!@baseboard_fab2_lib.baseboard_fab2(sch_1):page33_i86@chpset_lib.skx_ext_b(chips)!SKX_EXT_B_BGA1-IC,TBD!!!F89!UPI0_TX_DN(16)!!!!
S!UPI_CPU0_CPU1_P0P0_DN<2>!U5D1!BB3!@baseboard_fab2_lib.baseboard_fab2(sch_1):page33_i86@chpset_lib.skx_ext_b(chips)!SKX_EXT_B_BGA1-IC,TBD!!!F89!UPI0_TX_DN(17)!!!!
S!UPI_CPU0_CPU1_P0P0_DN<1>!U5D1!BF3!@baseboard_fab2_lib.baseboard_fab2(sch_1):page33_i86@chpset_lib.skx_ext_b(chips)!SKX_EXT_B_BGA1-IC,TBD!!!F89!UPI0_TX_DN(18)!!!!
S!UPI_CPU0_CPU1_P0P0_DN<0>!U5D1!BG4!@baseboard_fab2_lib.baseboard_fab2(sch_1):page33_i86@chpset_lib.skx_ext_b(chips)!SKX_EXT_B_BGA1-IC,TBD!!!F89!UPI0_TX_DN(19)!!!!
S!UPI_CPU0_CPU1_P0P0_DN<18>!U5D1!P1!@baseboard_fab2_lib.baseboard_fab2(sch_1):page33_i86@chpset_lib.skx_ext_b(chips)!SKX_EXT_B_BGA1-IC,TBD!!!F89!UPI0_TX_DN(1)!!!!
S!UPI_CPU0_CPU1_P0P0_DN<17>!U5D1!V3!@baseboard_fab2_lib.baseboard_fab2(sch_1):page33_i86@chpset_lib.skx_ext_b(chips)!SKX_EXT_B_BGA1-IC,TBD!!!F89!UPI0_TX_DN(2)!!!!
S!UPI_CPU0_CPU1_P0P0_DN<16>!U5D1!Y1!@baseboard_fab2_lib.baseboard_fab2(sch_1):page33_i86@chpset_lib.skx_ext_b(chips)!SKX_EXT_B_BGA1-IC,TBD!!!F89!UPI0_TX_DN(3)!!!!
S!UPI_CPU0_CPU1_P0P0_DN<15>!U5D1!AB3!@baseboard_fab2_lib.baseboard_fab2(sch_1):page33_i86@chpset_lib.skx_ext_b(chips)!SKX_EXT_B_BGA1-IC,TBD!!!F89!UPI0_TX_DN(4)!!!!
S!UPI_CPU0_CPU1_P0P0_DN<14>!U5D1!AC2!@baseboard_fab2_lib.baseboard_fab2(sch_1):page33_i86@chpset_lib.skx_ext_b(chips)!SKX_EXT_B_BGA1-IC,TBD!!!F89!UPI0_TX_DN(5)!!!!
S!UPI_CPU0_CPU1_P0P0_DN<13>!U5D1!AG4!@baseboard_fab2_lib.baseboard_fab2(sch_1):page33_i86@chpset_lib.skx_ext_b(chips)!SKX_EXT_B_BGA1-IC,TBD!!!F89!UPI0_TX_DN(6)!!!!
S!UPI_CPU0_CPU1_P0P0_DN<12>!U5D1!AE2!@baseboard_fab2_lib.baseboard_fab2(sch_1):page33_i86@chpset_lib.skx_ext_b(chips)!SKX_EXT_B_BGA1-IC,TBD!!!F89!UPI0_TX_DN(7)!!!!
S!UPI_CPU0_CPU1_P0P0_DN<11>!U5D1!AH3!@baseboard_fab2_lib.baseboard_fab2(sch_1):page33_i86@chpset_lib.skx_ext_b(chips)!SKX_EXT_B_BGA1-IC,TBD!!!F89!UPI0_TX_DN(8)!!!!
S!UPI_CPU0_CPU1_P0P0_DN<10>!U5D1!AL2!@baseboard_fab2_lib.baseboard_fab2(sch_1):page33_i86@chpset_lib.skx_ext_b(chips)!SKX_EXT_B_BGA1-IC,TBD!!!F89!UPI0_TX_DN(9)!!!!
S!UPI_CPU0_CPU1_P0P0_DP<19>!U5D1!M1!@baseboard_fab2_lib.baseboard_fab2(sch_1):page33_i86@chpset_lib.skx_ext_b(chips)!SKX_EXT_B_BGA1-IC,TBD!!!F89!UPI0_TX_DP(0)!!!!
S!UPI_CPU0_CPU1_P0P0_DP<9>!U5D1!AK3!@baseboard_fab2_lib.baseboard_fab2(sch_1):page33_i86@chpset_lib.skx_ext_b(chips)!SKX_EXT_B_BGA1-IC,TBD!!!F89!UPI0_TX_DP(10)!!!!
S!UPI_CPU0_CPU1_P0P0_DP<8>!U5D1!AP3!@baseboard_fab2_lib.baseboard_fab2(sch_1):page33_i86@chpset_lib.skx_ext_b(chips)!SKX_EXT_B_BGA1-IC,TBD!!!F89!UPI0_TX_DP(11)!!!!
S!UPI_CPU0_CPU1_P0P0_DP<7>!U5D1!AP1!@baseboard_fab2_lib.baseboard_fab2(sch_1):page33_i86@chpset_lib.skx_ext_b(chips)!SKX_EXT_B_BGA1-IC,TBD!!!F89!UPI0_TX_DP(12)!!!!
S!UPI_CPU0_CPU1_P0P0_DP<6>!U5D1!AR2!@baseboard_fab2_lib.baseboard_fab2(sch_1):page33_i86@chpset_lib.skx_ext_b(chips)!SKX_EXT_B_BGA1-IC,TBD!!!F89!UPI0_TX_DP(13)!!!!
S!UPI_CPU0_CPU1_P0P0_DP<5>!U5D1!AR4!@baseboard_fab2_lib.baseboard_fab2(sch_1):page33_i86@chpset_lib.skx_ext_b(chips)!SKX_EXT_B_BGA1-IC,TBD!!!F89!UPI0_TX_DP(14)!!!!
S!UPI_CPU0_CPU1_P0P0_DP<4>!U5D1!AW4!@baseboard_fab2_lib.baseboard_fab2(sch_1):page33_i86@chpset_lib.skx_ext_b(chips)!SKX_EXT_B_BGA1-IC,TBD!!!F89!UPI0_TX_DP(15)!!!!
S!UPI_CPU0_CPU1_P0P0_DP<3>!U5D1!AY3!@baseboard_fab2_lib.baseboard_fab2(sch_1):page33_i86@chpset_lib.skx_ext_b(chips)!SKX_EXT_B_BGA1-IC,TBD!!!F89!UPI0_TX_DP(16)!!!!
S!UPI_CPU0_CPU1_P0P0_DP<2>!U5D1!BC2!@baseboard_fab2_lib.baseboard_fab2(sch_1):page33_i86@chpset_lib.skx_ext_b(chips)!SKX_EXT_B_BGA1-IC,TBD!!!F89!UPI0_TX_DP(17)!!!!
S!UPI_CPU0_CPU1_P0P0_DP<1>!U5D1!BD3!@baseboard_fab2_lib.baseboard_fab2(sch_1):page33_i86@chpset_lib.skx_ext_b(chips)!SKX_EXT_B_BGA1-IC,TBD!!!F89!UPI0_TX_DP(18)!!!!
S!UPI_CPU0_CPU1_P0P0_DP<0>!U5D1!BH3!@baseboard_fab2_lib.baseboard_fab2(sch_1):page33_i86@chpset_lib.skx_ext_b(chips)!SKX_EXT_B_BGA1-IC,TBD!!!F89!UPI0_TX_DP(19)!!!!
S!UPI_CPU0_CPU1_P0P0_DP<18>!U5D1!T1!@baseboard_fab2_lib.baseboard_fab2(sch_1):page33_i86@chpset_lib.skx_ext_b(chips)!SKX_EXT_B_BGA1-IC,TBD!!!F89!UPI0_TX_DP(1)!!!!
S!UPI_CPU0_CPU1_P0P0_DP<17>!U5D1!Y3!@baseboard_fab2_lib.baseboard_fab2(sch_1):page33_i86@chpset_lib.skx_ext_b(chips)!SKX_EXT_B_BGA1-IC,TBD!!!F89!UPI0_TX_DP(2)!!!!
S!UPI_CPU0_CPU1_P0P0_DP<16>!U5D1!W2!@baseboard_fab2_lib.baseboard_fab2(sch_1):page33_i86@chpset_lib.skx_ext_b(chips)!SKX_EXT_B_BGA1-IC,TBD!!!F89!UPI0_TX_DP(3)!!!!
S!UPI_CPU0_CPU1_P0P0_DP<15>!U5D1!AA2!@baseboard_fab2_lib.baseboard_fab2(sch_1):page33_i86@chpset_lib.skx_ext_b(chips)!SKX_EXT_B_BGA1-IC,TBD!!!F89!UPI0_TX_DP(4)!!!!
S!UPI_CPU0_CPU1_P0P0_DP<14>!U5D1!AD1!@baseboard_fab2_lib.baseboard_fab2(sch_1):page33_i86@chpset_lib.skx_ext_b(chips)!SKX_EXT_B_BGA1-IC,TBD!!!F89!UPI0_TX_DP(5)!!!!
S!UPI_CPU0_CPU1_P0P0_DP<13>!U5D1!AF3!@baseboard_fab2_lib.baseboard_fab2(sch_1):page33_i86@chpset_lib.skx_ext_b(chips)!SKX_EXT_B_BGA1-IC,TBD!!!F89!UPI0_TX_DP(6)!!!!
S!UPI_CPU0_CPU1_P0P0_DP<12>!U5D1!AG2!@baseboard_fab2_lib.baseboard_fab2(sch_1):page33_i86@chpset_lib.skx_ext_b(chips)!SKX_EXT_B_BGA1-IC,TBD!!!F89!UPI0_TX_DP(7)!!!!
S!UPI_CPU0_CPU1_P0P0_DP<11>!U5D1!AJ2!@baseboard_fab2_lib.baseboard_fab2(sch_1):page33_i86@chpset_lib.skx_ext_b(chips)!SKX_EXT_B_BGA1-IC,TBD!!!F89!UPI0_TX_DP(8)!!!!
S!UPI_CPU0_CPU1_P0P0_DP<10>!U5D1!AK1!@baseboard_fab2_lib.baseboard_fab2(sch_1):page33_i86@chpset_lib.skx_ext_b(chips)!SKX_EXT_B_BGA1-IC,TBD!!!F89!UPI0_TX_DP(9)!!!!
S!UPI_CPU1_CPU0_P1P1_DN<19>!U5D1!T5!@baseboard_fab2_lib.baseboard_fab2(sch_1):page34_i86@chpset_lib.skx_ext_b(chips)!SKX_EXT_B_BGA1-IC,TBD!!!F88!UPI1_RX_DN(0)!!!!
S!UPI_CPU1_CPU0_P1P1_DN<9>!U5D1!R16!@baseboard_fab2_lib.baseboard_fab2(sch_1):page34_i86@chpset_lib.skx_ext_b(chips)!SKX_EXT_B_BGA1-IC,TBD!!!F88!UPI1_RX_DN(10)!!!!
S!UPI_CPU1_CPU0_P1P1_DN<8>!U5D1!P17!@baseboard_fab2_lib.baseboard_fab2(sch_1):page34_i86@chpset_lib.skx_ext_b(chips)!SKX_EXT_B_BGA1-IC,TBD!!!F88!UPI1_RX_DN(11)!!!!
S!UPI_CPU1_CPU0_P1P1_DN<7>!U5D1!U16!@baseboard_fab2_lib.baseboard_fab2(sch_1):page34_i86@chpset_lib.skx_ext_b(chips)!SKX_EXT_B_BGA1-IC,TBD!!!F88!UPI1_RX_DN(12)!!!!
S!UPI_CPU1_CPU0_P1P1_DN<6>!U5D1!W18!@baseboard_fab2_lib.baseboard_fab2(sch_1):page34_i86@chpset_lib.skx_ext_b(chips)!SKX_EXT_B_BGA1-IC,TBD!!!F88!UPI1_RX_DN(13)!!!!
S!UPI_CPU1_CPU0_P1P1_DN<5>!U5D1!R20!@baseboard_fab2_lib.baseboard_fab2(sch_1):page34_i86@chpset_lib.skx_ext_b(chips)!SKX_EXT_B_BGA1-IC,TBD!!!F88!UPI1_RX_DN(14)!!!!
S!UPI_CPU1_CPU0_P1P1_DN<4>!U5D1!U18!@baseboard_fab2_lib.baseboard_fab2(sch_1):page34_i86@chpset_lib.skx_ext_b(chips)!SKX_EXT_B_BGA1-IC,TBD!!!F88!UPI1_RX_DN(15)!!!!
S!UPI_CPU1_CPU0_P1P1_DN<3>!U5D1!P21!@baseboard_fab2_lib.baseboard_fab2(sch_1):page34_i86@chpset_lib.skx_ext_b(chips)!SKX_EXT_B_BGA1-IC,TBD!!!F88!UPI1_RX_DN(16)!!!!
S!UPI_CPU1_CPU0_P1P1_DN<2>!U5D1!V19!@baseboard_fab2_lib.baseboard_fab2(sch_1):page34_i86@chpset_lib.skx_ext_b(chips)!SKX_EXT_B_BGA1-IC,TBD!!!F88!UPI1_RX_DN(17)!!!!
S!UPI_CPU1_CPU0_P1P1_DN<1>!U5D1!Y21!@baseboard_fab2_lib.baseboard_fab2(sch_1):page34_i86@chpset_lib.skx_ext_b(chips)!SKX_EXT_B_BGA1-IC,TBD!!!F88!UPI1_RX_DN(18)!!!!
S!UPI_CPU1_CPU0_P1P1_DN<0>!U5D1!AB19!@baseboard_fab2_lib.baseboard_fab2(sch_1):page34_i86@chpset_lib.skx_ext_b(chips)!SKX_EXT_B_BGA1-IC,TBD!!!F88!UPI1_RX_DN(19)!!!!
S!UPI_CPU1_CPU0_P1P1_DN<18>!U5D1!P7!@baseboard_fab2_lib.baseboard_fab2(sch_1):page34_i86@chpset_lib.skx_ext_b(chips)!SKX_EXT_B_BGA1-IC,TBD!!!F88!UPI1_RX_DN(1)!!!!
S!UPI_CPU1_CPU0_P1P1_DN<17>!U5D1!V7!@baseboard_fab2_lib.baseboard_fab2(sch_1):page34_i86@chpset_lib.skx_ext_b(chips)!SKX_EXT_B_BGA1-IC,TBD!!!F88!UPI1_RX_DN(2)!!!!
S!UPI_CPU1_CPU0_P1P1_DN<16>!U5D1!T9!@baseboard_fab2_lib.baseboard_fab2(sch_1):page34_i86@chpset_lib.skx_ext_b(chips)!SKX_EXT_B_BGA1-IC,TBD!!!F88!UPI1_RX_DN(3)!!!!
S!UPI_CPU1_CPU0_P1P1_DN<15>!U5D1!P9!@baseboard_fab2_lib.baseboard_fab2(sch_1):page34_i86@chpset_lib.skx_ext_b(chips)!SKX_EXT_B_BGA1-IC,TBD!!!F88!UPI1_RX_DN(4)!!!!
S!UPI_CPU1_CPU0_P1P1_DN<14>!U5D1!R10!@baseboard_fab2_lib.baseboard_fab2(sch_1):page34_i86@chpset_lib.skx_ext_b(chips)!SKX_EXT_B_BGA1-IC,TBD!!!F88!UPI1_RX_DN(5)!!!!
S!UPI_CPU1_CPU0_P1P1_DN<13>!U5D1!U12!@baseboard_fab2_lib.baseboard_fab2(sch_1):page34_i86@chpset_lib.skx_ext_b(chips)!SKX_EXT_B_BGA1-IC,TBD!!!F88!UPI1_RX_DN(6)!!!!
S!UPI_CPU1_CPU0_P1P1_DN<12>!U5D1!L12!@baseboard_fab2_lib.baseboard_fab2(sch_1):page34_i86@chpset_lib.skx_ext_b(chips)!SKX_EXT_B_BGA1-IC,TBD!!!F88!UPI1_RX_DN(7)!!!!
S!UPI_CPU1_CPU0_P1P1_DN<11>!U5D1!N14!@baseboard_fab2_lib.baseboard_fab2(sch_1):page34_i86@chpset_lib.skx_ext_b(chips)!SKX_EXT_B_BGA1-IC,TBD!!!F88!UPI1_RX_DN(8)!!!!
S!UPI_CPU1_CPU0_P1P1_DN<10>!U5D1!R12!@baseboard_fab2_lib.baseboard_fab2(sch_1):page34_i86@chpset_lib.skx_ext_b(chips)!SKX_EXT_B_BGA1-IC,TBD!!!F88!UPI1_RX_DN(9)!!!!
S!UPI_CPU1_CPU0_P1P1_DP<19>!U5D1!R6!@baseboard_fab2_lib.baseboard_fab2(sch_1):page34_i86@chpset_lib.skx_ext_b(chips)!SKX_EXT_B_BGA1-IC,TBD!!!F88!UPI1_RX_DP(0)!!!!
S!UPI_CPU1_CPU0_P1P1_DP<9>!U5D1!T15!@baseboard_fab2_lib.baseboard_fab2(sch_1):page34_i86@chpset_lib.skx_ext_b(chips)!SKX_EXT_B_BGA1-IC,TBD!!!F88!UPI1_RX_DP(10)!!!!
S!UPI_CPU1_CPU0_P1P1_DP<8>!U5D1!N16!@baseboard_fab2_lib.baseboard_fab2(sch_1):page34_i86@chpset_lib.skx_ext_b(chips)!SKX_EXT_B_BGA1-IC,TBD!!!F88!UPI1_RX_DP(11)!!!!
S!UPI_CPU1_CPU0_P1P1_DP<7>!U5D1!W16!@baseboard_fab2_lib.baseboard_fab2(sch_1):page34_i86@chpset_lib.skx_ext_b(chips)!SKX_EXT_B_BGA1-IC,TBD!!!F88!UPI1_RX_DP(12)!!!!
S!UPI_CPU1_CPU0_P1P1_DP<6>!U5D1!V17!@baseboard_fab2_lib.baseboard_fab2(sch_1):page34_i86@chpset_lib.skx_ext_b(chips)!SKX_EXT_B_BGA1-IC,TBD!!!F88!UPI1_RX_DP(13)!!!!
S!UPI_CPU1_CPU0_P1P1_DP<5>!U5D1!P19!@baseboard_fab2_lib.baseboard_fab2(sch_1):page34_i86@chpset_lib.skx_ext_b(chips)!SKX_EXT_B_BGA1-IC,TBD!!!F88!UPI1_RX_DP(14)!!!!
S!UPI_CPU1_CPU0_P1P1_DP<4>!U5D1!T19!@baseboard_fab2_lib.baseboard_fab2(sch_1):page34_i86@chpset_lib.skx_ext_b(chips)!SKX_EXT_B_BGA1-IC,TBD!!!F88!UPI1_RX_DP(15)!!!!
S!UPI_CPU1_CPU0_P1P1_DP<3>!U5D1!T21!@baseboard_fab2_lib.baseboard_fab2(sch_1):page34_i86@chpset_lib.skx_ext_b(chips)!SKX_EXT_B_BGA1-IC,TBD!!!F88!UPI1_RX_DP(16)!!!!
S!UPI_CPU1_CPU0_P1P1_DP<2>!U5D1!Y19!@baseboard_fab2_lib.baseboard_fab2(sch_1):page34_i86@chpset_lib.skx_ext_b(chips)!SKX_EXT_B_BGA1-IC,TBD!!!F88!UPI1_RX_DP(17)!!!!
S!UPI_CPU1_CPU0_P1P1_DP<1>!U5D1!W20!@baseboard_fab2_lib.baseboard_fab2(sch_1):page34_i86@chpset_lib.skx_ext_b(chips)!SKX_EXT_B_BGA1-IC,TBD!!!F88!UPI1_RX_DP(18)!!!!
S!UPI_CPU1_CPU0_P1P1_DP<0>!U5D1!AA20!@baseboard_fab2_lib.baseboard_fab2(sch_1):page34_i86@chpset_lib.skx_ext_b(chips)!SKX_EXT_B_BGA1-IC,TBD!!!F88!UPI1_RX_DP(19)!!!!
S!UPI_CPU1_CPU0_P1P1_DP<18>!U5D1!T7!@baseboard_fab2_lib.baseboard_fab2(sch_1):page34_i86@chpset_lib.skx_ext_b(chips)!SKX_EXT_B_BGA1-IC,TBD!!!F88!UPI1_RX_DP(1)!!!!
S!UPI_CPU1_CPU0_P1P1_DP<17>!U5D1!U8!@baseboard_fab2_lib.baseboard_fab2(sch_1):page34_i86@chpset_lib.skx_ext_b(chips)!SKX_EXT_B_BGA1-IC,TBD!!!F88!UPI1_RX_DP(2)!!!!
S!UPI_CPU1_CPU0_P1P1_DP<16>!U5D1!R8!@baseboard_fab2_lib.baseboard_fab2(sch_1):page34_i86@chpset_lib.skx_ext_b(chips)!SKX_EXT_B_BGA1-IC,TBD!!!F88!UPI1_RX_DP(3)!!!!
S!UPI_CPU1_CPU0_P1P1_DP<15>!U5D1!N10!@baseboard_fab2_lib.baseboard_fab2(sch_1):page34_i86@chpset_lib.skx_ext_b(chips)!SKX_EXT_B_BGA1-IC,TBD!!!F88!UPI1_RX_DP(4)!!!!
S!UPI_CPU1_CPU0_P1P1_DP<14>!U5D1!U10!@baseboard_fab2_lib.baseboard_fab2(sch_1):page34_i86@chpset_lib.skx_ext_b(chips)!SKX_EXT_B_BGA1-IC,TBD!!!F88!UPI1_RX_DP(5)!!!!
S!UPI_CPU1_CPU0_P1P1_DP<13>!U5D1!T11!@baseboard_fab2_lib.baseboard_fab2(sch_1):page34_i86@chpset_lib.skx_ext_b(chips)!SKX_EXT_B_BGA1-IC,TBD!!!F88!UPI1_RX_DP(6)!!!!
S!UPI_CPU1_CPU0_P1P1_DP<12>!U5D1!N12!@baseboard_fab2_lib.baseboard_fab2(sch_1):page34_i86@chpset_lib.skx_ext_b(chips)!SKX_EXT_B_BGA1-IC,TBD!!!F88!UPI1_RX_DP(7)!!!!
S!UPI_CPU1_CPU0_P1P1_DP<11>!U5D1!M13!@baseboard_fab2_lib.baseboard_fab2(sch_1):page34_i86@chpset_lib.skx_ext_b(chips)!SKX_EXT_B_BGA1-IC,TBD!!!F88!UPI1_RX_DP(8)!!!!
S!UPI_CPU1_CPU0_P1P1_DP<10>!U5D1!P13!@baseboard_fab2_lib.baseboard_fab2(sch_1):page34_i86@chpset_lib.skx_ext_b(chips)!SKX_EXT_B_BGA1-IC,TBD!!!F88!UPI1_RX_DP(9)!!!!
S!UPI_CPU0_CPU1_P1P1_DN<19>!U5D1!M3!@baseboard_fab2_lib.baseboard_fab2(sch_1):page34_i86@chpset_lib.skx_ext_b(chips)!SKX_EXT_B_BGA1-IC,TBD!!!F88!UPI1_TX_DN(0)!!!!
S!UPI_CPU0_CPU1_P1P1_DN<9>!U5D1!E12!@baseboard_fab2_lib.baseboard_fab2(sch_1):page34_i86@chpset_lib.skx_ext_b(chips)!SKX_EXT_B_BGA1-IC,TBD!!!F88!UPI1_TX_DN(10)!!!!
S!UPI_CPU0_CPU1_P1P1_DN<8>!U5D1!G14!@baseboard_fab2_lib.baseboard_fab2(sch_1):page34_i86@chpset_lib.skx_ext_b(chips)!SKX_EXT_B_BGA1-IC,TBD!!!F88!UPI1_TX_DN(11)!!!!
S!UPI_CPU0_CPU1_P1P1_DN<7>!U5D1!D15!@baseboard_fab2_lib.baseboard_fab2(sch_1):page34_i86@chpset_lib.skx_ext_b(chips)!SKX_EXT_B_BGA1-IC,TBD!!!F88!UPI1_TX_DN(12)!!!!
S!UPI_CPU0_CPU1_P1P1_DN<6>!U5D1!F15!@baseboard_fab2_lib.baseboard_fab2(sch_1):page34_i86@chpset_lib.skx_ext_b(chips)!SKX_EXT_B_BGA1-IC,TBD!!!F88!UPI1_TX_DN(13)!!!!
S!UPI_CPU0_CPU1_P1P1_DN<5>!U5D1!H17!@baseboard_fab2_lib.baseboard_fab2(sch_1):page34_i86@chpset_lib.skx_ext_b(chips)!SKX_EXT_B_BGA1-IC,TBD!!!F88!UPI1_TX_DN(14)!!!!
S!UPI_CPU0_CPU1_P1P1_DN<4>!U5D1!K19!@baseboard_fab2_lib.baseboard_fab2(sch_1):page34_i86@chpset_lib.skx_ext_b(chips)!SKX_EXT_B_BGA1-IC,TBD!!!F88!UPI1_TX_DN(15)!!!!
S!UPI_CPU0_CPU1_P1P1_DN<3>!U5D1!G18!@baseboard_fab2_lib.baseboard_fab2(sch_1):page34_i86@chpset_lib.skx_ext_b(chips)!SKX_EXT_B_BGA1-IC,TBD!!!F88!UPI1_TX_DN(16)!!!!
S!UPI_CPU0_CPU1_P1P1_DN<2>!U5D1!J20!@baseboard_fab2_lib.baseboard_fab2(sch_1):page34_i86@chpset_lib.skx_ext_b(chips)!SKX_EXT_B_BGA1-IC,TBD!!!F88!UPI1_TX_DN(17)!!!!
S!UPI_CPU0_CPU1_P1P1_DN<1>!U5D1!F21!@baseboard_fab2_lib.baseboard_fab2(sch_1):page34_i86@chpset_lib.skx_ext_b(chips)!SKX_EXT_B_BGA1-IC,TBD!!!F88!UPI1_TX_DN(18)!!!!
S!UPI_CPU0_CPU1_P1P1_DN<0>!U5D1!H21!@baseboard_fab2_lib.baseboard_fab2(sch_1):page34_i86@chpset_lib.skx_ext_b(chips)!SKX_EXT_B_BGA1-IC,TBD!!!F88!UPI1_TX_DN(19)!!!!
S!UPI_CPU0_CPU1_P1P1_DN<18>!U5D1!L4!@baseboard_fab2_lib.baseboard_fab2(sch_1):page34_i86@chpset_lib.skx_ext_b(chips)!SKX_EXT_B_BGA1-IC,TBD!!!F88!UPI1_TX_DN(1)!!!!
S!UPI_CPU0_CPU1_P1P1_DN<17>!U5D1!K5!@baseboard_fab2_lib.baseboard_fab2(sch_1):page34_i86@chpset_lib.skx_ext_b(chips)!SKX_EXT_B_BGA1-IC,TBD!!!F88!UPI1_TX_DN(2)!!!!
S!UPI_CPU0_CPU1_P1P1_DN<16>!U5D1!J6!@baseboard_fab2_lib.baseboard_fab2(sch_1):page34_i86@chpset_lib.skx_ext_b(chips)!SKX_EXT_B_BGA1-IC,TBD!!!F88!UPI1_TX_DN(3)!!!!
S!UPI_CPU0_CPU1_P1P1_DN<15>!U5D1!G6!@baseboard_fab2_lib.baseboard_fab2(sch_1):page34_i86@chpset_lib.skx_ext_b(chips)!SKX_EXT_B_BGA1-IC,TBD!!!F88!UPI1_TX_DN(4)!!!!
S!UPI_CPU0_CPU1_P1P1_DN<14>!U5D1!H7!@baseboard_fab2_lib.baseboard_fab2(sch_1):page34_i86@chpset_lib.skx_ext_b(chips)!SKX_EXT_B_BGA1-IC,TBD!!!F88!UPI1_TX_DN(5)!!!!
S!UPI_CPU0_CPU1_P1P1_DN<13>!U5D1!K9!@baseboard_fab2_lib.baseboard_fab2(sch_1):page34_i86@chpset_lib.skx_ext_b(chips)!SKX_EXT_B_BGA1-IC,TBD!!!F88!UPI1_TX_DN(6)!!!!
S!UPI_CPU0_CPU1_P1P1_DN<12>!U5D1!D9!@baseboard_fab2_lib.baseboard_fab2(sch_1):page34_i86@chpset_lib.skx_ext_b(chips)!SKX_EXT_B_BGA1-IC,TBD!!!F88!UPI1_TX_DN(7)!!!!
S!UPI_CPU0_CPU1_P1P1_DN<11>!U5D1!F11!@baseboard_fab2_lib.baseboard_fab2(sch_1):page34_i86@chpset_lib.skx_ext_b(chips)!SKX_EXT_B_BGA1-IC,TBD!!!F88!UPI1_TX_DN(8)!!!!
S!UPI_CPU0_CPU1_P1P1_DN<10>!U5D1!G10!@baseboard_fab2_lib.baseboard_fab2(sch_1):page34_i86@chpset_lib.skx_ext_b(chips)!SKX_EXT_B_BGA1-IC,TBD!!!F88!UPI1_TX_DN(9)!!!!
S!UPI_CPU0_CPU1_P1P1_DP<19>!U5D1!P3!@baseboard_fab2_lib.baseboard_fab2(sch_1):page34_i86@chpset_lib.skx_ext_b(chips)!SKX_EXT_B_BGA1-IC,TBD!!!F88!UPI1_TX_DP(0)!!!!
S!UPI_CPU0_CPU1_P1P1_DP<9>!U5D1!G12!@baseboard_fab2_lib.baseboard_fab2(sch_1):page34_i86@chpset_lib.skx_ext_b(chips)!SKX_EXT_B_BGA1-IC,TBD!!!F88!UPI1_TX_DP(10)!!!!
S!UPI_CPU0_CPU1_P1P1_DP<8>!U5D1!F13!@baseboard_fab2_lib.baseboard_fab2(sch_1):page34_i86@chpset_lib.skx_ext_b(chips)!SKX_EXT_B_BGA1-IC,TBD!!!F88!UPI1_TX_DP(11)!!!!
S!UPI_CPU0_CPU1_P1P1_DP<7>!U5D1!E14!@baseboard_fab2_lib.baseboard_fab2(sch_1):page34_i86@chpset_lib.skx_ext_b(chips)!SKX_EXT_B_BGA1-IC,TBD!!!F88!UPI1_TX_DP(12)!!!!
S!UPI_CPU0_CPU1_P1P1_DP<6>!U5D1!H15!@baseboard_fab2_lib.baseboard_fab2(sch_1):page34_i86@chpset_lib.skx_ext_b(chips)!SKX_EXT_B_BGA1-IC,TBD!!!F88!UPI1_TX_DP(13)!!!!
S!UPI_CPU0_CPU1_P1P1_DP<5>!U5D1!G16!@baseboard_fab2_lib.baseboard_fab2(sch_1):page34_i86@chpset_lib.skx_ext_b(chips)!SKX_EXT_B_BGA1-IC,TBD!!!F88!UPI1_TX_DP(14)!!!!
S!UPI_CPU0_CPU1_P1P1_DP<4>!U5D1!L18!@baseboard_fab2_lib.baseboard_fab2(sch_1):page34_i86@chpset_lib.skx_ext_b(chips)!SKX_EXT_B_BGA1-IC,TBD!!!F88!UPI1_TX_DP(15)!!!!
S!UPI_CPU0_CPU1_P1P1_DP<3>!U5D1!J18!@baseboard_fab2_lib.baseboard_fab2(sch_1):page34_i86@chpset_lib.skx_ext_b(chips)!SKX_EXT_B_BGA1-IC,TBD!!!F88!UPI1_TX_DP(16)!!!!
S!UPI_CPU0_CPU1_P1P1_DP<2>!U5D1!H19!@baseboard_fab2_lib.baseboard_fab2(sch_1):page34_i86@chpset_lib.skx_ext_b(chips)!SKX_EXT_B_BGA1-IC,TBD!!!F88!UPI1_TX_DP(17)!!!!
S!UPI_CPU0_CPU1_P1P1_DP<1>!U5D1!G20!@baseboard_fab2_lib.baseboard_fab2(sch_1):page34_i86@chpset_lib.skx_ext_b(chips)!SKX_EXT_B_BGA1-IC,TBD!!!F88!UPI1_TX_DP(18)!!!!
S!UPI_CPU0_CPU1_P1P1_DP<0>!U5D1!K21!@baseboard_fab2_lib.baseboard_fab2(sch_1):page34_i86@chpset_lib.skx_ext_b(chips)!SKX_EXT_B_BGA1-IC,TBD!!!F88!UPI1_TX_DP(19)!!!!
S!UPI_CPU0_CPU1_P1P1_DP<18>!U5D1!K3!@baseboard_fab2_lib.baseboard_fab2(sch_1):page34_i86@chpset_lib.skx_ext_b(chips)!SKX_EXT_B_BGA1-IC,TBD!!!F88!UPI1_TX_DP(1)!!!!
S!UPI_CPU0_CPU1_P1P1_DP<17>!U5D1!M5!@baseboard_fab2_lib.baseboard_fab2(sch_1):page34_i86@chpset_lib.skx_ext_b(chips)!SKX_EXT_B_BGA1-IC,TBD!!!F88!UPI1_TX_DP(2)!!!!
S!UPI_CPU0_CPU1_P1P1_DP<16>!U5D1!H5!@baseboard_fab2_lib.baseboard_fab2(sch_1):page34_i86@chpset_lib.skx_ext_b(chips)!SKX_EXT_B_BGA1-IC,TBD!!!F88!UPI1_TX_DP(3)!!!!
S!UPI_CPU0_CPU1_P1P1_DP<15>!U5D1!F7!@baseboard_fab2_lib.baseboard_fab2(sch_1):page34_i86@chpset_lib.skx_ext_b(chips)!SKX_EXT_B_BGA1-IC,TBD!!!F88!UPI1_TX_DP(4)!!!!
S!UPI_CPU0_CPU1_P1P1_DP<14>!U5D1!K7!@baseboard_fab2_lib.baseboard_fab2(sch_1):page34_i86@chpset_lib.skx_ext_b(chips)!SKX_EXT_B_BGA1-IC,TBD!!!F88!UPI1_TX_DP(5)!!!!
S!UPI_CPU0_CPU1_P1P1_DP<13>!U5D1!J8!@baseboard_fab2_lib.baseboard_fab2(sch_1):page34_i86@chpset_lib.skx_ext_b(chips)!SKX_EXT_B_BGA1-IC,TBD!!!F88!UPI1_TX_DP(6)!!!!
S!UPI_CPU0_CPU1_P1P1_DP<12>!U5D1!F9!@baseboard_fab2_lib.baseboard_fab2(sch_1):page34_i86@chpset_lib.skx_ext_b(chips)!SKX_EXT_B_BGA1-IC,TBD!!!F88!UPI1_TX_DP(7)!!!!
S!UPI_CPU0_CPU1_P1P1_DP<11>!U5D1!E10!@baseboard_fab2_lib.baseboard_fab2(sch_1):page34_i86@chpset_lib.skx_ext_b(chips)!SKX_EXT_B_BGA1-IC,TBD!!!F88!UPI1_TX_DP(8)!!!!
S!UPI_CPU0_CPU1_P1P1_DP<10>!U5D1!H9!@baseboard_fab2_lib.baseboard_fab2(sch_1):page34_i86@chpset_lib.skx_ext_b(chips)!SKX_EXT_B_BGA1-IC,TBD!!!F88!UPI1_TX_DP(9)!!!!
S!GND!U5D1!BY17!@baseboard_fab2_lib.baseboard_fab2(sch_1):page35_i3@chpset_lib.skx_ext_b(chips)!SKX_EXT_B_BGA1-IC,TBD!!!F87!UPI2_RX_DN(19)!!!!
S!GND!U5D1!CR18!@baseboard_fab2_lib.baseboard_fab2(sch_1):page35_i3@chpset_lib.skx_ext_b(chips)!SKX_EXT_B_BGA1-IC,TBD!!!F87!UPI2_RX_DN(9)!!!!
S!GND!U5D1!CT21!@baseboard_fab2_lib.baseboard_fab2(sch_1):page35_i3@chpset_lib.skx_ext_b(chips)!SKX_EXT_B_BGA1-IC,TBD!!!F87!UPI2_RX_DN(8)!!!!
S!GND!U5D1!CV19!@baseboard_fab2_lib.baseboard_fab2(sch_1):page35_i3@chpset_lib.skx_ext_b(chips)!SKX_EXT_B_BGA1-IC,TBD!!!F87!UPI2_RX_DN(7)!!!!
S!GND!U5D1!CW20!@baseboard_fab2_lib.baseboard_fab2(sch_1):page35_i3@chpset_lib.skx_ext_b(chips)!SKX_EXT_B_BGA1-IC,TBD!!!F87!UPI2_RX_DN(6)!!!!
S!GND!U5D1!DA20!@baseboard_fab2_lib.baseboard_fab2(sch_1):page35_i3@chpset_lib.skx_ext_b(chips)!SKX_EXT_B_BGA1-IC,TBD!!!F87!UPI2_RX_DN(5)!!!!
S!GND!U5D1!DD19!@baseboard_fab2_lib.baseboard_fab2(sch_1):page35_i3@chpset_lib.skx_ext_b(chips)!SKX_EXT_B_BGA1-IC,TBD!!!F87!UPI2_RX_DN(4)!!!!
S!GND!U5D1!DB21!@baseboard_fab2_lib.baseboard_fab2(sch_1):page35_i3@chpset_lib.skx_ext_b(chips)!SKX_EXT_B_BGA1-IC,TBD!!!F87!UPI2_RX_DN(3)!!!!
S!GND!U5D1!DC22!@baseboard_fab2_lib.baseboard_fab2(sch_1):page35_i3@chpset_lib.skx_ext_b(chips)!SKX_EXT_B_BGA1-IC,TBD!!!F87!UPI2_RX_DN(2)!!!!
S!GND!U5D1!DE22!@baseboard_fab2_lib.baseboard_fab2(sch_1):page35_i3@chpset_lib.skx_ext_b(chips)!SKX_EXT_B_BGA1-IC,TBD!!!F87!UPI2_RX_DN(1)!!!!
S!GND!U5D1!DF23!@baseboard_fab2_lib.baseboard_fab2(sch_1):page35_i3@chpset_lib.skx_ext_b(chips)!SKX_EXT_B_BGA1-IC,TBD!!!F87!UPI2_RX_DN(0)!!!!
S!GND!U5D1!CB15!@baseboard_fab2_lib.baseboard_fab2(sch_1):page35_i3@chpset_lib.skx_ext_b(chips)!SKX_EXT_B_BGA1-IC,TBD!!!F87!UPI2_RX_DN(18)!!!!
S!GND!U5D1!CF17!@baseboard_fab2_lib.baseboard_fab2(sch_1):page35_i3@chpset_lib.skx_ext_b(chips)!SKX_EXT_B_BGA1-IC,TBD!!!F87!UPI2_RX_DN(17)!!!!
S!GND!U5D1!CD15!@baseboard_fab2_lib.baseboard_fab2(sch_1):page35_i3@chpset_lib.skx_ext_b(chips)!SKX_EXT_B_BGA1-IC,TBD!!!F87!UPI2_RX_DN(16)!!!!
S!GND!U5D1!CE16!@baseboard_fab2_lib.baseboard_fab2(sch_1):page35_i3@chpset_lib.skx_ext_b(chips)!SKX_EXT_B_BGA1-IC,TBD!!!F87!UPI2_RX_DN(15)!!!!
S!GND!U5D1!CH17!@baseboard_fab2_lib.baseboard_fab2(sch_1):page35_i3@chpset_lib.skx_ext_b(chips)!SKX_EXT_B_BGA1-IC,TBD!!!F87!UPI2_RX_DN(14)!!!!
S!GND!U5D1!CJ18!@baseboard_fab2_lib.baseboard_fab2(sch_1):page35_i3@chpset_lib.skx_ext_b(chips)!SKX_EXT_B_BGA1-IC,TBD!!!F87!UPI2_RX_DN(13)!!!!
S!GND!U5D1!CL16!@baseboard_fab2_lib.baseboard_fab2(sch_1):page35_i3@chpset_lib.skx_ext_b(chips)!SKX_EXT_B_BGA1-IC,TBD!!!F87!UPI2_RX_DN(12)!!!!
S!GND!U5D1!CP21!@baseboard_fab2_lib.baseboard_fab2(sch_1):page35_i3@chpset_lib.skx_ext_b(chips)!SKX_EXT_B_BGA1-IC,TBD!!!F87!UPI2_RX_DN(11)!!!!
S!GND!U5D1!CN20!@baseboard_fab2_lib.baseboard_fab2(sch_1):page35_i3@chpset_lib.skx_ext_b(chips)!SKX_EXT_B_BGA1-IC,TBD!!!F87!UPI2_RX_DN(10)!!!!
S!GND!U5D1!CA16!@baseboard_fab2_lib.baseboard_fab2(sch_1):page35_i3@chpset_lib.skx_ext_b(chips)!SKX_EXT_B_BGA1-IC,TBD!!!F87!UPI2_RX_DP(19)!!!!
S!GND!U5D1!CN18!@baseboard_fab2_lib.baseboard_fab2(sch_1):page35_i3@chpset_lib.skx_ext_b(chips)!SKX_EXT_B_BGA1-IC,TBD!!!F87!UPI2_RX_DP(9)!!!!
S!GND!U5D1!CR20!@baseboard_fab2_lib.baseboard_fab2(sch_1):page35_i3@chpset_lib.skx_ext_b(chips)!SKX_EXT_B_BGA1-IC,TBD!!!F87!UPI2_RX_DP(8)!!!!
S!GND!U5D1!CW18!@baseboard_fab2_lib.baseboard_fab2(sch_1):page35_i3@chpset_lib.skx_ext_b(chips)!SKX_EXT_B_BGA1-IC,TBD!!!F87!UPI2_RX_DP(7)!!!!
S!GND!U5D1!CU20!@baseboard_fab2_lib.baseboard_fab2(sch_1):page35_i3@chpset_lib.skx_ext_b(chips)!SKX_EXT_B_BGA1-IC,TBD!!!F87!UPI2_RX_DP(6)!!!!
S!GND!U5D1!CY19!@baseboard_fab2_lib.baseboard_fab2(sch_1):page35_i3@chpset_lib.skx_ext_b(chips)!SKX_EXT_B_BGA1-IC,TBD!!!F87!UPI2_RX_DP(5)!!!!
S!GND!U5D1!DB19!@baseboard_fab2_lib.baseboard_fab2(sch_1):page35_i3@chpset_lib.skx_ext_b(chips)!SKX_EXT_B_BGA1-IC,TBD!!!F87!UPI2_RX_DP(4)!!!!
S!GND!U5D1!DC20!@baseboard_fab2_lib.baseboard_fab2(sch_1):page35_i3@chpset_lib.skx_ext_b(chips)!SKX_EXT_B_BGA1-IC,TBD!!!F87!UPI2_RX_DP(3)!!!!
S!GND!U5D1!DA22!@baseboard_fab2_lib.baseboard_fab2(sch_1):page35_i3@chpset_lib.skx_ext_b(chips)!SKX_EXT_B_BGA1-IC,TBD!!!F87!UPI2_RX_DP(2)!!!!
S!GND!U5D1!DD21!@baseboard_fab2_lib.baseboard_fab2(sch_1):page35_i3@chpset_lib.skx_ext_b(chips)!SKX_EXT_B_BGA1-IC,TBD!!!F87!UPI2_RX_DP(1)!!!!
S!GND!U5D1!DG22!@baseboard_fab2_lib.baseboard_fab2(sch_1):page35_i3@chpset_lib.skx_ext_b(chips)!SKX_EXT_B_BGA1-IC,TBD!!!F87!UPI2_RX_DP(0)!!!!
S!GND!U5D1!BY15!@baseboard_fab2_lib.baseboard_fab2(sch_1):page35_i3@chpset_lib.skx_ext_b(chips)!SKX_EXT_B_BGA1-IC,TBD!!!F87!UPI2_RX_DP(18)!!!!
S!GND!U5D1!CD17!@baseboard_fab2_lib.baseboard_fab2(sch_1):page35_i3@chpset_lib.skx_ext_b(chips)!SKX_EXT_B_BGA1-IC,TBD!!!F87!UPI2_RX_DP(17)!!!!
S!GND!U5D1!CC14!@baseboard_fab2_lib.baseboard_fab2(sch_1):page35_i3@chpset_lib.skx_ext_b(chips)!SKX_EXT_B_BGA1-IC,TBD!!!F87!UPI2_RX_DP(16)!!!!
S!GND!U5D1!CF15!@baseboard_fab2_lib.baseboard_fab2(sch_1):page35_i3@chpset_lib.skx_ext_b(chips)!SKX_EXT_B_BGA1-IC,TBD!!!F87!UPI2_RX_DP(15)!!!!
S!GND!U5D1!CG16!@baseboard_fab2_lib.baseboard_fab2(sch_1):page35_i3@chpset_lib.skx_ext_b(chips)!SKX_EXT_B_BGA1-IC,TBD!!!F87!UPI2_RX_DP(14)!!!!
S!GND!U5D1!CK17!@baseboard_fab2_lib.baseboard_fab2(sch_1):page35_i3@chpset_lib.skx_ext_b(chips)!SKX_EXT_B_BGA1-IC,TBD!!!F87!UPI2_RX_DP(13)!!!!
S!GND!U5D1!CJ16!@baseboard_fab2_lib.baseboard_fab2(sch_1):page35_i3@chpset_lib.skx_ext_b(chips)!SKX_EXT_B_BGA1-IC,TBD!!!F87!UPI2_RX_DP(12)!!!!
S!GND!U5D1!CM21!@baseboard_fab2_lib.baseboard_fab2(sch_1):page35_i3@chpset_lib.skx_ext_b(chips)!SKX_EXT_B_BGA1-IC,TBD!!!F87!UPI2_RX_DP(11)!!!!
S!GND!U5D1!CP19!@baseboard_fab2_lib.baseboard_fab2(sch_1):page35_i3@chpset_lib.skx_ext_b(chips)!SKX_EXT_B_BGA1-IC,TBD!!!F87!UPI2_RX_DP(10)!!!!
S!TP_CPU0_UPI2_RSVD_DT21!U5D1!CC12!@baseboard_fab2_lib.baseboard_fab2(sch_1):page35_i3@chpset_lib.skx_ext_b(chips)!SKX_EXT_B_BGA1-IC,TBD!!!F87!UPI2_TX_DN(19)!!!!
S!TP_CPU0_UPI2_RSVD_DA16!U5D1!DC16!@baseboard_fab2_lib.baseboard_fab2(sch_1):page35_i3@chpset_lib.skx_ext_b(chips)!SKX_EXT_B_BGA1-IC,TBD!!!F87!UPI2_TX_DN(9)!!!!
S!TP_CPU0_UPI2_RSVD_CW14!U5D1!DF15!@baseboard_fab2_lib.baseboard_fab2(sch_1):page35_i3@chpset_lib.skx_ext_b(chips)!SKX_EXT_B_BGA1-IC,TBD!!!F87!UPI2_TX_DN(8)!!!!
S!TP_CPU0_UPI2_RSVD_CU14!U5D1!DD17!@baseboard_fab2_lib.baseboard_fab2(sch_1):page35_i3@chpset_lib.skx_ext_b(chips)!SKX_EXT_B_BGA1-IC,TBD!!!F87!UPI2_TX_DN(7)!!!!
S!TP_CPU0_UPI2_RSVD_CM13!U5D1!DG18!@baseboard_fab2_lib.baseboard_fab2(sch_1):page35_i3@chpset_lib.skx_ext_b(chips)!SKX_EXT_B_BGA1-IC,TBD!!!F87!UPI2_TX_DN(6)!!!!
S!TP_CPU0_UPI2_RSVD_CJ14!U5D1!DK17!@baseboard_fab2_lib.baseboard_fab2(sch_1):page35_i3@chpset_lib.skx_ext_b(chips)!SKX_EXT_B_BGA1-IC,TBD!!!F87!UPI2_TX_DN(5)!!!!
S!TP_CPU0_UPI2_RSVD_CF13!U5D1!DH19!@baseboard_fab2_lib.baseboard_fab2(sch_1):page35_i3@chpset_lib.skx_ext_b(chips)!SKX_EXT_B_BGA1-IC,TBD!!!F87!UPI2_TX_DN(4)!!!!
S!TP_CPU0_UPI2_RSVD_CH11!U5D1!DG20!@baseboard_fab2_lib.baseboard_fab2(sch_1):page35_i3@chpset_lib.skx_ext_b(chips)!SKX_EXT_B_BGA1-IC,TBD!!!F87!UPI2_TX_DN(3)!!!!
S!TP_CPU0_UPI2_RSVD_CE12!U5D1!DL20!@baseboard_fab2_lib.baseboard_fab2(sch_1):page35_i3@chpset_lib.skx_ext_b(chips)!SKX_EXT_B_BGA1-IC,TBD!!!F87!UPI2_TX_DN(2)!!!!
S!TP_CPU0_UPI2_RSVD_CC10!U5D1!DM21!@baseboard_fab2_lib.baseboard_fab2(sch_1):page35_i3@chpset_lib.skx_ext_b(chips)!SKX_EXT_B_BGA1-IC,TBD!!!F87!UPI2_TX_DN(1)!!!!
S!TP_CPU0_UPI2_RSVD_CC12!U5D1!DT21!@baseboard_fab2_lib.baseboard_fab2(sch_1):page35_i3@chpset_lib.skx_ext_b(chips)!SKX_EXT_B_BGA1-IC,TBD!!!F87!UPI2_TX_DN(0)!!!!
S!TP_CPU0_UPI2_RSVD_DM21!U5D1!CC10!@baseboard_fab2_lib.baseboard_fab2(sch_1):page35_i3@chpset_lib.skx_ext_b(chips)!SKX_EXT_B_BGA1-IC,TBD!!!F87!UPI2_TX_DN(18)!!!!
S!TP_CPU0_UPI2_RSVD_DL20!U5D1!CE12!@baseboard_fab2_lib.baseboard_fab2(sch_1):page35_i3@chpset_lib.skx_ext_b(chips)!SKX_EXT_B_BGA1-IC,TBD!!!F87!UPI2_TX_DN(17)!!!!
S!TP_CPU0_UPI2_RSVD_DG20!U5D1!CH11!@baseboard_fab2_lib.baseboard_fab2(sch_1):page35_i3@chpset_lib.skx_ext_b(chips)!SKX_EXT_B_BGA1-IC,TBD!!!F87!UPI2_TX_DN(16)!!!!
S!TP_CPU0_UPI2_RSVD_DH19!U5D1!CF13!@baseboard_fab2_lib.baseboard_fab2(sch_1):page35_i3@chpset_lib.skx_ext_b(chips)!SKX_EXT_B_BGA1-IC,TBD!!!F87!UPI2_TX_DN(15)!!!!
S!TP_CPU0_UPI2_RSVD_DK17!U5D1!CJ14!@baseboard_fab2_lib.baseboard_fab2(sch_1):page35_i3@chpset_lib.skx_ext_b(chips)!SKX_EXT_B_BGA1-IC,TBD!!!F87!UPI2_TX_DN(14)!!!!
S!TP_CPU0_UPI2_RSVD_DG18!U5D1!CM13!@baseboard_fab2_lib.baseboard_fab2(sch_1):page35_i3@chpset_lib.skx_ext_b(chips)!SKX_EXT_B_BGA1-IC,TBD!!!F87!UPI2_TX_DN(13)!!!!
S!TP_CPU0_UPI2_RSVD_DD17!U5D1!CU14!@baseboard_fab2_lib.baseboard_fab2(sch_1):page35_i3@chpset_lib.skx_ext_b(chips)!SKX_EXT_B_BGA1-IC,TBD!!!F87!UPI2_TX_DN(12)!!!!
S!TP_CPU0_UPI2_RSVD_DF15!U5D1!CW14!@baseboard_fab2_lib.baseboard_fab2(sch_1):page35_i3@chpset_lib.skx_ext_b(chips)!SKX_EXT_B_BGA1-IC,TBD!!!F87!UPI2_TX_DN(11)!!!!
S!TP_CPU0_UPI2_RSVD_DC16!U5D1!DA16!@baseboard_fab2_lib.baseboard_fab2(sch_1):page35_i3@chpset_lib.skx_ext_b(chips)!SKX_EXT_B_BGA1-IC,TBD!!!F87!UPI2_TX_DN(10)!!!!
S!TP_CPU0_UPI2_RSVD_DP21!U5D1!CA12!@baseboard_fab2_lib.baseboard_fab2(sch_1):page35_i3@chpset_lib.skx_ext_b(chips)!SKX_EXT_B_BGA1-IC,TBD!!!F87!UPI2_TX_DP(19)!!!!
S!TP_CPU0_UPI2_RSVD_CW16!U5D1!DB15!@baseboard_fab2_lib.baseboard_fab2(sch_1):page35_i3@chpset_lib.skx_ext_b(chips)!SKX_EXT_B_BGA1-IC,TBD!!!F87!UPI2_TX_DP(9)!!!!
S!TP_CPU0_UPI2_RSVD_CV13!U5D1!DD15!@baseboard_fab2_lib.baseboard_fab2(sch_1):page35_i3@chpset_lib.skx_ext_b(chips)!SKX_EXT_B_BGA1-IC,TBD!!!F87!UPI2_TX_DP(8)!!!!
S!TP_CPU0_UPI2_RSVD_CR14!U5D1!DE16!@baseboard_fab2_lib.baseboard_fab2(sch_1):page35_i3@chpset_lib.skx_ext_b(chips)!SKX_EXT_B_BGA1-IC,TBD!!!F87!UPI2_TX_DP(7)!!!!
S!TP_CPU0_UPI2_RSVD_CK13!U5D1!DF17!@baseboard_fab2_lib.baseboard_fab2(sch_1):page35_i3@chpset_lib.skx_ext_b(chips)!SKX_EXT_B_BGA1-IC,TBD!!!F87!UPI2_TX_DP(6)!!!!
S!TP_CPU0_UPI2_RSVD_CH13!U5D1!DH17!@baseboard_fab2_lib.baseboard_fab2(sch_1):page35_i3@chpset_lib.skx_ext_b(chips)!SKX_EXT_B_BGA1-IC,TBD!!!F87!UPI2_TX_DP(5)!!!!
S!TP_CPU0_UPI2_RSVD_CG12!U5D1!DJ18!@baseboard_fab2_lib.baseboard_fab2(sch_1):page35_i3@chpset_lib.skx_ext_b(chips)!SKX_EXT_B_BGA1-IC,TBD!!!F87!UPI2_TX_DP(4)!!!!
S!TP_CPU0_UPI2_RSVD_CF11!U5D1!DJ20!@baseboard_fab2_lib.baseboard_fab2(sch_1):page35_i3@chpset_lib.skx_ext_b(chips)!SKX_EXT_B_BGA1-IC,TBD!!!F87!UPI2_TX_DP(3)!!!!
S!TP_CPU0_UPI2_RSVD_CD11!U5D1!DK19!@baseboard_fab2_lib.baseboard_fab2(sch_1):page35_i3@chpset_lib.skx_ext_b(chips)!SKX_EXT_B_BGA1-IC,TBD!!!F87!UPI2_TX_DP(2)!!!!
S!TP_CPU0_UPI2_RSVD_CB11!U5D1!DN20!@baseboard_fab2_lib.baseboard_fab2(sch_1):page35_i3@chpset_lib.skx_ext_b(chips)!SKX_EXT_B_BGA1-IC,TBD!!!F87!UPI2_TX_DP(1)!!!!
S!TP_CPU0_UPI2_RSVD_CA12!U5D1!DP21!@baseboard_fab2_lib.baseboard_fab2(sch_1):page35_i3@chpset_lib.skx_ext_b(chips)!SKX_EXT_B_BGA1-IC,TBD!!!F87!UPI2_TX_DP(0)!!!!
S!TP_CPU0_UPI2_RSVD_DN20!U5D1!CB11!@baseboard_fab2_lib.baseboard_fab2(sch_1):page35_i3@chpset_lib.skx_ext_b(chips)!SKX_EXT_B_BGA1-IC,TBD!!!F87!UPI2_TX_DP(18)!!!!
S!TP_CPU0_UPI2_RSVD_DK19!U5D1!CD11!@baseboard_fab2_lib.baseboard_fab2(sch_1):page35_i3@chpset_lib.skx_ext_b(chips)!SKX_EXT_B_BGA1-IC,TBD!!!F87!UPI2_TX_DP(17)!!!!
S!TP_CPU0_UPI2_RSVD_DJ20!U5D1!CF11!@baseboard_fab2_lib.baseboard_fab2(sch_1):page35_i3@chpset_lib.skx_ext_b(chips)!SKX_EXT_B_BGA1-IC,TBD!!!F87!UPI2_TX_DP(16)!!!!
S!TP_CPU0_UPI2_RSVD_DJ18!U5D1!CG12!@baseboard_fab2_lib.baseboard_fab2(sch_1):page35_i3@chpset_lib.skx_ext_b(chips)!SKX_EXT_B_BGA1-IC,TBD!!!F87!UPI2_TX_DP(15)!!!!
S!TP_CPU0_UPI2_RSVD_DH17!U5D1!CH13!@baseboard_fab2_lib.baseboard_fab2(sch_1):page35_i3@chpset_lib.skx_ext_b(chips)!SKX_EXT_B_BGA1-IC,TBD!!!F87!UPI2_TX_DP(14)!!!!
S!TP_CPU0_UPI2_RSVD_DF17!U5D1!CK13!@baseboard_fab2_lib.baseboard_fab2(sch_1):page35_i3@chpset_lib.skx_ext_b(chips)!SKX_EXT_B_BGA1-IC,TBD!!!F87!UPI2_TX_DP(13)!!!!
S!TP_CPU0_UPI2_RSVD_DE16!U5D1!CR14!@baseboard_fab2_lib.baseboard_fab2(sch_1):page35_i3@chpset_lib.skx_ext_b(chips)!SKX_EXT_B_BGA1-IC,TBD!!!F87!UPI2_TX_DP(12)!!!!
S!TP_CPU0_UPI2_RSVD_DD15!U5D1!CV13!@baseboard_fab2_lib.baseboard_fab2(sch_1):page35_i3@chpset_lib.skx_ext_b(chips)!SKX_EXT_B_BGA1-IC,TBD!!!F87!UPI2_TX_DP(11)!!!!
S!TP_CPU0_UPI2_RSVD_DB15!U5D1!CW16!@baseboard_fab2_lib.baseboard_fab2(sch_1):page35_i3@chpset_lib.skx_ext_b(chips)!SKX_EXT_B_BGA1-IC,TBD!!!F87!UPI2_TX_DP(10)!!!!
S!TP_CPU0_RSVD_2!U5D1!EF77!@baseboard_fab2_lib.baseboard_fab2(sch_1):page39_i127@chpset_lib.skx_ext_b(chips)!SKX_EXT_B_BGA1-IC,TBD!!!F80!RSVD(2)!!!!
S!TP_CPU0_RSVD_267!U5D1!K61!@baseboard_fab2_lib.baseboard_fab2(sch_1):page22_i204@chpset_lib.skx_ext_b(chips)!SKX_EXT_B_BGA1-IC,TBD!!!F100!RSVD(267)!!!!
S!TP_CPU0_RSVD_268!U5D1!J62!@baseboard_fab2_lib.baseboard_fab2(sch_1):page22_i204@chpset_lib.skx_ext_b(chips)!SKX_EXT_B_BGA1-IC,TBD!!!F100!RSVD(268)!!!!
S!TP_CPU0_RSVD_269!U5D1!J46!@baseboard_fab2_lib.baseboard_fab2(sch_1):page22_i204@chpset_lib.skx_ext_b(chips)!SKX_EXT_B_BGA1-IC,TBD!!!F100!RSVD(269)!!!!
S!TP_CPU0_RSVD_271!U5D1!H83!@baseboard_fab2_lib.baseboard_fab2(sch_1):page22_i204@chpset_lib.skx_ext_b(chips)!SKX_EXT_B_BGA1-IC,TBD!!!F100!RSVD(271)!!!!
S!TP_CPU0_RSVD_274!U5D1!G64!@baseboard_fab2_lib.baseboard_fab2(sch_1):page22_i204@chpset_lib.skx_ext_b(chips)!SKX_EXT_B_BGA1-IC,TBD!!!F100!RSVD(274)!!!!
S!TP_CPU0_RSVD_277!U5D1!F65!@baseboard_fab2_lib.baseboard_fab2(sch_1):page22_i204@chpset_lib.skx_ext_b(chips)!SKX_EXT_B_BGA1-IC,TBD!!!F100!RSVD(277)!!!!
S!GND!U5D1!E66!@baseboard_fab2_lib.baseboard_fab2(sch_1):page40_i20@chpset_lib.skx_ext_b(chips)!SKX_EXT_B_BGA1-IC,TBD!!!F79!VSS(1228)!!!!
S!TP_CPU0_RSVD_285!U5D1!D65!@baseboard_fab2_lib.baseboard_fab2(sch_1):page22_i204@chpset_lib.skx_ext_b(chips)!SKX_EXT_B_BGA1-IC,TBD!!!F100!RSVD(285)!!!!
S!TP_CPU0_RSVD_293!U5D1!B77!@baseboard_fab2_lib.baseboard_fab2(sch_1):page22_i204@chpset_lib.skx_ext_b(chips)!SKX_EXT_B_BGA1-IC,TBD!!!F100!RSVD(293)!!!!
S!GND!U5D1!B9!@baseboard_fab2_lib.baseboard_fab2(sch_1):page40_i20@chpset_lib.skx_ext_b(chips)!SKX_EXT_B_BGA1-IC,TBD!!!F79!VSS(1253)!!!!
S!TP_CPU0_RSVD_26!U5D1!DU44!@baseboard_fab2_lib.baseboard_fab2(sch_1):page39_i127@chpset_lib.skx_ext_b(chips)!SKX_EXT_B_BGA1-IC,TBD!!!F80!RSVD(26)!!!!
S!TP_CPU0_RSVD_28!U5D1!DR44!@baseboard_fab2_lib.baseboard_fab2(sch_1):page39_i127@chpset_lib.skx_ext_b(chips)!SKX_EXT_B_BGA1-IC,TBD!!!F80!RSVD(28)!!!!
S!TP_CPU0_RSVD_29!U5D1!DP65!@baseboard_fab2_lib.baseboard_fab2(sch_1):page39_i127@chpset_lib.skx_ext_b(chips)!SKX_EXT_B_BGA1-IC,TBD!!!F80!RSVD(29)!!!!
S!TP_CPU0_RSVD_32!U5D1!DN62!@baseboard_fab2_lib.baseboard_fab2(sch_1):page39_i127@chpset_lib.skx_ext_b(chips)!SKX_EXT_B_BGA1-IC,TBD!!!F80!RSVD(32)!!!!
S!TP_CPU0_RSVD_34!U5D1!DL66!@baseboard_fab2_lib.baseboard_fab2(sch_1):page39_i127@chpset_lib.skx_ext_b(chips)!SKX_EXT_B_BGA1-IC,TBD!!!F80!RSVD(34)!!!!
S!TP_CPU0_RSVD_36!U5D1!DK67!@baseboard_fab2_lib.baseboard_fab2(sch_1):page39_i127@chpset_lib.skx_ext_b(chips)!SKX_EXT_B_BGA1-IC,TBD!!!F80!RSVD(36)!!!!
S!TP_CPU0_RSVD_37!U5D1!DK65!@baseboard_fab2_lib.baseboard_fab2(sch_1):page39_i127@chpset_lib.skx_ext_b(chips)!SKX_EXT_B_BGA1-IC,TBD!!!F80!RSVD(37)!!!!
S!TP_CPU0_RSVD_40!U5D1!DJ66!@baseboard_fab2_lib.baseboard_fab2(sch_1):page39_i127@chpset_lib.skx_ext_b(chips)!SKX_EXT_B_BGA1-IC,TBD!!!F80!RSVD(40)!!!!
S!TP_CPU0_RSVD_42!U5D1!DH65!@baseboard_fab2_lib.baseboard_fab2(sch_1):page39_i127@chpset_lib.skx_ext_b(chips)!SKX_EXT_B_BGA1-IC,TBD!!!F80!RSVD(42)!!!!
S!TP_CPU0_RSVD_43!U5D1!DG64!@baseboard_fab2_lib.baseboard_fab2(sch_1):page39_i127@chpset_lib.skx_ext_b(chips)!SKX_EXT_B_BGA1-IC,TBD!!!F80!RSVD(43)!!!!
S!TP_CPU0_RSVD_3!U5D1!EF47!@baseboard_fab2_lib.baseboard_fab2(sch_1):page39_i127@chpset_lib.skx_ext_b(chips)!SKX_EXT_B_BGA1-IC,TBD!!!F80!RSVD(3)!!!!
S!TP_CPU0_RSVD_45!U5D1!DD51!@baseboard_fab2_lib.baseboard_fab2(sch_1):page39_i127@chpset_lib.skx_ext_b(chips)!SKX_EXT_B_BGA1-IC,TBD!!!F80!RSVD(45)!!!!
S!TP_CPU0_RSVD_46!U5D1!DC52!@baseboard_fab2_lib.baseboard_fab2(sch_1):page39_i127@chpset_lib.skx_ext_b(chips)!SKX_EXT_B_BGA1-IC,TBD!!!F80!RSVD(46)!!!!
S!TP_CPU0_RSVD_47!U5D1!DC46!@baseboard_fab2_lib.baseboard_fab2(sch_1):page39_i127@chpset_lib.skx_ext_b(chips)!SKX_EXT_B_BGA1-IC,TBD!!!F80!RSVD(47)!!!!
S!TP_CPU0_RSVD_48!U5D1!DA56!@baseboard_fab2_lib.baseboard_fab2(sch_1):page39_i127@chpset_lib.skx_ext_b(chips)!SKX_EXT_B_BGA1-IC,TBD!!!F80!RSVD(48)!!!!
S!TP_CPU0_RSVD_49!U5D1!DA54!@baseboard_fab2_lib.baseboard_fab2(sch_1):page39_i127@chpset_lib.skx_ext_b(chips)!SKX_EXT_B_BGA1-IC,TBD!!!F80!RSVD(49)!!!!
S!TP_CPU0_RSVD_53!U5D1!CY73!@baseboard_fab2_lib.baseboard_fab2(sch_1):page39_i127@chpset_lib.skx_ext_b(chips)!SKX_EXT_B_BGA1-IC,TBD!!!F80!RSVD(53)!!!!
S!TP_CPU0_RSVD_54!U5D1!CY63!@baseboard_fab2_lib.baseboard_fab2(sch_1):page39_i127@chpset_lib.skx_ext_b(chips)!SKX_EXT_B_BGA1-IC,TBD!!!F80!RSVD(54)!!!!
S!TP_CPU0_RSVD_55!U5D1!CY57!@baseboard_fab2_lib.baseboard_fab2(sch_1):page39_i127@chpset_lib.skx_ext_b(chips)!SKX_EXT_B_BGA1-IC,TBD!!!F80!RSVD(55)!!!!
S!TP_CPU0_RSVD_60!U5D1!CW62!@baseboard_fab2_lib.baseboard_fab2(sch_1):page39_i127@chpset_lib.skx_ext_b(chips)!SKX_EXT_B_BGA1-IC,TBD!!!F80!RSVD(60)!!!!
S!TP_CPU0_RSVD_61!U5D1!CW60!@baseboard_fab2_lib.baseboard_fab2(sch_1):page39_i127@chpset_lib.skx_ext_b(chips)!SKX_EXT_B_BGA1-IC,TBD!!!F80!RSVD(61)!!!!
S!TP_CPU0_RSVD_7!U5D1!EE46!@baseboard_fab2_lib.baseboard_fab2(sch_1):page39_i127@chpset_lib.skx_ext_b(chips)!SKX_EXT_B_BGA1-IC,TBD!!!F80!RSVD(7)!!!!
S!TP_CPU0_RSVD_64!U5D1!CV69!@baseboard_fab2_lib.baseboard_fab2(sch_1):page39_i127@chpset_lib.skx_ext_b(chips)!SKX_EXT_B_BGA1-IC,TBD!!!F80!RSVD(64)!!!!
S!TP_CPU0_RSVD_66!U5D1!CU60!@baseboard_fab2_lib.baseboard_fab2(sch_1):page39_i127@chpset_lib.skx_ext_b(chips)!SKX_EXT_B_BGA1-IC,TBD!!!F80!RSVD(66)!!!!
S!TP_CPU0_RSVD_69!U5D1!CT69!@baseboard_fab2_lib.baseboard_fab2(sch_1):page39_i127@chpset_lib.skx_ext_b(chips)!SKX_EXT_B_BGA1-IC,TBD!!!F80!RSVD(69)!!!!
S!TP_CPU0_RSVD_72!U5D1!CR60!@baseboard_fab2_lib.baseboard_fab2(sch_1):page39_i127@chpset_lib.skx_ext_b(chips)!SKX_EXT_B_BGA1-IC,TBD!!!F80!RSVD(72)!!!!
S!TP_CPU0_RSVD_73!U5D1!CP31!@baseboard_fab2_lib.baseboard_fab2(sch_1):page39_i127@chpset_lib.skx_ext_b(chips)!SKX_EXT_B_BGA1-IC,TBD!!!F80!RSVD(73)!!!!
S!TP_CPU0_RSVD_82!U5D1!CK77!@baseboard_fab2_lib.baseboard_fab2(sch_1):page36_i16@chpset_lib.skx_ext_b(chips)!SKX_EXT_B_BGA1-IC,TBD!!!F85!RSVD(82)!!!!
S!TP_CPU0_RSVD_90!U5D1!CH77!@baseboard_fab2_lib.baseboard_fab2(sch_1):page36_i16@chpset_lib.skx_ext_b(chips)!SKX_EXT_B_BGA1-IC,TBD!!!F85!RSVD(90)!!!!
S!TP_CPU0_RSVD_94!U5D1!CG82!@baseboard_fab2_lib.baseboard_fab2(sch_1):page36_i15@chpset_lib.skx_ext_b(chips)!SKX_EXT_B_BGA1-IC,TBD!!!F86!RSVD(94)!!!!
S!TP_CPU0_RSVD_95!U5D1!CG78!@baseboard_fab2_lib.baseboard_fab2(sch_1):page36_i15@chpset_lib.skx_ext_b(chips)!SKX_EXT_B_BGA1-IC,TBD!!!F86!RSVD(95)!!!!
S!TP_CPU0_RSVD_100!U5D1!CF81!@baseboard_fab2_lib.baseboard_fab2(sch_1):page36_i15@chpset_lib.skx_ext_b(chips)!SKX_EXT_B_BGA1-IC,TBD!!!F86!RSVD(100)!!!!
S!GND!U5D1!ED69!@baseboard_fab2_lib.baseboard_fab2(sch_1):page40_i20@chpset_lib.skx_ext_b(chips)!SKX_EXT_B_BGA1-IC,TBD!!!F79!VSS(1229)!!!!
S!TP_CPU0_RSVD_101!U5D1!CF79!@baseboard_fab2_lib.baseboard_fab2(sch_1):page36_i15@chpset_lib.skx_ext_b(chips)!SKX_EXT_B_BGA1-IC,TBD!!!F86!RSVD(101)!!!!
S!TP_CPU0_RSVD_105!U5D1!CE80!@baseboard_fab2_lib.baseboard_fab2(sch_1):page36_i15@chpset_lib.skx_ext_b(chips)!SKX_EXT_B_BGA1-IC,TBD!!!F86!RSVD(105)!!!!
S!TP_CPU0_RSVD_106!U5D1!CE78!@baseboard_fab2_lib.baseboard_fab2(sch_1):page36_i15@chpset_lib.skx_ext_b(chips)!SKX_EXT_B_BGA1-IC,TBD!!!F86!RSVD(106)!!!!
S!TP_CPU0_RSVD_150!U5D1!BD69!@baseboard_fab2_lib.baseboard_fab2(sch_1):page36_i15@chpset_lib.skx_ext_b(chips)!SKX_EXT_B_BGA1-IC,TBD!!!F86!RSVD(150)!!!!
S!TP_CPU0_RSVD_151!U5D1!BD67!@baseboard_fab2_lib.baseboard_fab2(sch_1):page36_i15@chpset_lib.skx_ext_b(chips)!SKX_EXT_B_BGA1-IC,TBD!!!F86!RSVD(151)!!!!
S!TP_CPU0_RSVD_152!U5D1!BD65!@baseboard_fab2_lib.baseboard_fab2(sch_1):page36_i15@chpset_lib.skx_ext_b(chips)!SKX_EXT_B_BGA1-IC,TBD!!!F86!RSVD(152)!!!!
S!CLK_100M_CPU0_RC_REFCLK1_DP!U5D1!BD25!@baseboard_fab2_lib.baseboard_fab2(sch_1):page36_i15@chpset_lib.skx_ext_b(chips)!SKX_EXT_B_BGA1-IC,TBD!!!F86!RSVD(153)!!!!
S!TP_CPU0_RSVD_156!U5D1!BC68!@baseboard_fab2_lib.baseboard_fab2(sch_1):page36_i15@chpset_lib.skx_ext_b(chips)!SKX_EXT_B_BGA1-IC,TBD!!!F86!RSVD(156)!!!!
S!TP_CPU0_RSVD_157!U5D1!BC66!@baseboard_fab2_lib.baseboard_fab2(sch_1):page36_i15@chpset_lib.skx_ext_b(chips)!SKX_EXT_B_BGA1-IC,TBD!!!F86!RSVD(157)!!!!
S!TP_CPU0_RSVD_158!U5D1!BC64!@baseboard_fab2_lib.baseboard_fab2(sch_1):page36_i15@chpset_lib.skx_ext_b(chips)!SKX_EXT_B_BGA1-IC,TBD!!!F86!RSVD(158)!!!!
S!TP_CPU0_RSVD_11!U5D1!ED45!@baseboard_fab2_lib.baseboard_fab2(sch_1):page39_i127@chpset_lib.skx_ext_b(chips)!SKX_EXT_B_BGA1-IC,TBD!!!F80!RSVD(11)!!!!
S!TP_CPU0_RSVD_163!U5D1!BB67!@baseboard_fab2_lib.baseboard_fab2(sch_1):page36_i15@chpset_lib.skx_ext_b(chips)!SKX_EXT_B_BGA1-IC,TBD!!!F86!RSVD(163)!!!!
S!TP_CPU0_RSVD_164!U5D1!BB65!@baseboard_fab2_lib.baseboard_fab2(sch_1):page36_i15@chpset_lib.skx_ext_b(chips)!SKX_EXT_B_BGA1-IC,TBD!!!F86!RSVD(164)!!!!
S!CLK_100M_CPU0_RC_REFCLK1_DN!U5D1!BB25!@baseboard_fab2_lib.baseboard_fab2(sch_1):page36_i15@chpset_lib.skx_ext_b(chips)!SKX_EXT_B_BGA1-IC,TBD!!!F86!RSVD(165)!!!!
S!TP_CPU0_RSVD_170!U5D1!BA82!@baseboard_fab2_lib.baseboard_fab2(sch_1):page36_i15@chpset_lib.skx_ext_b(chips)!SKX_EXT_B_BGA1-IC,TBD!!!F86!RSVD(170)!!!!
S!TP_CPU0_RSVD_171!U5D1!BA78!@baseboard_fab2_lib.baseboard_fab2(sch_1):page36_i15@chpset_lib.skx_ext_b(chips)!SKX_EXT_B_BGA1-IC,TBD!!!F86!RSVD(171)!!!!
S!TP_CPU0_RSVD_172!U5D1!BA76!@baseboard_fab2_lib.baseboard_fab2(sch_1):page29_i61@chpset_lib.skx_ext_b(chips)!SKX_EXT_B_BGA1-IC,TBD!!!F93!RSVD(172)!!!!
S!TP_CPU0_RSVD_173!U5D1!BA66!@baseboard_fab2_lib.baseboard_fab2(sch_1):page29_i61@chpset_lib.skx_ext_b(chips)!SKX_EXT_B_BGA1-IC,TBD!!!F93!RSVD(173)!!!!
S!TP_CPU0_RSVD_174!U5D1!BA64!@baseboard_fab2_lib.baseboard_fab2(sch_1):page29_i61@chpset_lib.skx_ext_b(chips)!SKX_EXT_B_BGA1-IC,TBD!!!F93!RSVD(174)!!!!
S!TP_CPU0_RSVD_179!U5D1!AY77!@baseboard_fab2_lib.baseboard_fab2(sch_1):page29_i61@chpset_lib.skx_ext_b(chips)!SKX_EXT_B_BGA1-IC,TBD!!!F93!RSVD(179)!!!!
S!TP_CPU0_RSVD_180!U5D1!AY75!@baseboard_fab2_lib.baseboard_fab2(sch_1):page29_i61@chpset_lib.skx_ext_b(chips)!SKX_EXT_B_BGA1-IC,TBD!!!F93!RSVD(180)!!!!
S!TP_CPU0_RSVD_13!U5D1!EC44!@baseboard_fab2_lib.baseboard_fab2(sch_1):page39_i127@chpset_lib.skx_ext_b(chips)!SKX_EXT_B_BGA1-IC,TBD!!!F80!RSVD(13)!!!!
S!TP_CPU0_RSVD_181!U5D1!AY67!@baseboard_fab2_lib.baseboard_fab2(sch_1):page29_i61@chpset_lib.skx_ext_b(chips)!SKX_EXT_B_BGA1-IC,TBD!!!F93!RSVD(181)!!!!
S!TP_CPU0_RSVD_182!U5D1!AY65!@baseboard_fab2_lib.baseboard_fab2(sch_1):page29_i61@chpset_lib.skx_ext_b(chips)!SKX_EXT_B_BGA1-IC,TBD!!!F93!RSVD(182)!!!!
S!TP_CPU0_RSVD_183!U5D1!AW76!@baseboard_fab2_lib.baseboard_fab2(sch_1):page29_i61@chpset_lib.skx_ext_b(chips)!SKX_EXT_B_BGA1-IC,TBD!!!F93!RSVD(183)!!!!
S!TP_CPU0_RSVD_184!U5D1!AW64!@baseboard_fab2_lib.baseboard_fab2(sch_1):page29_i61@chpset_lib.skx_ext_b(chips)!SKX_EXT_B_BGA1-IC,TBD!!!F93!RSVD(184)!!!!
S!TP_CPU0_RSVD_186!U5D1!AV77!@baseboard_fab2_lib.baseboard_fab2(sch_1):page29_i61@chpset_lib.skx_ext_b(chips)!SKX_EXT_B_BGA1-IC,TBD!!!F93!RSVD(186)!!!!
S!TP_CPU0_RSVD_190!U5D1!AR62!@baseboard_fab2_lib.baseboard_fab2(sch_1):page29_i61@chpset_lib.skx_ext_b(chips)!SKX_EXT_B_BGA1-IC,TBD!!!F93!RSVD(190)!!!!
S!TP_CPU0_RSVD_194!U5D1!AP61!@baseboard_fab2_lib.baseboard_fab2(sch_1):page22_i204@chpset_lib.skx_ext_b(chips)!SKX_EXT_B_BGA1-IC,TBD!!!F100!RSVD(194)!!!!
S!TP_CPU0_RSVD_198!U5D1!AN62!@baseboard_fab2_lib.baseboard_fab2(sch_1):page22_i204@chpset_lib.skx_ext_b(chips)!SKX_EXT_B_BGA1-IC,TBD!!!F100!RSVD(198)!!!!
S!TP_CPU0_RSVD_199!U5D1!AN60!@baseboard_fab2_lib.baseboard_fab2(sch_1):page22_i204@chpset_lib.skx_ext_b(chips)!SKX_EXT_B_BGA1-IC,TBD!!!F100!RSVD(199)!!!!
S!TP_CPU0_RSVD_204!U5D1!AM61!@baseboard_fab2_lib.baseboard_fab2(sch_1):page22_i204@chpset_lib.skx_ext_b(chips)!SKX_EXT_B_BGA1-IC,TBD!!!F100!RSVD(204)!!!!
S!TP_CPU0_RSVD_19!U5D1!EA44!@baseboard_fab2_lib.baseboard_fab2(sch_1):page39_i127@chpset_lib.skx_ext_b(chips)!SKX_EXT_B_BGA1-IC,TBD!!!F80!RSVD(19)!!!!
S!TP_CPU0_RSVD_205!U5D1!AM59!@baseboard_fab2_lib.baseboard_fab2(sch_1):page22_i204@chpset_lib.skx_ext_b(chips)!SKX_EXT_B_BGA1-IC,TBD!!!F100!RSVD(205)!!!!
S!TP_CPU0_RSVD_210!U5D1!AL62!@baseboard_fab2_lib.baseboard_fab2(sch_1):page22_i204@chpset_lib.skx_ext_b(chips)!SKX_EXT_B_BGA1-IC,TBD!!!F100!RSVD(210)!!!!
S!TP_CPU0_RSVD_211!U5D1!AL60!@baseboard_fab2_lib.baseboard_fab2(sch_1):page22_i204@chpset_lib.skx_ext_b(chips)!SKX_EXT_B_BGA1-IC,TBD!!!F100!RSVD(211)!!!!
S!TP_CPU0_RSVD_212!U5D1!AL58!@baseboard_fab2_lib.baseboard_fab2(sch_1):page22_i204@chpset_lib.skx_ext_b(chips)!SKX_EXT_B_BGA1-IC,TBD!!!F100!RSVD(212)!!!!
S!TP_CPU0_RSVD_216!U5D1!AK69!@baseboard_fab2_lib.baseboard_fab2(sch_1):page22_i204@chpset_lib.skx_ext_b(chips)!SKX_EXT_B_BGA1-IC,TBD!!!F100!RSVD(216)!!!!
S!TP_CPU0_RSVD_217!U5D1!AK61!@baseboard_fab2_lib.baseboard_fab2(sch_1):page22_i204@chpset_lib.skx_ext_b(chips)!SKX_EXT_B_BGA1-IC,TBD!!!F100!RSVD(217)!!!!
S!TP_CPU0_RSVD_218!U5D1!AK59!@baseboard_fab2_lib.baseboard_fab2(sch_1):page22_i204@chpset_lib.skx_ext_b(chips)!SKX_EXT_B_BGA1-IC,TBD!!!F100!RSVD(218)!!!!
S!TP_CPU0_RSVD_222!U5D1!AJ70!@baseboard_fab2_lib.baseboard_fab2(sch_1):page22_i204@chpset_lib.skx_ext_b(chips)!SKX_EXT_B_BGA1-IC,TBD!!!F100!RSVD(222)!!!!
S!TP_CPU0_RSVD_223!U5D1!AJ62!@baseboard_fab2_lib.baseboard_fab2(sch_1):page22_i204@chpset_lib.skx_ext_b(chips)!SKX_EXT_B_BGA1-IC,TBD!!!F100!RSVD(223)!!!!
S!TP_CPU0_RSVD_224!U5D1!AJ60!@baseboard_fab2_lib.baseboard_fab2(sch_1):page22_i204@chpset_lib.skx_ext_b(chips)!SKX_EXT_B_BGA1-IC,TBD!!!F100!RSVD(224)!!!!
S!TP_CPU0_RSVD_22!U5D1!DW46!@baseboard_fab2_lib.baseboard_fab2(sch_1):page39_i127@chpset_lib.skx_ext_b(chips)!SKX_EXT_B_BGA1-IC,TBD!!!F80!RSVD(22)!!!!
S!TP_CPU0_RSVD_225!U5D1!AJ58!@baseboard_fab2_lib.baseboard_fab2(sch_1):page22_i204@chpset_lib.skx_ext_b(chips)!SKX_EXT_B_BGA1-IC,TBD!!!F100!RSVD(225)!!!!
S!TP_CPU0_RSVD_228!U5D1!AH73!@baseboard_fab2_lib.baseboard_fab2(sch_1):page22_i204@chpset_lib.skx_ext_b(chips)!SKX_EXT_B_BGA1-IC,TBD!!!F100!RSVD(228)!!!!
S!TP_CPU0_RSVD_229!U5D1!AH71!@baseboard_fab2_lib.baseboard_fab2(sch_1):page22_i204@chpset_lib.skx_ext_b(chips)!SKX_EXT_B_BGA1-IC,TBD!!!F100!RSVD(229)!!!!
S!TP_CPU0_RSVD_230!U5D1!AH57!@baseboard_fab2_lib.baseboard_fab2(sch_1):page22_i204@chpset_lib.skx_ext_b(chips)!SKX_EXT_B_BGA1-IC,TBD!!!F100!RSVD(230)!!!!
S!TP_CPU0_RSVD_234!U5D1!AG72!@baseboard_fab2_lib.baseboard_fab2(sch_1):page22_i204@chpset_lib.skx_ext_b(chips)!SKX_EXT_B_BGA1-IC,TBD!!!F100!RSVD(234)!!!!
S!TP_CPU0_RSVD_241!U5D1!AF71!@baseboard_fab2_lib.baseboard_fab2(sch_1):page22_i204@chpset_lib.skx_ext_b(chips)!SKX_EXT_B_BGA1-IC,TBD!!!F100!RSVD(241)!!!!
S!TP_CPU0_RSVD_247!U5D1!AE72!@baseboard_fab2_lib.baseboard_fab2(sch_1):page22_i204@chpset_lib.skx_ext_b(chips)!SKX_EXT_B_BGA1-IC,TBD!!!F100!RSVD(247)!!!!
S!TP_CPU0_RSVD_251!U5D1!AE46!@baseboard_fab2_lib.baseboard_fab2(sch_1):page22_i204@chpset_lib.skx_ext_b(chips)!SKX_EXT_B_BGA1-IC,TBD!!!F100!RSVD(251)!!!!
S!VSENSE_PMAX_CPU0!U5D1!AD41!@baseboard_fab2_lib.baseboard_fab2(sch_1):page37_i311@chpset_lib.skx_ext_b(chips)!SKX_EXT_B_BGA1-IC,TBD!!!F83!VSENSEPMAX!!!!
S!TP_CPU0_RSVD_256!U5D1!Y65!@baseboard_fab2_lib.baseboard_fab2(sch_1):page22_i204@chpset_lib.skx_ext_b(chips)!SKX_EXT_B_BGA1-IC,TBD!!!F100!RSVD(256)!!!!
S!TP_CPU0_RSVD_23!U5D1!DW44!@baseboard_fab2_lib.baseboard_fab2(sch_1):page39_i127@chpset_lib.skx_ext_b(chips)!SKX_EXT_B_BGA1-IC,TBD!!!F80!RSVD(23)!!!!
S!FM_CPU0_RC_ERROR_N!U5D1!Y23!@baseboard_fab2_lib.baseboard_fab2(sch_1):page22_i204@chpset_lib.skx_ext_b(chips)!SKX_EXT_B_BGA1-IC,TBD!!!F100!RSVD(257)!!!!
S!TP_CPU0_RSVD_258!U5D1!W66!@baseboard_fab2_lib.baseboard_fab2(sch_1):page22_i204@chpset_lib.skx_ext_b(chips)!SKX_EXT_B_BGA1-IC,TBD!!!F100!RSVD(258)!!!!
S!TP_CPU0_RSVD_259!U5D1!V67!@baseboard_fab2_lib.baseboard_fab2(sch_1):page22_i204@chpset_lib.skx_ext_b(chips)!SKX_EXT_B_BGA1-IC,TBD!!!F100!RSVD(259)!!!!
S!TP_CPU0_RSVD_260!U5D1!V65!@baseboard_fab2_lib.baseboard_fab2(sch_1):page22_i204@chpset_lib.skx_ext_b(chips)!SKX_EXT_B_BGA1-IC,TBD!!!F100!RSVD(260)!!!!
S!TP_CPU0_RSVD_261!U5D1!U66!@baseboard_fab2_lib.baseboard_fab2(sch_1):page22_i204@chpset_lib.skx_ext_b(chips)!SKX_EXT_B_BGA1-IC,TBD!!!F100!RSVD(261)!!!!
S!TP_CPU0_RSVD_262!U5D1!T67!@baseboard_fab2_lib.baseboard_fab2(sch_1):page22_i204@chpset_lib.skx_ext_b(chips)!SKX_EXT_B_BGA1-IC,TBD!!!F100!RSVD(262)!!!!
S!TP_CPU0_RSVD_263!U5D1!R66!@baseboard_fab2_lib.baseboard_fab2(sch_1):page22_i204@chpset_lib.skx_ext_b(chips)!SKX_EXT_B_BGA1-IC,TBD!!!F100!RSVD(263)!!!!
S!TP_CPU0_RSVD_264!U5D1!R62!@baseboard_fab2_lib.baseboard_fab2(sch_1):page22_i204@chpset_lib.skx_ext_b(chips)!SKX_EXT_B_BGA1-IC,TBD!!!F100!RSVD(264)!!!!
S!TP_CPU0_RSVD_265!U5D1!P65!@baseboard_fab2_lib.baseboard_fab2(sch_1):page22_i204@chpset_lib.skx_ext_b(chips)!SKX_EXT_B_BGA1-IC,TBD!!!F100!RSVD(265)!!!!
S!TP_CPU0_RSVD_266!U5D1!M63!@baseboard_fab2_lib.baseboard_fab2(sch_1):page22_i204@chpset_lib.skx_ext_b(chips)!SKX_EXT_B_BGA1-IC,TBD!!!F100!RSVD(266)!!!!
S!TP_CPU0_RSVD_25!U5D1!DV61!@baseboard_fab2_lib.baseboard_fab2(sch_1):page39_i127@chpset_lib.skx_ext_b(chips)!SKX_EXT_B_BGA1-IC,TBD!!!F80!RSVD(25)!!!!
S!TP_CPU0_RSVD_227!U5D1!AJ20!@baseboard_fab2_lib.baseboard_fab2(sch_1):page22_i204@chpset_lib.skx_ext_b(chips)!SKX_EXT_B_BGA1-IC,TBD!!!F100!RSVD(227)!!!!
S!TP_CPU0_RSVD_240!U5D1!AG20!@baseboard_fab2_lib.baseboard_fab2(sch_1):page22_i204@chpset_lib.skx_ext_b(chips)!SKX_EXT_B_BGA1-IC,TBD!!!F100!RSVD(240)!!!!
S!TP_CPU0_TEST_7!U5D1!AU18!@baseboard_fab2_lib.baseboard_fab2(sch_1):page36_i16@chpset_lib.skx_ext_b(chips)!SKX_EXT_B_BGA1-IC,TBD!!!F85!TEST_7!!!!
S!TP_CPU0_TEST_8!U5D1!AW16!@baseboard_fab2_lib.baseboard_fab2(sch_1):page36_i16@chpset_lib.skx_ext_b(chips)!SKX_EXT_B_BGA1-IC,TBD!!!F85!TEST_8!!!!
S!TP_CPU0_TEST_10!U5D1!AW22!@baseboard_fab2_lib.baseboard_fab2(sch_1):page36_i16@chpset_lib.skx_ext_b(chips)!SKX_EXT_B_BGA1-IC,TBD!!!F85!TEST_10!!!!
S!TP_CPU0_TEST_9!U5D1!AW20!@baseboard_fab2_lib.baseboard_fab2(sch_1):page36_i16@chpset_lib.skx_ext_b(chips)!SKX_EXT_B_BGA1-IC,TBD!!!F85!TEST_9!!!!
S!TP_CPU0_RSVD_TEST_11!U5D1!AY13!@baseboard_fab2_lib.baseboard_fab2(sch_1):page22_i204@chpset_lib.skx_ext_b(chips)!SKX_EXT_B_BGA1-IC,TBD!!!F100!TEST_11!!!!
S!TP_CPU0_RSVD_280!U5D1!E84!@baseboard_fab2_lib.baseboard_fab2(sch_1):page22_i204@chpset_lib.skx_ext_b(chips)!SKX_EXT_B_BGA1-IC,TBD!!!F100!RSVD(280)!!!!
S!TP_CPU0_RSVD_284!U5D1!D83!@baseboard_fab2_lib.baseboard_fab2(sch_1):page22_i204@chpset_lib.skx_ext_b(chips)!SKX_EXT_B_BGA1-IC,TBD!!!F100!RSVD(284)!!!!
S!TP_CPU0_RSVD_288!U5D1!C82!@baseboard_fab2_lib.baseboard_fab2(sch_1):page22_i204@chpset_lib.skx_ext_b(chips)!SKX_EXT_B_BGA1-IC,TBD!!!F100!RSVD(288)!!!!
S!TP_CPU0_RSVD_292!U5D1!B81!@baseboard_fab2_lib.baseboard_fab2(sch_1):page22_i204@chpset_lib.skx_ext_b(chips)!SKX_EXT_B_BGA1-IC,TBD!!!F100!RSVD(292)!!!!
S!TP_CPU0_RSVD_1!U5D1!EF81!@baseboard_fab2_lib.baseboard_fab2(sch_1):page39_i127@chpset_lib.skx_ext_b(chips)!SKX_EXT_B_BGA1-IC,TBD!!!F80!RSVD(1)!!!!
S!TP_CPU0_RSVD_5!U5D1!EE82!@baseboard_fab2_lib.baseboard_fab2(sch_1):page39_i127@chpset_lib.skx_ext_b(chips)!SKX_EXT_B_BGA1-IC,TBD!!!F80!RSVD(5)!!!!
S!TP_CPU0_RSVD_0!U5D1!EF83!@baseboard_fab2_lib.baseboard_fab2(sch_1):page39_i127@chpset_lib.skx_ext_b(chips)!SKX_EXT_B_BGA1-IC,TBD!!!F80!RSVD(0)!!!!
S!TP_CPU0_RSVD_4!U5D1!EE84!@baseboard_fab2_lib.baseboard_fab2(sch_1):page39_i127@chpset_lib.skx_ext_b(chips)!SKX_EXT_B_BGA1-IC,TBD!!!F80!RSVD(4)!!!!
S!TP_CPU0_RSVD_270!U5D1!H85!@baseboard_fab2_lib.baseboard_fab2(sch_1):page22_i204@chpset_lib.skx_ext_b(chips)!SKX_EXT_B_BGA1-IC,TBD!!!F100!RSVD(270)!!!!
S!PVCCIN_CPU0!U5D1!BN78!@baseboard_fab2_lib.baseboard_fab2(sch_1):page37_i310@chpset_lib.skx_ext_b(chips)!SKX_EXT_B_BGA1-IC,TBD!!!F84!VCCIN(130)!!!!
S!PVCCIN_CPU0!U5D1!BN76!@baseboard_fab2_lib.baseboard_fab2(sch_1):page37_i310@chpset_lib.skx_ext_b(chips)!SKX_EXT_B_BGA1-IC,TBD!!!F84!VCCIN(131)!!!!
S!PVCCIN_CPU0!U5D1!BN74!@baseboard_fab2_lib.baseboard_fab2(sch_1):page37_i310@chpset_lib.skx_ext_b(chips)!SKX_EXT_B_BGA1-IC,TBD!!!F84!VCCIN(132)!!!!
S!PVCCIN_CPU0!U5D1!BN72!@baseboard_fab2_lib.baseboard_fab2(sch_1):page37_i310@chpset_lib.skx_ext_b(chips)!SKX_EXT_B_BGA1-IC,TBD!!!F84!VCCIN(133)!!!!
S!PVCCIN_CPU0!U5D1!BN70!@baseboard_fab2_lib.baseboard_fab2(sch_1):page37_i310@chpset_lib.skx_ext_b(chips)!SKX_EXT_B_BGA1-IC,TBD!!!F84!VCCIN(134)!!!!
S!PVCCIN_CPU0!U5D1!BN68!@baseboard_fab2_lib.baseboard_fab2(sch_1):page37_i310@chpset_lib.skx_ext_b(chips)!SKX_EXT_B_BGA1-IC,TBD!!!F84!VCCIN(135)!!!!
S!PVCCIN_CPU0!U5D1!BN66!@baseboard_fab2_lib.baseboard_fab2(sch_1):page37_i310@chpset_lib.skx_ext_b(chips)!SKX_EXT_B_BGA1-IC,TBD!!!F84!VCCIN(136)!!!!
S!PVCCIN_CPU0!U5D1!BN64!@baseboard_fab2_lib.baseboard_fab2(sch_1):page37_i310@chpset_lib.skx_ext_b(chips)!SKX_EXT_B_BGA1-IC,TBD!!!F84!VCCIN(137)!!!!
S!PVCCIN_CPU0!U5D1!BN62!@baseboard_fab2_lib.baseboard_fab2(sch_1):page37_i310@chpset_lib.skx_ext_b(chips)!SKX_EXT_B_BGA1-IC,TBD!!!F84!VCCIN(138)!!!!
S!PVCCIN_CPU0!U5D1!BN60!@baseboard_fab2_lib.baseboard_fab2(sch_1):page37_i310@chpset_lib.skx_ext_b(chips)!SKX_EXT_B_BGA1-IC,TBD!!!F84!VCCIN(139)!!!!
S!PVCCIN_CPU0!U5D1!BM83!@baseboard_fab2_lib.baseboard_fab2(sch_1):page37_i310@chpset_lib.skx_ext_b(chips)!SKX_EXT_B_BGA1-IC,TBD!!!F84!VCCIN(140)!!!!
S!PVCCIN_CPU0!U5D1!BM81!@baseboard_fab2_lib.baseboard_fab2(sch_1):page37_i310@chpset_lib.skx_ext_b(chips)!SKX_EXT_B_BGA1-IC,TBD!!!F84!VCCIN(141)!!!!
S!PVCCIN_CPU0!U5D1!BM79!@baseboard_fab2_lib.baseboard_fab2(sch_1):page37_i310@chpset_lib.skx_ext_b(chips)!SKX_EXT_B_BGA1-IC,TBD!!!F84!VCCIN(142)!!!!
S!PVCCIN_CPU0!U5D1!BM77!@baseboard_fab2_lib.baseboard_fab2(sch_1):page37_i310@chpset_lib.skx_ext_b(chips)!SKX_EXT_B_BGA1-IC,TBD!!!F84!VCCIN(143)!!!!
S!PVCCIN_CPU0!U5D1!BM75!@baseboard_fab2_lib.baseboard_fab2(sch_1):page37_i310@chpset_lib.skx_ext_b(chips)!SKX_EXT_B_BGA1-IC,TBD!!!F84!VCCIN(144)!!!!
S!PVCCIN_CPU0!U5D1!BM73!@baseboard_fab2_lib.baseboard_fab2(sch_1):page37_i310@chpset_lib.skx_ext_b(chips)!SKX_EXT_B_BGA1-IC,TBD!!!F84!VCCIN(145)!!!!
S!PVCCIN_CPU0!U5D1!BM71!@baseboard_fab2_lib.baseboard_fab2(sch_1):page37_i310@chpset_lib.skx_ext_b(chips)!SKX_EXT_B_BGA1-IC,TBD!!!F84!VCCIN(146)!!!!
S!PVCCIN_CPU0!U5D1!BM69!@baseboard_fab2_lib.baseboard_fab2(sch_1):page37_i310@chpset_lib.skx_ext_b(chips)!SKX_EXT_B_BGA1-IC,TBD!!!F84!VCCIN(147)!!!!
S!PVCCIN_CPU0!U5D1!BM67!@baseboard_fab2_lib.baseboard_fab2(sch_1):page37_i310@chpset_lib.skx_ext_b(chips)!SKX_EXT_B_BGA1-IC,TBD!!!F84!VCCIN(148)!!!!
S!PVCCIN_CPU0!U5D1!BM65!@baseboard_fab2_lib.baseboard_fab2(sch_1):page37_i310@chpset_lib.skx_ext_b(chips)!SKX_EXT_B_BGA1-IC,TBD!!!F84!VCCIN(149)!!!!
S!PVCCIN_CPU0!U5D1!BM63!@baseboard_fab2_lib.baseboard_fab2(sch_1):page37_i310@chpset_lib.skx_ext_b(chips)!SKX_EXT_B_BGA1-IC,TBD!!!F84!VCCIN(150)!!!!
S!PVCCIN_CPU0!U5D1!BM61!@baseboard_fab2_lib.baseboard_fab2(sch_1):page37_i310@chpset_lib.skx_ext_b(chips)!SKX_EXT_B_BGA1-IC,TBD!!!F84!VCCIN(151)!!!!
S!PVCCIN_CPU0!U5D1!BL84!@baseboard_fab2_lib.baseboard_fab2(sch_1):page37_i310@chpset_lib.skx_ext_b(chips)!SKX_EXT_B_BGA1-IC,TBD!!!F84!VCCIN(152)!!!!
S!PVCCIN_CPU0!U5D1!BL62!@baseboard_fab2_lib.baseboard_fab2(sch_1):page37_i310@chpset_lib.skx_ext_b(chips)!SKX_EXT_B_BGA1-IC,TBD!!!F84!VCCIN(153)!!!!
S!PVCCIN_CPU0!U5D1!BL60!@baseboard_fab2_lib.baseboard_fab2(sch_1):page37_i310@chpset_lib.skx_ext_b(chips)!SKX_EXT_B_BGA1-IC,TBD!!!F84!VCCIN(154)!!!!
S!PVCCIN_CPU0!U5D1!BK83!@baseboard_fab2_lib.baseboard_fab2(sch_1):page37_i310@chpset_lib.skx_ext_b(chips)!SKX_EXT_B_BGA1-IC,TBD!!!F84!VCCIN(155)!!!!
S!PVCCIN_CPU0!U5D1!BK81!@baseboard_fab2_lib.baseboard_fab2(sch_1):page37_i310@chpset_lib.skx_ext_b(chips)!SKX_EXT_B_BGA1-IC,TBD!!!F84!VCCIN(156)!!!!
S!PVCCIN_CPU0!U5D1!BK79!@baseboard_fab2_lib.baseboard_fab2(sch_1):page37_i310@chpset_lib.skx_ext_b(chips)!SKX_EXT_B_BGA1-IC,TBD!!!F84!VCCIN(157)!!!!
S!PVCCIN_CPU0!U5D1!BK77!@baseboard_fab2_lib.baseboard_fab2(sch_1):page37_i310@chpset_lib.skx_ext_b(chips)!SKX_EXT_B_BGA1-IC,TBD!!!F84!VCCIN(158)!!!!
S!PVCCIN_CPU0!U5D1!BK75!@baseboard_fab2_lib.baseboard_fab2(sch_1):page37_i310@chpset_lib.skx_ext_b(chips)!SKX_EXT_B_BGA1-IC,TBD!!!F84!VCCIN(159)!!!!
S!PVCCIN_CPU0!U5D1!BK73!@baseboard_fab2_lib.baseboard_fab2(sch_1):page37_i310@chpset_lib.skx_ext_b(chips)!SKX_EXT_B_BGA1-IC,TBD!!!F84!VCCIN(160)!!!!
S!PVCCIN_CPU0!U5D1!BK71!@baseboard_fab2_lib.baseboard_fab2(sch_1):page37_i310@chpset_lib.skx_ext_b(chips)!SKX_EXT_B_BGA1-IC,TBD!!!F84!VCCIN(161)!!!!
S!PVCCIN_CPU0!U5D1!BK69!@baseboard_fab2_lib.baseboard_fab2(sch_1):page37_i310@chpset_lib.skx_ext_b(chips)!SKX_EXT_B_BGA1-IC,TBD!!!F84!VCCIN(162)!!!!
S!PVCCIN_CPU0!U5D1!BK67!@baseboard_fab2_lib.baseboard_fab2(sch_1):page37_i310@chpset_lib.skx_ext_b(chips)!SKX_EXT_B_BGA1-IC,TBD!!!F84!VCCIN(163)!!!!
S!PVCCIN_CPU0!U5D1!BK65!@baseboard_fab2_lib.baseboard_fab2(sch_1):page37_i310@chpset_lib.skx_ext_b(chips)!SKX_EXT_B_BGA1-IC,TBD!!!F84!VCCIN(164)!!!!
S!PVCCIN_CPU0!U5D1!BK63!@baseboard_fab2_lib.baseboard_fab2(sch_1):page37_i310@chpset_lib.skx_ext_b(chips)!SKX_EXT_B_BGA1-IC,TBD!!!F84!VCCIN(165)!!!!
S!PVCCIN_CPU0!U5D1!BK61!@baseboard_fab2_lib.baseboard_fab2(sch_1):page37_i310@chpset_lib.skx_ext_b(chips)!SKX_EXT_B_BGA1-IC,TBD!!!F84!VCCIN(166)!!!!
S!PVCCIN_CPU0!U5D1!BJ84!@baseboard_fab2_lib.baseboard_fab2(sch_1):page37_i310@chpset_lib.skx_ext_b(chips)!SKX_EXT_B_BGA1-IC,TBD!!!F84!VCCIN(167)!!!!
S!PVCCIN_CPU0!U5D1!BJ82!@baseboard_fab2_lib.baseboard_fab2(sch_1):page37_i310@chpset_lib.skx_ext_b(chips)!SKX_EXT_B_BGA1-IC,TBD!!!F84!VCCIN(168)!!!!
S!PVCCIN_CPU0!U5D1!BJ80!@baseboard_fab2_lib.baseboard_fab2(sch_1):page37_i310@chpset_lib.skx_ext_b(chips)!SKX_EXT_B_BGA1-IC,TBD!!!F84!VCCIN(169)!!!!
S!PVCCIN_CPU0!U5D1!BJ78!@baseboard_fab2_lib.baseboard_fab2(sch_1):page37_i310@chpset_lib.skx_ext_b(chips)!SKX_EXT_B_BGA1-IC,TBD!!!F84!VCCIN(170)!!!!
S!PVCCIN_CPU0!U5D1!BJ76!@baseboard_fab2_lib.baseboard_fab2(sch_1):page37_i310@chpset_lib.skx_ext_b(chips)!SKX_EXT_B_BGA1-IC,TBD!!!F84!VCCIN(171)!!!!
S!PVCCIN_CPU0!U5D1!BJ74!@baseboard_fab2_lib.baseboard_fab2(sch_1):page37_i310@chpset_lib.skx_ext_b(chips)!SKX_EXT_B_BGA1-IC,TBD!!!F84!VCCIN(172)!!!!
S!PVCCIN_CPU0!U5D1!BJ72!@baseboard_fab2_lib.baseboard_fab2(sch_1):page37_i310@chpset_lib.skx_ext_b(chips)!SKX_EXT_B_BGA1-IC,TBD!!!F84!VCCIN(173)!!!!
S!PVCCIN_CPU0!U5D1!BJ70!@baseboard_fab2_lib.baseboard_fab2(sch_1):page37_i310@chpset_lib.skx_ext_b(chips)!SKX_EXT_B_BGA1-IC,TBD!!!F84!VCCIN(174)!!!!
S!PVCCIN_CPU0!U5D1!BJ68!@baseboard_fab2_lib.baseboard_fab2(sch_1):page37_i310@chpset_lib.skx_ext_b(chips)!SKX_EXT_B_BGA1-IC,TBD!!!F84!VCCIN(175)!!!!
S!PVCCIN_CPU0!U5D1!BJ66!@baseboard_fab2_lib.baseboard_fab2(sch_1):page37_i310@chpset_lib.skx_ext_b(chips)!SKX_EXT_B_BGA1-IC,TBD!!!F84!VCCIN(176)!!!!
S!PVCCIN_CPU0!U5D1!BJ64!@baseboard_fab2_lib.baseboard_fab2(sch_1):page37_i310@chpset_lib.skx_ext_b(chips)!SKX_EXT_B_BGA1-IC,TBD!!!F84!VCCIN(177)!!!!
S!PVCCIN_CPU0!U5D1!BJ62!@baseboard_fab2_lib.baseboard_fab2(sch_1):page37_i310@chpset_lib.skx_ext_b(chips)!SKX_EXT_B_BGA1-IC,TBD!!!F84!VCCIN(178)!!!!
S!PVCCIN_CPU0!U5D1!BJ60!@baseboard_fab2_lib.baseboard_fab2(sch_1):page37_i310@chpset_lib.skx_ext_b(chips)!SKX_EXT_B_BGA1-IC,TBD!!!F84!VCCIN(179)!!!!
S!PVCCIN_CPU0!U5D1!BH83!@baseboard_fab2_lib.baseboard_fab2(sch_1):page37_i310@chpset_lib.skx_ext_b(chips)!SKX_EXT_B_BGA1-IC,TBD!!!F84!VCCIN(180)!!!!
S!PVCCIN_CPU0!U5D1!BH81!@baseboard_fab2_lib.baseboard_fab2(sch_1):page37_i310@chpset_lib.skx_ext_b(chips)!SKX_EXT_B_BGA1-IC,TBD!!!F84!VCCIN(181)!!!!
S!PVCCIN_CPU0!U5D1!BH79!@baseboard_fab2_lib.baseboard_fab2(sch_1):page37_i310@chpset_lib.skx_ext_b(chips)!SKX_EXT_B_BGA1-IC,TBD!!!F84!VCCIN(182)!!!!
S!PVCCIN_CPU0!U5D1!BH77!@baseboard_fab2_lib.baseboard_fab2(sch_1):page37_i310@chpset_lib.skx_ext_b(chips)!SKX_EXT_B_BGA1-IC,TBD!!!F84!VCCIN(183)!!!!
S!PVCCIN_CPU0!U5D1!BH75!@baseboard_fab2_lib.baseboard_fab2(sch_1):page37_i310@chpset_lib.skx_ext_b(chips)!SKX_EXT_B_BGA1-IC,TBD!!!F84!VCCIN(184)!!!!
S!PVCCIN_CPU0!U5D1!BH73!@baseboard_fab2_lib.baseboard_fab2(sch_1):page37_i310@chpset_lib.skx_ext_b(chips)!SKX_EXT_B_BGA1-IC,TBD!!!F84!VCCIN(185)!!!!
S!PVCCIN_CPU0!U5D1!BH71!@baseboard_fab2_lib.baseboard_fab2(sch_1):page37_i310@chpset_lib.skx_ext_b(chips)!SKX_EXT_B_BGA1-IC,TBD!!!F84!VCCIN(186)!!!!
S!PVCCIN_CPU0!U5D1!BH69!@baseboard_fab2_lib.baseboard_fab2(sch_1):page37_i310@chpset_lib.skx_ext_b(chips)!SKX_EXT_B_BGA1-IC,TBD!!!F84!VCCIN(187)!!!!
S!PVCCIN_CPU0!U5D1!BH67!@baseboard_fab2_lib.baseboard_fab2(sch_1):page37_i310@chpset_lib.skx_ext_b(chips)!SKX_EXT_B_BGA1-IC,TBD!!!F84!VCCIN(188)!!!!
S!PVCCIN_CPU0!U5D1!BH65!@baseboard_fab2_lib.baseboard_fab2(sch_1):page37_i310@chpset_lib.skx_ext_b(chips)!SKX_EXT_B_BGA1-IC,TBD!!!F84!VCCIN(189)!!!!
S!PVCCIN_CPU0!U5D1!BH63!@baseboard_fab2_lib.baseboard_fab2(sch_1):page37_i310@chpset_lib.skx_ext_b(chips)!SKX_EXT_B_BGA1-IC,TBD!!!F84!VCCIN(190)!!!!
S!PVCCIN_CPU0!U5D1!BH61!@baseboard_fab2_lib.baseboard_fab2(sch_1):page37_i310@chpset_lib.skx_ext_b(chips)!SKX_EXT_B_BGA1-IC,TBD!!!F84!VCCIN(191)!!!!
S!PVCCIN_CPU0!U5D1!BG84!@baseboard_fab2_lib.baseboard_fab2(sch_1):page37_i310@chpset_lib.skx_ext_b(chips)!SKX_EXT_B_BGA1-IC,TBD!!!F84!VCCIN(192)!!!!
S!PVCCIN_CPU0!U5D1!BG70!@baseboard_fab2_lib.baseboard_fab2(sch_1):page37_i310@chpset_lib.skx_ext_b(chips)!SKX_EXT_B_BGA1-IC,TBD!!!F84!VCCIN(193)!!!!
S!PVCCIN_CPU0!U5D1!BG68!@baseboard_fab2_lib.baseboard_fab2(sch_1):page37_i310@chpset_lib.skx_ext_b(chips)!SKX_EXT_B_BGA1-IC,TBD!!!F84!VCCIN(194)!!!!
S!PVCCIN_CPU0!U5D1!BG66!@baseboard_fab2_lib.baseboard_fab2(sch_1):page37_i310@chpset_lib.skx_ext_b(chips)!SKX_EXT_B_BGA1-IC,TBD!!!F84!VCCIN(195)!!!!
S!PVCCIN_CPU0!U5D1!BG64!@baseboard_fab2_lib.baseboard_fab2(sch_1):page37_i310@chpset_lib.skx_ext_b(chips)!SKX_EXT_B_BGA1-IC,TBD!!!F84!VCCIN(196)!!!!
S!PVCCIN_CPU0!U5D1!BG62!@baseboard_fab2_lib.baseboard_fab2(sch_1):page37_i310@chpset_lib.skx_ext_b(chips)!SKX_EXT_B_BGA1-IC,TBD!!!F84!VCCIN(197)!!!!
S!PVCCIN_CPU0!U5D1!BG60!@baseboard_fab2_lib.baseboard_fab2(sch_1):page37_i310@chpset_lib.skx_ext_b(chips)!SKX_EXT_B_BGA1-IC,TBD!!!F84!VCCIN(198)!!!!
S!PVCCIN_CPU0!U5D1!BF85!@baseboard_fab2_lib.baseboard_fab2(sch_1):page37_i310@chpset_lib.skx_ext_b(chips)!SKX_EXT_B_BGA1-IC,TBD!!!F84!VCCIN(199)!!!!
S!PVCCIN_CPU0!U5D1!BF83!@baseboard_fab2_lib.baseboard_fab2(sch_1):page37_i310@chpset_lib.skx_ext_b(chips)!SKX_EXT_B_BGA1-IC,TBD!!!F84!VCCIN(200)!!!!
S!PVCCIN_CPU0!U5D1!BF81!@baseboard_fab2_lib.baseboard_fab2(sch_1):page37_i310@chpset_lib.skx_ext_b(chips)!SKX_EXT_B_BGA1-IC,TBD!!!F84!VCCIN(201)!!!!
S!PVCCIN_CPU0!U5D1!BF79!@baseboard_fab2_lib.baseboard_fab2(sch_1):page37_i310@chpset_lib.skx_ext_b(chips)!SKX_EXT_B_BGA1-IC,TBD!!!F84!VCCIN(202)!!!!
S!PVCCIN_CPU0!U5D1!BF77!@baseboard_fab2_lib.baseboard_fab2(sch_1):page37_i310@chpset_lib.skx_ext_b(chips)!SKX_EXT_B_BGA1-IC,TBD!!!F84!VCCIN(203)!!!!
S!PVCCIN_CPU0!U5D1!BF75!@baseboard_fab2_lib.baseboard_fab2(sch_1):page37_i310@chpset_lib.skx_ext_b(chips)!SKX_EXT_B_BGA1-IC,TBD!!!F84!VCCIN(204)!!!!
S!PVCCIN_CPU0!U5D1!BF73!@baseboard_fab2_lib.baseboard_fab2(sch_1):page37_i310@chpset_lib.skx_ext_b(chips)!SKX_EXT_B_BGA1-IC,TBD!!!F84!VCCIN(205)!!!!
S!PVCCIN_CPU0!U5D1!BF61!@baseboard_fab2_lib.baseboard_fab2(sch_1):page37_i310@chpset_lib.skx_ext_b(chips)!SKX_EXT_B_BGA1-IC,TBD!!!F84!VCCIN(206)!!!!
S!PVCCIN_CPU0!U5D1!BE84!@baseboard_fab2_lib.baseboard_fab2(sch_1):page37_i310@chpset_lib.skx_ext_b(chips)!SKX_EXT_B_BGA1-IC,TBD!!!F84!VCCIN(207)!!!!
S!PVCCIN_CPU0!U5D1!BE82!@baseboard_fab2_lib.baseboard_fab2(sch_1):page37_i310@chpset_lib.skx_ext_b(chips)!SKX_EXT_B_BGA1-IC,TBD!!!F84!VCCIN(208)!!!!
S!PVCCIN_CPU0!U5D1!BE80!@baseboard_fab2_lib.baseboard_fab2(sch_1):page37_i310@chpset_lib.skx_ext_b(chips)!SKX_EXT_B_BGA1-IC,TBD!!!F84!VCCIN(209)!!!!
S!PVCCIN_CPU0!U5D1!BE78!@baseboard_fab2_lib.baseboard_fab2(sch_1):page37_i310@chpset_lib.skx_ext_b(chips)!SKX_EXT_B_BGA1-IC,TBD!!!F84!VCCIN(210)!!!!
S!PVCCIN_CPU0!U5D1!BE76!@baseboard_fab2_lib.baseboard_fab2(sch_1):page37_i310@chpset_lib.skx_ext_b(chips)!SKX_EXT_B_BGA1-IC,TBD!!!F84!VCCIN(211)!!!!
S!PVCCIN_CPU0!U5D1!BE74!@baseboard_fab2_lib.baseboard_fab2(sch_1):page37_i310@chpset_lib.skx_ext_b(chips)!SKX_EXT_B_BGA1-IC,TBD!!!F84!VCCIN(212)!!!!
S!PVCCIN_CPU0!U5D1!BE72!@baseboard_fab2_lib.baseboard_fab2(sch_1):page37_i310@chpset_lib.skx_ext_b(chips)!SKX_EXT_B_BGA1-IC,TBD!!!F84!VCCIN(213)!!!!
S!PVCCIN_CPU0!U5D1!BE62!@baseboard_fab2_lib.baseboard_fab2(sch_1):page37_i310@chpset_lib.skx_ext_b(chips)!SKX_EXT_B_BGA1-IC,TBD!!!F84!VCCIN(214)!!!!
S!PVCCIN_CPU0!U5D1!BE60!@baseboard_fab2_lib.baseboard_fab2(sch_1):page37_i310@chpset_lib.skx_ext_b(chips)!SKX_EXT_B_BGA1-IC,TBD!!!F84!VCCIN(215)!!!!
S!PVCCIN_CPU0!U5D1!BD85!@baseboard_fab2_lib.baseboard_fab2(sch_1):page37_i310@chpset_lib.skx_ext_b(chips)!SKX_EXT_B_BGA1-IC,TBD!!!F84!VCCIN(216)!!!!
S!PVCCIN_CPU0!U5D1!BD83!@baseboard_fab2_lib.baseboard_fab2(sch_1):page37_i310@chpset_lib.skx_ext_b(chips)!SKX_EXT_B_BGA1-IC,TBD!!!F84!VCCIN(217)!!!!
S!PVCCIN_CPU0!U5D1!BD81!@baseboard_fab2_lib.baseboard_fab2(sch_1):page37_i310@chpset_lib.skx_ext_b(chips)!SKX_EXT_B_BGA1-IC,TBD!!!F84!VCCIN(218)!!!!
S!PVCCIN_CPU0!U5D1!BD79!@baseboard_fab2_lib.baseboard_fab2(sch_1):page37_i310@chpset_lib.skx_ext_b(chips)!SKX_EXT_B_BGA1-IC,TBD!!!F84!VCCIN(219)!!!!
S!PVCCIN_CPU0!U5D1!BD77!@baseboard_fab2_lib.baseboard_fab2(sch_1):page37_i310@chpset_lib.skx_ext_b(chips)!SKX_EXT_B_BGA1-IC,TBD!!!F84!VCCIN(220)!!!!
S!PVCCIN_CPU0!U5D1!BD75!@baseboard_fab2_lib.baseboard_fab2(sch_1):page37_i310@chpset_lib.skx_ext_b(chips)!SKX_EXT_B_BGA1-IC,TBD!!!F84!VCCIN(221)!!!!
S!PVCCIN_CPU0!U5D1!BD73!@baseboard_fab2_lib.baseboard_fab2(sch_1):page37_i310@chpset_lib.skx_ext_b(chips)!SKX_EXT_B_BGA1-IC,TBD!!!F84!VCCIN(222)!!!!
S!PVCCIN_CPU0!U5D1!BD61!@baseboard_fab2_lib.baseboard_fab2(sch_1):page37_i310@chpset_lib.skx_ext_b(chips)!SKX_EXT_B_BGA1-IC,TBD!!!F84!VCCIN(223)!!!!
S!PVCCIN_CPU0!U5D1!BC84!@baseboard_fab2_lib.baseboard_fab2(sch_1):page37_i310@chpset_lib.skx_ext_b(chips)!SKX_EXT_B_BGA1-IC,TBD!!!F84!VCCIN(224)!!!!
S!PVCCIN_CPU0!U5D1!BC62!@baseboard_fab2_lib.baseboard_fab2(sch_1):page37_i310@chpset_lib.skx_ext_b(chips)!SKX_EXT_B_BGA1-IC,TBD!!!F84!VCCIN(225)!!!!
S!PVCCIN_CPU0!U5D1!BC60!@baseboard_fab2_lib.baseboard_fab2(sch_1):page37_i310@chpset_lib.skx_ext_b(chips)!SKX_EXT_B_BGA1-IC,TBD!!!F84!VCCIN(226)!!!!
S!PVCCIN_CPU0!U5D1!BB85!@baseboard_fab2_lib.baseboard_fab2(sch_1):page37_i310@chpset_lib.skx_ext_b(chips)!SKX_EXT_B_BGA1-IC,TBD!!!F84!VCCIN(227)!!!!
S!PVCCIN_CPU0!U5D1!BB61!@baseboard_fab2_lib.baseboard_fab2(sch_1):page37_i310@chpset_lib.skx_ext_b(chips)!SKX_EXT_B_BGA1-IC,TBD!!!F84!VCCIN(228)!!!!
S!PVCCIN_CPU0!U5D1!BA60!@baseboard_fab2_lib.baseboard_fab2(sch_1):page37_i310@chpset_lib.skx_ext_b(chips)!SKX_EXT_B_BGA1-IC,TBD!!!F84!VCCIN(229)!!!!
S!PVCCIN_CPU0!U5D1!AY61!@baseboard_fab2_lib.baseboard_fab2(sch_1):page37_i310@chpset_lib.skx_ext_b(chips)!SKX_EXT_B_BGA1-IC,TBD!!!F84!VCCIN(230)!!!!
S!PVCCIN_CPU0!U5D1!AW60!@baseboard_fab2_lib.baseboard_fab2(sch_1):page37_i310@chpset_lib.skx_ext_b(chips)!SKX_EXT_B_BGA1-IC,TBD!!!F84!VCCIN(231)!!!!
S!PVCCIN_CPU0!U5D1!AV61!@baseboard_fab2_lib.baseboard_fab2(sch_1):page37_i310@chpset_lib.skx_ext_b(chips)!SKX_EXT_B_BGA1-IC,TBD!!!F84!VCCIN(232)!!!!
S!PVCCIN_CPU0!U5D1!AV59!@baseboard_fab2_lib.baseboard_fab2(sch_1):page37_i310@chpset_lib.skx_ext_b(chips)!SKX_EXT_B_BGA1-IC,TBD!!!F84!VCCIN(233)!!!!
S!PVCCIN_CPU0!U5D1!AU60!@baseboard_fab2_lib.baseboard_fab2(sch_1):page37_i310@chpset_lib.skx_ext_b(chips)!SKX_EXT_B_BGA1-IC,TBD!!!F84!VCCIN(234)!!!!
S!PVCCIN_CPU0!U5D1!AU58!@baseboard_fab2_lib.baseboard_fab2(sch_1):page37_i310@chpset_lib.skx_ext_b(chips)!SKX_EXT_B_BGA1-IC,TBD!!!F84!VCCIN(235)!!!!
S!PVCCIN_CPU0!U5D1!AT59!@baseboard_fab2_lib.baseboard_fab2(sch_1):page37_i310@chpset_lib.skx_ext_b(chips)!SKX_EXT_B_BGA1-IC,TBD!!!F84!VCCIN(236)!!!!
S!PVCCIN_CPU0!U5D1!AT57!@baseboard_fab2_lib.baseboard_fab2(sch_1):page37_i310@chpset_lib.skx_ext_b(chips)!SKX_EXT_B_BGA1-IC,TBD!!!F84!VCCIN(237)!!!!
S!PVCCIN_CPU0!U5D1!AR58!@baseboard_fab2_lib.baseboard_fab2(sch_1):page37_i310@chpset_lib.skx_ext_b(chips)!SKX_EXT_B_BGA1-IC,TBD!!!F84!VCCIN(238)!!!!
S!PVCCIN_CPU0!U5D1!AR56!@baseboard_fab2_lib.baseboard_fab2(sch_1):page37_i310@chpset_lib.skx_ext_b(chips)!SKX_EXT_B_BGA1-IC,TBD!!!F84!VCCIN(239)!!!!
S!PVCCIN_CPU0!U5D1!AP57!@baseboard_fab2_lib.baseboard_fab2(sch_1):page37_i310@chpset_lib.skx_ext_b(chips)!SKX_EXT_B_BGA1-IC,TBD!!!F84!VCCIN(240)!!!!
S!PVCCIN_CPU0!U5D1!AP55!@baseboard_fab2_lib.baseboard_fab2(sch_1):page37_i310@chpset_lib.skx_ext_b(chips)!SKX_EXT_B_BGA1-IC,TBD!!!F84!VCCIN(241)!!!!
S!PVCCIN_CPU0!U5D1!AN56!@baseboard_fab2_lib.baseboard_fab2(sch_1):page37_i310@chpset_lib.skx_ext_b(chips)!SKX_EXT_B_BGA1-IC,TBD!!!F84!VCCIN(242)!!!!
S!PVCCIN_CPU0!U5D1!AN54!@baseboard_fab2_lib.baseboard_fab2(sch_1):page37_i310@chpset_lib.skx_ext_b(chips)!SKX_EXT_B_BGA1-IC,TBD!!!F84!VCCIN(243)!!!!
S!PVCCIN_CPU0!U5D1!AN32!@baseboard_fab2_lib.baseboard_fab2(sch_1):page37_i310@chpset_lib.skx_ext_b(chips)!SKX_EXT_B_BGA1-IC,TBD!!!F84!VCCIN(244)!!!!
S!PVCCIN_CPU0!U5D1!AM55!@baseboard_fab2_lib.baseboard_fab2(sch_1):page37_i310@chpset_lib.skx_ext_b(chips)!SKX_EXT_B_BGA1-IC,TBD!!!F84!VCCIN(245)!!!!
S!PVCCIN_CPU0!U5D1!AM53!@baseboard_fab2_lib.baseboard_fab2(sch_1):page37_i310@chpset_lib.skx_ext_b(chips)!SKX_EXT_B_BGA1-IC,TBD!!!F84!VCCIN(246)!!!!
S!PVCCIN_CPU0!U5D1!AM33!@baseboard_fab2_lib.baseboard_fab2(sch_1):page37_i310@chpset_lib.skx_ext_b(chips)!SKX_EXT_B_BGA1-IC,TBD!!!F84!VCCIN(247)!!!!
S!PVCCIN_CPU0!U5D1!AL54!@baseboard_fab2_lib.baseboard_fab2(sch_1):page37_i310@chpset_lib.skx_ext_b(chips)!SKX_EXT_B_BGA1-IC,TBD!!!F84!VCCIN(248)!!!!
S!PVCCIN_CPU0!U5D1!AL52!@baseboard_fab2_lib.baseboard_fab2(sch_1):page37_i310@chpset_lib.skx_ext_b(chips)!SKX_EXT_B_BGA1-IC,TBD!!!F84!VCCIN(249)!!!!
S!PVCCIN_CPU0!U5D1!AL50!@baseboard_fab2_lib.baseboard_fab2(sch_1):page37_i310@chpset_lib.skx_ext_b(chips)!SKX_EXT_B_BGA1-IC,TBD!!!F84!VCCIN(250)!!!!
S!PVCCIN_CPU0!U5D1!AL48!@baseboard_fab2_lib.baseboard_fab2(sch_1):page37_i310@chpset_lib.skx_ext_b(chips)!SKX_EXT_B_BGA1-IC,TBD!!!F84!VCCIN(251)!!!!
S!PVCCIN_CPU0!U5D1!AL46!@baseboard_fab2_lib.baseboard_fab2(sch_1):page37_i310@chpset_lib.skx_ext_b(chips)!SKX_EXT_B_BGA1-IC,TBD!!!F84!VCCIN(252)!!!!
S!PVCCIN_CPU0!U5D1!AL34!@baseboard_fab2_lib.baseboard_fab2(sch_1):page37_i310@chpset_lib.skx_ext_b(chips)!SKX_EXT_B_BGA1-IC,TBD!!!F84!VCCIN(253)!!!!
S!PVCCIN_CPU0!U5D1!AK53!@baseboard_fab2_lib.baseboard_fab2(sch_1):page37_i310@chpset_lib.skx_ext_b(chips)!SKX_EXT_B_BGA1-IC,TBD!!!F84!VCCIN(254)!!!!
S!PVCCIN_CPU0!U5D1!AK51!@baseboard_fab2_lib.baseboard_fab2(sch_1):page37_i310@chpset_lib.skx_ext_b(chips)!SKX_EXT_B_BGA1-IC,TBD!!!F84!VCCIN(255)!!!!
S!PVCCIN_CPU0!U5D1!AK49!@baseboard_fab2_lib.baseboard_fab2(sch_1):page37_i310@chpset_lib.skx_ext_b(chips)!SKX_EXT_B_BGA1-IC,TBD!!!F84!VCCIN(256)!!!!
S!PVCCIN_CPU0!U5D1!AK47!@baseboard_fab2_lib.baseboard_fab2(sch_1):page37_i310@chpset_lib.skx_ext_b(chips)!SKX_EXT_B_BGA1-IC,TBD!!!F84!VCCIN(257)!!!!
S!PVCCIN_CPU0!U5D1!AK45!@baseboard_fab2_lib.baseboard_fab2(sch_1):page37_i310@chpset_lib.skx_ext_b(chips)!SKX_EXT_B_BGA1-IC,TBD!!!F84!VCCIN(258)!!!!
S!PVCCIN_CPU0!U5D1!AK35!@baseboard_fab2_lib.baseboard_fab2(sch_1):page37_i310@chpset_lib.skx_ext_b(chips)!SKX_EXT_B_BGA1-IC,TBD!!!F84!VCCIN(259)!!!!
S!PVCCIN_CPU0!U5D1!AJ36!@baseboard_fab2_lib.baseboard_fab2(sch_1):page37_i310@chpset_lib.skx_ext_b(chips)!SKX_EXT_B_BGA1-IC,TBD!!!F84!VCCIN(260)!!!!
S!PVCCIN_CPU0!U5D1!AH41!@baseboard_fab2_lib.baseboard_fab2(sch_1):page37_i310@chpset_lib.skx_ext_b(chips)!SKX_EXT_B_BGA1-IC,TBD!!!F84!VCCIN(261)!!!!
S!PVCCIN_CPU0!U5D1!AH39!@baseboard_fab2_lib.baseboard_fab2(sch_1):page37_i310@chpset_lib.skx_ext_b(chips)!SKX_EXT_B_BGA1-IC,TBD!!!F84!VCCIN(262)!!!!
S!PVCCIN_CPU0!U5D1!AH37!@baseboard_fab2_lib.baseboard_fab2(sch_1):page37_i310@chpset_lib.skx_ext_b(chips)!SKX_EXT_B_BGA1-IC,TBD!!!F84!VCCIN(263)!!!!
S!PVCCIN_CPU0!U5D1!AG42!@baseboard_fab2_lib.baseboard_fab2(sch_1):page37_i310@chpset_lib.skx_ext_b(chips)!SKX_EXT_B_BGA1-IC,TBD!!!F84!VCCIN(264)!!!!
S!PVCCIN_CPU0!U5D1!AG40!@baseboard_fab2_lib.baseboard_fab2(sch_1):page37_i310@chpset_lib.skx_ext_b(chips)!SKX_EXT_B_BGA1-IC,TBD!!!F84!VCCIN(265)!!!!
S!PVCCIN_CPU0!U5D1!AG38!@baseboard_fab2_lib.baseboard_fab2(sch_1):page37_i310@chpset_lib.skx_ext_b(chips)!SKX_EXT_B_BGA1-IC,TBD!!!F84!VCCIN(266)!!!!
S!PVCCIN_CPU0!U5D1!AF43!@baseboard_fab2_lib.baseboard_fab2(sch_1):page37_i310@chpset_lib.skx_ext_b(chips)!SKX_EXT_B_BGA1-IC,TBD!!!F84!VCCIN(267)!!!!
S!PVCCIN_CPU0!U5D1!CY49!@baseboard_fab2_lib.baseboard_fab2(sch_1):page37_i311@chpset_lib.skx_ext_b(chips)!SKX_EXT_B_BGA1-IC,TBD!!!F83!VCCIN(0)!!!!
S!PVCCIN_CPU0!U5D1!BT83!@baseboard_fab2_lib.baseboard_fab2(sch_1):page37_i311@chpset_lib.skx_ext_b(chips)!SKX_EXT_B_BGA1-IC,TBD!!!F83!VCCIN(100)!!!!
S!PVCCIN_CPU0!U5D1!BT81!@baseboard_fab2_lib.baseboard_fab2(sch_1):page37_i311@chpset_lib.skx_ext_b(chips)!SKX_EXT_B_BGA1-IC,TBD!!!F83!VCCIN(101)!!!!
S!PVCCIN_CPU0!U5D1!BT79!@baseboard_fab2_lib.baseboard_fab2(sch_1):page37_i311@chpset_lib.skx_ext_b(chips)!SKX_EXT_B_BGA1-IC,TBD!!!F83!VCCIN(102)!!!!
S!PVCCIN_CPU0!U5D1!BT77!@baseboard_fab2_lib.baseboard_fab2(sch_1):page37_i311@chpset_lib.skx_ext_b(chips)!SKX_EXT_B_BGA1-IC,TBD!!!F83!VCCIN(103)!!!!
S!PVCCIN_CPU0!U5D1!BT75!@baseboard_fab2_lib.baseboard_fab2(sch_1):page37_i311@chpset_lib.skx_ext_b(chips)!SKX_EXT_B_BGA1-IC,TBD!!!F83!VCCIN(104)!!!!
S!PVCCIN_CPU0!U5D1!BT73!@baseboard_fab2_lib.baseboard_fab2(sch_1):page37_i311@chpset_lib.skx_ext_b(chips)!SKX_EXT_B_BGA1-IC,TBD!!!F83!VCCIN(105)!!!!
S!PVCCIN_CPU0!U5D1!BT71!@baseboard_fab2_lib.baseboard_fab2(sch_1):page37_i311@chpset_lib.skx_ext_b(chips)!SKX_EXT_B_BGA1-IC,TBD!!!F83!VCCIN(106)!!!!
S!PVCCIN_CPU0!U5D1!BT69!@baseboard_fab2_lib.baseboard_fab2(sch_1):page37_i311@chpset_lib.skx_ext_b(chips)!SKX_EXT_B_BGA1-IC,TBD!!!F83!VCCIN(107)!!!!
S!PVCCIN_CPU0!U5D1!BT67!@baseboard_fab2_lib.baseboard_fab2(sch_1):page37_i311@chpset_lib.skx_ext_b(chips)!SKX_EXT_B_BGA1-IC,TBD!!!F83!VCCIN(108)!!!!
S!PVCCIN_CPU0!U5D1!BT65!@baseboard_fab2_lib.baseboard_fab2(sch_1):page37_i311@chpset_lib.skx_ext_b(chips)!SKX_EXT_B_BGA1-IC,TBD!!!F83!VCCIN(109)!!!!
S!PVCCIN_CPU0!U5D1!CU38!@baseboard_fab2_lib.baseboard_fab2(sch_1):page37_i311@chpset_lib.skx_ext_b(chips)!SKX_EXT_B_BGA1-IC,TBD!!!F83!VCCIN(10)!!!!
S!PVCCIN_CPU0!U5D1!BT63!@baseboard_fab2_lib.baseboard_fab2(sch_1):page37_i311@chpset_lib.skx_ext_b(chips)!SKX_EXT_B_BGA1-IC,TBD!!!F83!VCCIN(110)!!!!
S!PVCCIN_CPU0!U5D1!BT61!@baseboard_fab2_lib.baseboard_fab2(sch_1):page37_i311@chpset_lib.skx_ext_b(chips)!SKX_EXT_B_BGA1-IC,TBD!!!F83!VCCIN(111)!!!!
S!PVCCIN_CPU0!U5D1!BR84!@baseboard_fab2_lib.baseboard_fab2(sch_1):page37_i311@chpset_lib.skx_ext_b(chips)!SKX_EXT_B_BGA1-IC,TBD!!!F83!VCCIN(112)!!!!
S!PVCCIN_CPU0!U5D1!BR62!@baseboard_fab2_lib.baseboard_fab2(sch_1):page37_i311@chpset_lib.skx_ext_b(chips)!SKX_EXT_B_BGA1-IC,TBD!!!F83!VCCIN(113)!!!!
S!PVCCIN_CPU0!U5D1!BR60!@baseboard_fab2_lib.baseboard_fab2(sch_1):page37_i311@chpset_lib.skx_ext_b(chips)!SKX_EXT_B_BGA1-IC,TBD!!!F83!VCCIN(114)!!!!
S!PVCCIN_CPU0!U5D1!BP83!@baseboard_fab2_lib.baseboard_fab2(sch_1):page37_i311@chpset_lib.skx_ext_b(chips)!SKX_EXT_B_BGA1-IC,TBD!!!F83!VCCIN(115)!!!!
S!PVCCIN_CPU0!U5D1!BP81!@baseboard_fab2_lib.baseboard_fab2(sch_1):page37_i311@chpset_lib.skx_ext_b(chips)!SKX_EXT_B_BGA1-IC,TBD!!!F83!VCCIN(116)!!!!
S!PVCCIN_CPU0!U5D1!BP79!@baseboard_fab2_lib.baseboard_fab2(sch_1):page37_i311@chpset_lib.skx_ext_b(chips)!SKX_EXT_B_BGA1-IC,TBD!!!F83!VCCIN(117)!!!!
S!PVCCIN_CPU0!U5D1!BP77!@baseboard_fab2_lib.baseboard_fab2(sch_1):page37_i311@chpset_lib.skx_ext_b(chips)!SKX_EXT_B_BGA1-IC,TBD!!!F83!VCCIN(118)!!!!
S!PVCCIN_CPU0!U5D1!BP75!@baseboard_fab2_lib.baseboard_fab2(sch_1):page37_i311@chpset_lib.skx_ext_b(chips)!SKX_EXT_B_BGA1-IC,TBD!!!F83!VCCIN(119)!!!!
S!PVCCIN_CPU0!U5D1!CT55!@baseboard_fab2_lib.baseboard_fab2(sch_1):page37_i311@chpset_lib.skx_ext_b(chips)!SKX_EXT_B_BGA1-IC,TBD!!!F83!VCCIN(11)!!!!
S!PVCCIN_CPU0!U5D1!BP73!@baseboard_fab2_lib.baseboard_fab2(sch_1):page37_i311@chpset_lib.skx_ext_b(chips)!SKX_EXT_B_BGA1-IC,TBD!!!F83!VCCIN(120)!!!!
S!PVCCIN_CPU0!U5D1!BP71!@baseboard_fab2_lib.baseboard_fab2(sch_1):page37_i311@chpset_lib.skx_ext_b(chips)!SKX_EXT_B_BGA1-IC,TBD!!!F83!VCCIN(121)!!!!
S!PVCCIN_CPU0!U5D1!BP69!@baseboard_fab2_lib.baseboard_fab2(sch_1):page37_i311@chpset_lib.skx_ext_b(chips)!SKX_EXT_B_BGA1-IC,TBD!!!F83!VCCIN(122)!!!!
S!PVCCIN_CPU0!U5D1!BP67!@baseboard_fab2_lib.baseboard_fab2(sch_1):page37_i311@chpset_lib.skx_ext_b(chips)!SKX_EXT_B_BGA1-IC,TBD!!!F83!VCCIN(123)!!!!
S!PVCCIN_CPU0!U5D1!BP65!@baseboard_fab2_lib.baseboard_fab2(sch_1):page37_i311@chpset_lib.skx_ext_b(chips)!SKX_EXT_B_BGA1-IC,TBD!!!F83!VCCIN(124)!!!!
S!PVCCIN_CPU0!U5D1!BP63!@baseboard_fab2_lib.baseboard_fab2(sch_1):page37_i311@chpset_lib.skx_ext_b(chips)!SKX_EXT_B_BGA1-IC,TBD!!!F83!VCCIN(125)!!!!
S!PVCCIN_CPU0!U5D1!BP61!@baseboard_fab2_lib.baseboard_fab2(sch_1):page37_i311@chpset_lib.skx_ext_b(chips)!SKX_EXT_B_BGA1-IC,TBD!!!F83!VCCIN(126)!!!!
S!PVCCIN_CPU0!U5D1!BN84!@baseboard_fab2_lib.baseboard_fab2(sch_1):page37_i311@chpset_lib.skx_ext_b(chips)!SKX_EXT_B_BGA1-IC,TBD!!!F83!VCCIN(127)!!!!
S!PVCCIN_CPU0!U5D1!BN82!@baseboard_fab2_lib.baseboard_fab2(sch_1):page37_i311@chpset_lib.skx_ext_b(chips)!SKX_EXT_B_BGA1-IC,TBD!!!F83!VCCIN(128)!!!!
S!PVCCIN_CPU0!U5D1!BN80!@baseboard_fab2_lib.baseboard_fab2(sch_1):page37_i311@chpset_lib.skx_ext_b(chips)!SKX_EXT_B_BGA1-IC,TBD!!!F83!VCCIN(129)!!!!
S!PVCCIN_CPU0!U5D1!CT53!@baseboard_fab2_lib.baseboard_fab2(sch_1):page37_i311@chpset_lib.skx_ext_b(chips)!SKX_EXT_B_BGA1-IC,TBD!!!F83!VCCIN(12)!!!!
S!PVCCIN_CPU0!U5D1!CT41!@baseboard_fab2_lib.baseboard_fab2(sch_1):page37_i311@chpset_lib.skx_ext_b(chips)!SKX_EXT_B_BGA1-IC,TBD!!!F83!VCCIN(13)!!!!
S!PVCCIN_CPU0!U5D1!CT39!@baseboard_fab2_lib.baseboard_fab2(sch_1):page37_i311@chpset_lib.skx_ext_b(chips)!SKX_EXT_B_BGA1-IC,TBD!!!F83!VCCIN(14)!!!!
S!PVCCIN_CPU0!U5D1!CT37!@baseboard_fab2_lib.baseboard_fab2(sch_1):page37_i311@chpset_lib.skx_ext_b(chips)!SKX_EXT_B_BGA1-IC,TBD!!!F83!VCCIN(15)!!!!
S!PVCCIN_CPU0!U5D1!CR56!@baseboard_fab2_lib.baseboard_fab2(sch_1):page37_i311@chpset_lib.skx_ext_b(chips)!SKX_EXT_B_BGA1-IC,TBD!!!F83!VCCIN(16)!!!!
S!PVCCIN_CPU0!U5D1!CR54!@baseboard_fab2_lib.baseboard_fab2(sch_1):page37_i311@chpset_lib.skx_ext_b(chips)!SKX_EXT_B_BGA1-IC,TBD!!!F83!VCCIN(17)!!!!
S!PVCCIN_CPU0!U5D1!CR34!@baseboard_fab2_lib.baseboard_fab2(sch_1):page37_i311@chpset_lib.skx_ext_b(chips)!SKX_EXT_B_BGA1-IC,TBD!!!F83!VCCIN(18)!!!!
S!PVCCIN_CPU0!U5D1!CP57!@baseboard_fab2_lib.baseboard_fab2(sch_1):page37_i311@chpset_lib.skx_ext_b(chips)!SKX_EXT_B_BGA1-IC,TBD!!!F83!VCCIN(19)!!!!
S!PVCCIN_CPU0!U5D1!CY47!@baseboard_fab2_lib.baseboard_fab2(sch_1):page37_i311@chpset_lib.skx_ext_b(chips)!SKX_EXT_B_BGA1-IC,TBD!!!F83!VCCIN(1)!!!!
S!PVCCIN_CPU0!U5D1!CP55!@baseboard_fab2_lib.baseboard_fab2(sch_1):page37_i311@chpset_lib.skx_ext_b(chips)!SKX_EXT_B_BGA1-IC,TBD!!!F83!VCCIN(20)!!!!
S!PVCCIN_CPU0!U5D1!CP33!@baseboard_fab2_lib.baseboard_fab2(sch_1):page37_i311@chpset_lib.skx_ext_b(chips)!SKX_EXT_B_BGA1-IC,TBD!!!F83!VCCIN(21)!!!!
S!PVCCIN_CPU0!U5D1!CN58!@baseboard_fab2_lib.baseboard_fab2(sch_1):page37_i311@chpset_lib.skx_ext_b(chips)!SKX_EXT_B_BGA1-IC,TBD!!!F83!VCCIN(22)!!!!
S!PVCCIN_CPU0!U5D1!CN56!@baseboard_fab2_lib.baseboard_fab2(sch_1):page37_i311@chpset_lib.skx_ext_b(chips)!SKX_EXT_B_BGA1-IC,TBD!!!F83!VCCIN(23)!!!!
S!PVCCIN_CPU0!U5D1!CM59!@baseboard_fab2_lib.baseboard_fab2(sch_1):page37_i311@chpset_lib.skx_ext_b(chips)!SKX_EXT_B_BGA1-IC,TBD!!!F83!VCCIN(24)!!!!
S!PVCCIN_CPU0!U5D1!CM57!@baseboard_fab2_lib.baseboard_fab2(sch_1):page37_i311@chpset_lib.skx_ext_b(chips)!SKX_EXT_B_BGA1-IC,TBD!!!F83!VCCIN(25)!!!!
S!PVCCIN_CPU0!U5D1!CL60!@baseboard_fab2_lib.baseboard_fab2(sch_1):page37_i311@chpset_lib.skx_ext_b(chips)!SKX_EXT_B_BGA1-IC,TBD!!!F83!VCCIN(26)!!!!
S!PVCCIN_CPU0!U5D1!CL58!@baseboard_fab2_lib.baseboard_fab2(sch_1):page37_i311@chpset_lib.skx_ext_b(chips)!SKX_EXT_B_BGA1-IC,TBD!!!F83!VCCIN(27)!!!!
S!PVCCIN_CPU0!U5D1!CK61!@baseboard_fab2_lib.baseboard_fab2(sch_1):page37_i311@chpset_lib.skx_ext_b(chips)!SKX_EXT_B_BGA1-IC,TBD!!!F83!VCCIN(28)!!!!
S!PVCCIN_CPU0!U5D1!CK59!@baseboard_fab2_lib.baseboard_fab2(sch_1):page37_i311@chpset_lib.skx_ext_b(chips)!SKX_EXT_B_BGA1-IC,TBD!!!F83!VCCIN(29)!!!!
S!PVCCIN_CPU0!U5D1!CW50!@baseboard_fab2_lib.baseboard_fab2(sch_1):page37_i311@chpset_lib.skx_ext_b(chips)!SKX_EXT_B_BGA1-IC,TBD!!!F83!VCCIN(2)!!!!
S!PVCCIN_CPU0!U5D1!CJ60!@baseboard_fab2_lib.baseboard_fab2(sch_1):page37_i311@chpset_lib.skx_ext_b(chips)!SKX_EXT_B_BGA1-IC,TBD!!!F83!VCCIN(30)!!!!
S!PVCCIN_CPU0!U5D1!CH85!@baseboard_fab2_lib.baseboard_fab2(sch_1):page37_i311@chpset_lib.skx_ext_b(chips)!SKX_EXT_B_BGA1-IC,TBD!!!F83!VCCIN(31)!!!!
S!PVCCIN_CPU0!U5D1!CH61!@baseboard_fab2_lib.baseboard_fab2(sch_1):page37_i311@chpset_lib.skx_ext_b(chips)!SKX_EXT_B_BGA1-IC,TBD!!!F83!VCCIN(32)!!!!
S!PVCCIN_CPU0!U5D1!CG84!@baseboard_fab2_lib.baseboard_fab2(sch_1):page37_i311@chpset_lib.skx_ext_b(chips)!SKX_EXT_B_BGA1-IC,TBD!!!F83!VCCIN(33)!!!!
S!PVCCIN_CPU0!U5D1!CG60!@baseboard_fab2_lib.baseboard_fab2(sch_1):page37_i311@chpset_lib.skx_ext_b(chips)!SKX_EXT_B_BGA1-IC,TBD!!!F83!VCCIN(34)!!!!
S!PVCCIN_CPU0!U5D1!CF85!@baseboard_fab2_lib.baseboard_fab2(sch_1):page37_i311@chpset_lib.skx_ext_b(chips)!SKX_EXT_B_BGA1-IC,TBD!!!F83!VCCIN(35)!!!!
S!PVCCIN_CPU0!U5D1!CF61!@baseboard_fab2_lib.baseboard_fab2(sch_1):page37_i311@chpset_lib.skx_ext_b(chips)!SKX_EXT_B_BGA1-IC,TBD!!!F83!VCCIN(36)!!!!
S!PVCCIN_CPU0!U5D1!CE84!@baseboard_fab2_lib.baseboard_fab2(sch_1):page37_i311@chpset_lib.skx_ext_b(chips)!SKX_EXT_B_BGA1-IC,TBD!!!F83!VCCIN(37)!!!!
S!PVCCIN_CPU0!U5D1!CE60!@baseboard_fab2_lib.baseboard_fab2(sch_1):page37_i311@chpset_lib.skx_ext_b(chips)!SKX_EXT_B_BGA1-IC,TBD!!!F83!VCCIN(38)!!!!
S!PVCCIN_CPU0!U5D1!CD85!@baseboard_fab2_lib.baseboard_fab2(sch_1):page37_i311@chpset_lib.skx_ext_b(chips)!SKX_EXT_B_BGA1-IC,TBD!!!F83!VCCIN(39)!!!!
S!PVCCIN_CPU0!U5D1!CW48!@baseboard_fab2_lib.baseboard_fab2(sch_1):page37_i311@chpset_lib.skx_ext_b(chips)!SKX_EXT_B_BGA1-IC,TBD!!!F83!VCCIN(3)!!!!
S!PVCCIN_CPU0!U5D1!CD83!@baseboard_fab2_lib.baseboard_fab2(sch_1):page37_i311@chpset_lib.skx_ext_b(chips)!SKX_EXT_B_BGA1-IC,TBD!!!F83!VCCIN(40)!!!!
S!PVCCIN_CPU0!U5D1!CD61!@baseboard_fab2_lib.baseboard_fab2(sch_1):page37_i311@chpset_lib.skx_ext_b(chips)!SKX_EXT_B_BGA1-IC,TBD!!!F83!VCCIN(41)!!!!
S!PVCCIN_CPU0!U5D1!CC84!@baseboard_fab2_lib.baseboard_fab2(sch_1):page37_i311@chpset_lib.skx_ext_b(chips)!SKX_EXT_B_BGA1-IC,TBD!!!F83!VCCIN(42)!!!!
S!PVCCIN_CPU0!U5D1!CC62!@baseboard_fab2_lib.baseboard_fab2(sch_1):page37_i311@chpset_lib.skx_ext_b(chips)!SKX_EXT_B_BGA1-IC,TBD!!!F83!VCCIN(43)!!!!
S!PVCCIN_CPU0!U5D1!CC60!@baseboard_fab2_lib.baseboard_fab2(sch_1):page37_i311@chpset_lib.skx_ext_b(chips)!SKX_EXT_B_BGA1-IC,TBD!!!F83!VCCIN(44)!!!!
S!PVCCIN_CPU0!U5D1!CB83!@baseboard_fab2_lib.baseboard_fab2(sch_1):page37_i311@chpset_lib.skx_ext_b(chips)!SKX_EXT_B_BGA1-IC,TBD!!!F83!VCCIN(45)!!!!
S!PVCCIN_CPU0!U5D1!CB81!@baseboard_fab2_lib.baseboard_fab2(sch_1):page37_i311@chpset_lib.skx_ext_b(chips)!SKX_EXT_B_BGA1-IC,TBD!!!F83!VCCIN(46)!!!!
S!PVCCIN_CPU0!U5D1!CB79!@baseboard_fab2_lib.baseboard_fab2(sch_1):page37_i311@chpset_lib.skx_ext_b(chips)!SKX_EXT_B_BGA1-IC,TBD!!!F83!VCCIN(47)!!!!
S!PVCCIN_CPU0!U5D1!CB77!@baseboard_fab2_lib.baseboard_fab2(sch_1):page37_i311@chpset_lib.skx_ext_b(chips)!SKX_EXT_B_BGA1-IC,TBD!!!F83!VCCIN(48)!!!!
S!PVCCIN_CPU0!U5D1!CB75!@baseboard_fab2_lib.baseboard_fab2(sch_1):page37_i311@chpset_lib.skx_ext_b(chips)!SKX_EXT_B_BGA1-IC,TBD!!!F83!VCCIN(49)!!!!
S!PVCCIN_CPU0!U5D1!CW46!@baseboard_fab2_lib.baseboard_fab2(sch_1):page37_i311@chpset_lib.skx_ext_b(chips)!SKX_EXT_B_BGA1-IC,TBD!!!F83!VCCIN(4)!!!!
S!PVCCIN_CPU0!U5D1!CB73!@baseboard_fab2_lib.baseboard_fab2(sch_1):page37_i311@chpset_lib.skx_ext_b(chips)!SKX_EXT_B_BGA1-IC,TBD!!!F83!VCCIN(50)!!!!
S!PVCCIN_CPU0!U5D1!CB61!@baseboard_fab2_lib.baseboard_fab2(sch_1):page37_i311@chpset_lib.skx_ext_b(chips)!SKX_EXT_B_BGA1-IC,TBD!!!F83!VCCIN(51)!!!!
S!PVCCIN_CPU0!U5D1!CA84!@baseboard_fab2_lib.baseboard_fab2(sch_1):page37_i311@chpset_lib.skx_ext_b(chips)!SKX_EXT_B_BGA1-IC,TBD!!!F83!VCCIN(52)!!!!
S!PVCCIN_CPU0!U5D1!CA82!@baseboard_fab2_lib.baseboard_fab2(sch_1):page37_i311@chpset_lib.skx_ext_b(chips)!SKX_EXT_B_BGA1-IC,TBD!!!F83!VCCIN(53)!!!!
S!PVCCIN_CPU0!U5D1!CA80!@baseboard_fab2_lib.baseboard_fab2(sch_1):page37_i311@chpset_lib.skx_ext_b(chips)!SKX_EXT_B_BGA1-IC,TBD!!!F83!VCCIN(54)!!!!
S!PVCCIN_CPU0!U5D1!CA78!@baseboard_fab2_lib.baseboard_fab2(sch_1):page37_i311@chpset_lib.skx_ext_b(chips)!SKX_EXT_B_BGA1-IC,TBD!!!F83!VCCIN(55)!!!!
S!PVCCIN_CPU0!U5D1!CA76!@baseboard_fab2_lib.baseboard_fab2(sch_1):page37_i311@chpset_lib.skx_ext_b(chips)!SKX_EXT_B_BGA1-IC,TBD!!!F83!VCCIN(56)!!!!
S!PVCCIN_CPU0!U5D1!CA74!@baseboard_fab2_lib.baseboard_fab2(sch_1):page37_i311@chpset_lib.skx_ext_b(chips)!SKX_EXT_B_BGA1-IC,TBD!!!F83!VCCIN(57)!!!!
S!PVCCIN_CPU0!U5D1!CA72!@baseboard_fab2_lib.baseboard_fab2(sch_1):page37_i311@chpset_lib.skx_ext_b(chips)!SKX_EXT_B_BGA1-IC,TBD!!!F83!VCCIN(58)!!!!
S!PVCCIN_CPU0!U5D1!CA62!@baseboard_fab2_lib.baseboard_fab2(sch_1):page37_i311@chpset_lib.skx_ext_b(chips)!SKX_EXT_B_BGA1-IC,TBD!!!F83!VCCIN(59)!!!!
S!PVCCIN_CPU0!U5D1!CV51!@baseboard_fab2_lib.baseboard_fab2(sch_1):page37_i311@chpset_lib.skx_ext_b(chips)!SKX_EXT_B_BGA1-IC,TBD!!!F83!VCCIN(5)!!!!
S!PVCCIN_CPU0!U5D1!CA60!@baseboard_fab2_lib.baseboard_fab2(sch_1):page37_i311@chpset_lib.skx_ext_b(chips)!SKX_EXT_B_BGA1-IC,TBD!!!F83!VCCIN(60)!!!!
S!PVCCIN_CPU0!U5D1!BY83!@baseboard_fab2_lib.baseboard_fab2(sch_1):page37_i311@chpset_lib.skx_ext_b(chips)!SKX_EXT_B_BGA1-IC,TBD!!!F83!VCCIN(61)!!!!
S!PVCCIN_CPU0!U5D1!BY81!@baseboard_fab2_lib.baseboard_fab2(sch_1):page37_i311@chpset_lib.skx_ext_b(chips)!SKX_EXT_B_BGA1-IC,TBD!!!F83!VCCIN(62)!!!!
S!PVCCIN_CPU0!U5D1!BY79!@baseboard_fab2_lib.baseboard_fab2(sch_1):page37_i311@chpset_lib.skx_ext_b(chips)!SKX_EXT_B_BGA1-IC,TBD!!!F83!VCCIN(63)!!!!
S!PVCCIN_CPU0!U5D1!BY77!@baseboard_fab2_lib.baseboard_fab2(sch_1):page37_i311@chpset_lib.skx_ext_b(chips)!SKX_EXT_B_BGA1-IC,TBD!!!F83!VCCIN(64)!!!!
S!PVCCIN_CPU0!U5D1!BY75!@baseboard_fab2_lib.baseboard_fab2(sch_1):page37_i311@chpset_lib.skx_ext_b(chips)!SKX_EXT_B_BGA1-IC,TBD!!!F83!VCCIN(65)!!!!
S!PVCCIN_CPU0!U5D1!BY73!@baseboard_fab2_lib.baseboard_fab2(sch_1):page37_i311@chpset_lib.skx_ext_b(chips)!SKX_EXT_B_BGA1-IC,TBD!!!F83!VCCIN(66)!!!!
S!PVCCIN_CPU0!U5D1!BY61!@baseboard_fab2_lib.baseboard_fab2(sch_1):page37_i311@chpset_lib.skx_ext_b(chips)!SKX_EXT_B_BGA1-IC,TBD!!!F83!VCCIN(67)!!!!
S!PVCCIN_CPU0!U5D1!BW84!@baseboard_fab2_lib.baseboard_fab2(sch_1):page37_i311@chpset_lib.skx_ext_b(chips)!SKX_EXT_B_BGA1-IC,TBD!!!F83!VCCIN(68)!!!!
S!PVCCIN_CPU0!U5D1!BW70!@baseboard_fab2_lib.baseboard_fab2(sch_1):page37_i311@chpset_lib.skx_ext_b(chips)!SKX_EXT_B_BGA1-IC,TBD!!!F83!VCCIN(69)!!!!
S!PVCCIN_CPU0!U5D1!CU54!@baseboard_fab2_lib.baseboard_fab2(sch_1):page37_i311@chpset_lib.skx_ext_b(chips)!SKX_EXT_B_BGA1-IC,TBD!!!F83!VCCIN(6)!!!!
S!PVCCIN_CPU0!U5D1!BW68!@baseboard_fab2_lib.baseboard_fab2(sch_1):page37_i311@chpset_lib.skx_ext_b(chips)!SKX_EXT_B_BGA1-IC,TBD!!!F83!VCCIN(70)!!!!
S!PVCCIN_CPU0!U5D1!BW66!@baseboard_fab2_lib.baseboard_fab2(sch_1):page37_i311@chpset_lib.skx_ext_b(chips)!SKX_EXT_B_BGA1-IC,TBD!!!F83!VCCIN(71)!!!!
S!PVCCIN_CPU0!U5D1!BW64!@baseboard_fab2_lib.baseboard_fab2(sch_1):page37_i311@chpset_lib.skx_ext_b(chips)!SKX_EXT_B_BGA1-IC,TBD!!!F83!VCCIN(72)!!!!
S!PVCCIN_CPU0!U5D1!BW62!@baseboard_fab2_lib.baseboard_fab2(sch_1):page37_i311@chpset_lib.skx_ext_b(chips)!SKX_EXT_B_BGA1-IC,TBD!!!F83!VCCIN(73)!!!!
S!PVCCIN_CPU0!U5D1!BW60!@baseboard_fab2_lib.baseboard_fab2(sch_1):page37_i311@chpset_lib.skx_ext_b(chips)!SKX_EXT_B_BGA1-IC,TBD!!!F83!VCCIN(74)!!!!
S!PVCCIN_CPU0!U5D1!BV83!@baseboard_fab2_lib.baseboard_fab2(sch_1):page37_i311@chpset_lib.skx_ext_b(chips)!SKX_EXT_B_BGA1-IC,TBD!!!F83!VCCIN(75)!!!!
S!PVCCIN_CPU0!U5D1!BV81!@baseboard_fab2_lib.baseboard_fab2(sch_1):page37_i311@chpset_lib.skx_ext_b(chips)!SKX_EXT_B_BGA1-IC,TBD!!!F83!VCCIN(76)!!!!
S!PVCCIN_CPU0!U5D1!BV79!@baseboard_fab2_lib.baseboard_fab2(sch_1):page37_i311@chpset_lib.skx_ext_b(chips)!SKX_EXT_B_BGA1-IC,TBD!!!F83!VCCIN(77)!!!!
S!PVCCIN_CPU0!U5D1!BV77!@baseboard_fab2_lib.baseboard_fab2(sch_1):page37_i311@chpset_lib.skx_ext_b(chips)!SKX_EXT_B_BGA1-IC,TBD!!!F83!VCCIN(78)!!!!
S!PVCCIN_CPU0!U5D1!BV75!@baseboard_fab2_lib.baseboard_fab2(sch_1):page37_i311@chpset_lib.skx_ext_b(chips)!SKX_EXT_B_BGA1-IC,TBD!!!F83!VCCIN(79)!!!!
S!PVCCIN_CPU0!U5D1!CU52!@baseboard_fab2_lib.baseboard_fab2(sch_1):page37_i311@chpset_lib.skx_ext_b(chips)!SKX_EXT_B_BGA1-IC,TBD!!!F83!VCCIN(7)!!!!
S!PVCCIN_CPU0!U5D1!BV73!@baseboard_fab2_lib.baseboard_fab2(sch_1):page37_i311@chpset_lib.skx_ext_b(chips)!SKX_EXT_B_BGA1-IC,TBD!!!F83!VCCIN(80)!!!!
S!PVCCIN_CPU0!U5D1!BV71!@baseboard_fab2_lib.baseboard_fab2(sch_1):page37_i311@chpset_lib.skx_ext_b(chips)!SKX_EXT_B_BGA1-IC,TBD!!!F83!VCCIN(81)!!!!
S!PVCCIN_CPU0!U5D1!BV69!@baseboard_fab2_lib.baseboard_fab2(sch_1):page37_i311@chpset_lib.skx_ext_b(chips)!SKX_EXT_B_BGA1-IC,TBD!!!F83!VCCIN(82)!!!!
S!PVCCIN_CPU0!U5D1!BV67!@baseboard_fab2_lib.baseboard_fab2(sch_1):page37_i311@chpset_lib.skx_ext_b(chips)!SKX_EXT_B_BGA1-IC,TBD!!!F83!VCCIN(83)!!!!
S!PVCCIN_CPU0!U5D1!BV65!@baseboard_fab2_lib.baseboard_fab2(sch_1):page37_i311@chpset_lib.skx_ext_b(chips)!SKX_EXT_B_BGA1-IC,TBD!!!F83!VCCIN(84)!!!!
S!PVCCIN_CPU0!U5D1!BV63!@baseboard_fab2_lib.baseboard_fab2(sch_1):page37_i311@chpset_lib.skx_ext_b(chips)!SKX_EXT_B_BGA1-IC,TBD!!!F83!VCCIN(85)!!!!
S!PVCCIN_CPU0!U5D1!BV61!@baseboard_fab2_lib.baseboard_fab2(sch_1):page37_i311@chpset_lib.skx_ext_b(chips)!SKX_EXT_B_BGA1-IC,TBD!!!F83!VCCIN(86)!!!!
S!PVCCIN_CPU0!U5D1!BU84!@baseboard_fab2_lib.baseboard_fab2(sch_1):page37_i311@chpset_lib.skx_ext_b(chips)!SKX_EXT_B_BGA1-IC,TBD!!!F83!VCCIN(87)!!!!
S!PVCCIN_CPU0!U5D1!BU82!@baseboard_fab2_lib.baseboard_fab2(sch_1):page37_i311@chpset_lib.skx_ext_b(chips)!SKX_EXT_B_BGA1-IC,TBD!!!F83!VCCIN(88)!!!!
S!PVCCIN_CPU0!U5D1!BU80!@baseboard_fab2_lib.baseboard_fab2(sch_1):page37_i311@chpset_lib.skx_ext_b(chips)!SKX_EXT_B_BGA1-IC,TBD!!!F83!VCCIN(89)!!!!
S!PVCCIN_CPU0!U5D1!CU42!@baseboard_fab2_lib.baseboard_fab2(sch_1):page37_i311@chpset_lib.skx_ext_b(chips)!SKX_EXT_B_BGA1-IC,TBD!!!F83!VCCIN(8)!!!!
S!PVCCIN_CPU0!U5D1!BU78!@baseboard_fab2_lib.baseboard_fab2(sch_1):page37_i311@chpset_lib.skx_ext_b(chips)!SKX_EXT_B_BGA1-IC,TBD!!!F83!VCCIN(90)!!!!
S!PVCCIN_CPU0!U5D1!BU76!@baseboard_fab2_lib.baseboard_fab2(sch_1):page37_i311@chpset_lib.skx_ext_b(chips)!SKX_EXT_B_BGA1-IC,TBD!!!F83!VCCIN(91)!!!!
S!PVCCIN_CPU0!U5D1!BU74!@baseboard_fab2_lib.baseboard_fab2(sch_1):page37_i311@chpset_lib.skx_ext_b(chips)!SKX_EXT_B_BGA1-IC,TBD!!!F83!VCCIN(92)!!!!
S!PVCCIN_CPU0!U5D1!BU72!@baseboard_fab2_lib.baseboard_fab2(sch_1):page37_i311@chpset_lib.skx_ext_b(chips)!SKX_EXT_B_BGA1-IC,TBD!!!F83!VCCIN(93)!!!!
S!PVCCIN_CPU0!U5D1!BU70!@baseboard_fab2_lib.baseboard_fab2(sch_1):page37_i311@chpset_lib.skx_ext_b(chips)!SKX_EXT_B_BGA1-IC,TBD!!!F83!VCCIN(94)!!!!
S!PVCCIN_CPU0!U5D1!BU68!@baseboard_fab2_lib.baseboard_fab2(sch_1):page37_i311@chpset_lib.skx_ext_b(chips)!SKX_EXT_B_BGA1-IC,TBD!!!F83!VCCIN(95)!!!!
S!PVCCIN_CPU0!U5D1!BU66!@baseboard_fab2_lib.baseboard_fab2(sch_1):page37_i311@chpset_lib.skx_ext_b(chips)!SKX_EXT_B_BGA1-IC,TBD!!!F83!VCCIN(96)!!!!
S!PVCCIN_CPU0!U5D1!BU64!@baseboard_fab2_lib.baseboard_fab2(sch_1):page37_i311@chpset_lib.skx_ext_b(chips)!SKX_EXT_B_BGA1-IC,TBD!!!F83!VCCIN(97)!!!!
S!PVCCIN_CPU0!U5D1!BU62!@baseboard_fab2_lib.baseboard_fab2(sch_1):page37_i311@chpset_lib.skx_ext_b(chips)!SKX_EXT_B_BGA1-IC,TBD!!!F83!VCCIN(98)!!!!
S!PVCCIN_CPU0!U5D1!BU60!@baseboard_fab2_lib.baseboard_fab2(sch_1):page37_i311@chpset_lib.skx_ext_b(chips)!SKX_EXT_B_BGA1-IC,TBD!!!F83!VCCIN(99)!!!!
S!PVCCIN_CPU0!U5D1!CU40!@baseboard_fab2_lib.baseboard_fab2(sch_1):page37_i311@chpset_lib.skx_ext_b(chips)!SKX_EXT_B_BGA1-IC,TBD!!!F83!VCCIN(9)!!!!
S!VSENSE_VCCINR2PMAX_CPU0!U5D1!AW86!@baseboard_fab2_lib.baseboard_fab2(sch_1):page37_i311@chpset_lib.skx_ext_b(chips)!SKX_EXT_B_BGA1-IC,TBD!!!F83!VCCINPMAX(0)!!!!
S!VSENSE_VCCINR2PMAX_CPU0!U5D1!AV85!@baseboard_fab2_lib.baseboard_fab2(sch_1):page37_i311@chpset_lib.skx_ext_b(chips)!SKX_EXT_B_BGA1-IC,TBD!!!F83!VCCINPMAX(1)!!!!
S!VSENSE_PVCCIN_CPU0_SKT_VSEN!U5D1!BA86!@baseboard_fab2_lib.baseboard_fab2(sch_1):page37_i311@chpset_lib.skx_ext_b(chips)!SKX_EXT_B_BGA1-IC,TBD!!!F83!VCCIN_SENSE!!!!
S!TP_CPU0_RSVD_255!U5D1!AY83!@baseboard_fab2_lib.baseboard_fab2(sch_1):page36_i15@chpset_lib.skx_ext_b(chips)!SKX_EXT_B_BGA1-IC,TBD!!!F86!RSVD(255)!!!!
S!VSENSE_PVCCIN_CPU0_SKT_VRTN!U5D1!AY85!@baseboard_fab2_lib.baseboard_fab2(sch_1):page37_i311@chpset_lib.skx_ext_b(chips)!SKX_EXT_B_BGA1-IC,TBD!!!F83!VSS_VCCIN_SENSE!!!!
S!PVDDQ_ABC!U5D1!B49!@baseboard_fab2_lib.baseboard_fab2(sch_1):page38_i33@chpset_lib.skx_ext_b(chips)!SKX_EXT_B_BGA1-IC,TBD!!!F82!VCCD012(0)!!!!
S!PVDDQ_ABC!U5D1!E60!@baseboard_fab2_lib.baseboard_fab2(sch_1):page38_i33@chpset_lib.skx_ext_b(chips)!SKX_EXT_B_BGA1-IC,TBD!!!F82!VCCD012(10)!!!!
S!PVDDQ_ABC!U5D1!E62!@baseboard_fab2_lib.baseboard_fab2(sch_1):page38_i33@chpset_lib.skx_ext_b(chips)!SKX_EXT_B_BGA1-IC,TBD!!!F82!VCCD012(11)!!!!
S!PVDDQ_ABC!U5D1!E64!@baseboard_fab2_lib.baseboard_fab2(sch_1):page38_i33@chpset_lib.skx_ext_b(chips)!SKX_EXT_B_BGA1-IC,TBD!!!F82!VCCD012(12)!!!!
S!PVDDQ_ABC!U5D1!L46!@baseboard_fab2_lib.baseboard_fab2(sch_1):page38_i33@chpset_lib.skx_ext_b(chips)!SKX_EXT_B_BGA1-IC,TBD!!!F82!VCCD012(13)!!!!
S!PVDDQ_ABC!U5D1!L48!@baseboard_fab2_lib.baseboard_fab2(sch_1):page38_i33@chpset_lib.skx_ext_b(chips)!SKX_EXT_B_BGA1-IC,TBD!!!F82!VCCD012(14)!!!!
S!PVDDQ_ABC!U5D1!L50!@baseboard_fab2_lib.baseboard_fab2(sch_1):page38_i33@chpset_lib.skx_ext_b(chips)!SKX_EXT_B_BGA1-IC,TBD!!!F82!VCCD012(15)!!!!
S!PVDDQ_ABC!U5D1!L52!@baseboard_fab2_lib.baseboard_fab2(sch_1):page38_i33@chpset_lib.skx_ext_b(chips)!SKX_EXT_B_BGA1-IC,TBD!!!F82!VCCD012(16)!!!!
S!PVDDQ_ABC!U5D1!L54!@baseboard_fab2_lib.baseboard_fab2(sch_1):page38_i33@chpset_lib.skx_ext_b(chips)!SKX_EXT_B_BGA1-IC,TBD!!!F82!VCCD012(17)!!!!
S!PVDDQ_ABC!U5D1!L56!@baseboard_fab2_lib.baseboard_fab2(sch_1):page38_i33@chpset_lib.skx_ext_b(chips)!SKX_EXT_B_BGA1-IC,TBD!!!F82!VCCD012(18)!!!!
S!PVDDQ_ABC!U5D1!L58!@baseboard_fab2_lib.baseboard_fab2(sch_1):page38_i33@chpset_lib.skx_ext_b(chips)!SKX_EXT_B_BGA1-IC,TBD!!!F82!VCCD012(19)!!!!
S!PVDDQ_ABC!U5D1!B53!@baseboard_fab2_lib.baseboard_fab2(sch_1):page38_i33@chpset_lib.skx_ext_b(chips)!SKX_EXT_B_BGA1-IC,TBD!!!F82!VCCD012(1)!!!!
S!PVDDQ_ABC!U5D1!L60!@baseboard_fab2_lib.baseboard_fab2(sch_1):page38_i33@chpset_lib.skx_ext_b(chips)!SKX_EXT_B_BGA1-IC,TBD!!!F82!VCCD012(20)!!!!
S!PVDDQ_ABC!U5D1!L62!@baseboard_fab2_lib.baseboard_fab2(sch_1):page38_i33@chpset_lib.skx_ext_b(chips)!SKX_EXT_B_BGA1-IC,TBD!!!F82!VCCD012(21)!!!!
S!PVDDQ_ABC!U5D1!N64!@baseboard_fab2_lib.baseboard_fab2(sch_1):page38_i33@chpset_lib.skx_ext_b(chips)!SKX_EXT_B_BGA1-IC,TBD!!!F82!VCCD012(22)!!!!
S!PVDDQ_ABC!U5D1!U46!@baseboard_fab2_lib.baseboard_fab2(sch_1):page38_i33@chpset_lib.skx_ext_b(chips)!SKX_EXT_B_BGA1-IC,TBD!!!F82!VCCD012(23)!!!!
S!PVDDQ_ABC!U5D1!U48!@baseboard_fab2_lib.baseboard_fab2(sch_1):page38_i33@chpset_lib.skx_ext_b(chips)!SKX_EXT_B_BGA1-IC,TBD!!!F82!VCCD012(24)!!!!
S!PVDDQ_ABC!U5D1!U50!@baseboard_fab2_lib.baseboard_fab2(sch_1):page38_i33@chpset_lib.skx_ext_b(chips)!SKX_EXT_B_BGA1-IC,TBD!!!F82!VCCD012(25)!!!!
S!PVDDQ_ABC!U5D1!U52!@baseboard_fab2_lib.baseboard_fab2(sch_1):page38_i33@chpset_lib.skx_ext_b(chips)!SKX_EXT_B_BGA1-IC,TBD!!!F82!VCCD012(26)!!!!
S!PVDDQ_ABC!U5D1!U54!@baseboard_fab2_lib.baseboard_fab2(sch_1):page38_i33@chpset_lib.skx_ext_b(chips)!SKX_EXT_B_BGA1-IC,TBD!!!F82!VCCD012(27)!!!!
S!PVDDQ_ABC!U5D1!U56!@baseboard_fab2_lib.baseboard_fab2(sch_1):page38_i33@chpset_lib.skx_ext_b(chips)!SKX_EXT_B_BGA1-IC,TBD!!!F82!VCCD012(28)!!!!
S!PVDDQ_ABC!U5D1!U58!@baseboard_fab2_lib.baseboard_fab2(sch_1):page38_i33@chpset_lib.skx_ext_b(chips)!SKX_EXT_B_BGA1-IC,TBD!!!F82!VCCD012(29)!!!!
S!PVDDQ_ABC!U5D1!B59!@baseboard_fab2_lib.baseboard_fab2(sch_1):page38_i33@chpset_lib.skx_ext_b(chips)!SKX_EXT_B_BGA1-IC,TBD!!!F82!VCCD012(2)!!!!
S!PVDDQ_ABC!U5D1!U60!@baseboard_fab2_lib.baseboard_fab2(sch_1):page38_i33@chpset_lib.skx_ext_b(chips)!SKX_EXT_B_BGA1-IC,TBD!!!F82!VCCD012(30)!!!!
S!PVDDQ_ABC!U5D1!U62!@baseboard_fab2_lib.baseboard_fab2(sch_1):page38_i33@chpset_lib.skx_ext_b(chips)!SKX_EXT_B_BGA1-IC,TBD!!!F82!VCCD012(31)!!!!
S!PVDDQ_ABC!U5D1!W64!@baseboard_fab2_lib.baseboard_fab2(sch_1):page38_i33@chpset_lib.skx_ext_b(chips)!SKX_EXT_B_BGA1-IC,TBD!!!F82!VCCD012(32)!!!!
S!PVDDQ_ABC!U5D1!Y45!@baseboard_fab2_lib.baseboard_fab2(sch_1):page38_i33@chpset_lib.skx_ext_b(chips)!SKX_EXT_B_BGA1-IC,TBD!!!F82!VCCD012(33)!!!!
S!PVDDQ_ABC!U5D1!Y47!@baseboard_fab2_lib.baseboard_fab2(sch_1):page38_i33@chpset_lib.skx_ext_b(chips)!SKX_EXT_B_BGA1-IC,TBD!!!F82!VCCD012(34)!!!!
S!PVDDQ_ABC!U5D1!Y49!@baseboard_fab2_lib.baseboard_fab2(sch_1):page38_i33@chpset_lib.skx_ext_b(chips)!SKX_EXT_B_BGA1-IC,TBD!!!F82!VCCD012(35)!!!!
S!PVDDQ_ABC!U5D1!Y51!@baseboard_fab2_lib.baseboard_fab2(sch_1):page38_i33@chpset_lib.skx_ext_b(chips)!SKX_EXT_B_BGA1-IC,TBD!!!F82!VCCD012(36)!!!!
S!PVDDQ_ABC!U5D1!Y53!@baseboard_fab2_lib.baseboard_fab2(sch_1):page38_i33@chpset_lib.skx_ext_b(chips)!SKX_EXT_B_BGA1-IC,TBD!!!F82!VCCD012(37)!!!!
S!PVDDQ_ABC!U5D1!Y55!@baseboard_fab2_lib.baseboard_fab2(sch_1):page38_i33@chpset_lib.skx_ext_b(chips)!SKX_EXT_B_BGA1-IC,TBD!!!F82!VCCD012(38)!!!!
S!PVDDQ_ABC!U5D1!Y57!@baseboard_fab2_lib.baseboard_fab2(sch_1):page38_i33@chpset_lib.skx_ext_b(chips)!SKX_EXT_B_BGA1-IC,TBD!!!F82!VCCD012(39)!!!!
S!PVDDQ_ABC!U5D1!E46!@baseboard_fab2_lib.baseboard_fab2(sch_1):page38_i33@chpset_lib.skx_ext_b(chips)!SKX_EXT_B_BGA1-IC,TBD!!!F82!VCCD012(3)!!!!
S!PVDDQ_ABC!U5D1!Y59!@baseboard_fab2_lib.baseboard_fab2(sch_1):page38_i33@chpset_lib.skx_ext_b(chips)!SKX_EXT_B_BGA1-IC,TBD!!!F82!VCCD012(40)!!!!
S!PVDDQ_ABC!U5D1!Y61!@baseboard_fab2_lib.baseboard_fab2(sch_1):page38_i33@chpset_lib.skx_ext_b(chips)!SKX_EXT_B_BGA1-IC,TBD!!!F82!VCCD012(41)!!!!
S!PVDDQ_ABC!U5D1!Y63!@baseboard_fab2_lib.baseboard_fab2(sch_1):page38_i33@chpset_lib.skx_ext_b(chips)!SKX_EXT_B_BGA1-IC,TBD!!!F82!VCCD012(42)!!!!
S!PVDDQ_ABC!U5D1!AD45!@baseboard_fab2_lib.baseboard_fab2(sch_1):page38_i33@chpset_lib.skx_ext_b(chips)!SKX_EXT_B_BGA1-IC,TBD!!!F82!VCCD012(43)!!!!
S!PVDDQ_ABC!U5D1!AF55!@baseboard_fab2_lib.baseboard_fab2(sch_1):page38_i33@chpset_lib.skx_ext_b(chips)!SKX_EXT_B_BGA1-IC,TBD!!!F82!VCCD012(44)!!!!
S!PVDDQ_ABC!U5D1!AF57!@baseboard_fab2_lib.baseboard_fab2(sch_1):page38_i33@chpset_lib.skx_ext_b(chips)!SKX_EXT_B_BGA1-IC,TBD!!!F82!VCCD012(45)!!!!
S!PVDDQ_ABC!U5D1!AF59!@baseboard_fab2_lib.baseboard_fab2(sch_1):page38_i33@chpset_lib.skx_ext_b(chips)!SKX_EXT_B_BGA1-IC,TBD!!!F82!VCCD012(46)!!!!
S!PVDDQ_ABC!U5D1!AF61!@baseboard_fab2_lib.baseboard_fab2(sch_1):page38_i33@chpset_lib.skx_ext_b(chips)!SKX_EXT_B_BGA1-IC,TBD!!!F82!VCCD012(47)!!!!
S!PVDDQ_ABC!U5D1!AF63!@baseboard_fab2_lib.baseboard_fab2(sch_1):page38_i33@chpset_lib.skx_ext_b(chips)!SKX_EXT_B_BGA1-IC,TBD!!!F82!VCCD012(48)!!!!
S!PVDDQ_ABC!U5D1!E48!@baseboard_fab2_lib.baseboard_fab2(sch_1):page38_i33@chpset_lib.skx_ext_b(chips)!SKX_EXT_B_BGA1-IC,TBD!!!F82!VCCD012(4)!!!!
S!PVDDQ_ABC!U5D1!E50!@baseboard_fab2_lib.baseboard_fab2(sch_1):page38_i33@chpset_lib.skx_ext_b(chips)!SKX_EXT_B_BGA1-IC,TBD!!!F82!VCCD012(5)!!!!
S!PVDDQ_ABC!U5D1!E52!@baseboard_fab2_lib.baseboard_fab2(sch_1):page38_i33@chpset_lib.skx_ext_b(chips)!SKX_EXT_B_BGA1-IC,TBD!!!F82!VCCD012(6)!!!!
S!PVDDQ_ABC!U5D1!E54!@baseboard_fab2_lib.baseboard_fab2(sch_1):page38_i33@chpset_lib.skx_ext_b(chips)!SKX_EXT_B_BGA1-IC,TBD!!!F82!VCCD012(7)!!!!
S!PVDDQ_ABC!U5D1!E56!@baseboard_fab2_lib.baseboard_fab2(sch_1):page38_i33@chpset_lib.skx_ext_b(chips)!SKX_EXT_B_BGA1-IC,TBD!!!F82!VCCD012(8)!!!!
S!PVDDQ_ABC!U5D1!E58!@baseboard_fab2_lib.baseboard_fab2(sch_1):page38_i33@chpset_lib.skx_ext_b(chips)!SKX_EXT_B_BGA1-IC,TBD!!!F82!VCCD012(9)!!!!
S!PVDDQ_ABC!U5D1!D45!@baseboard_fab2_lib.baseboard_fab2(sch_1):page38_i33@chpset_lib.skx_ext_b(chips)!SKX_EXT_B_BGA1-IC,TBD!!!F82!VCCD012(49)!!!!
S!PVDDQ_ABC!U5D1!C46!@baseboard_fab2_lib.baseboard_fab2(sch_1):page38_i33@chpset_lib.skx_ext_b(chips)!SKX_EXT_B_BGA1-IC,TBD!!!F82!VCCD012(50)!!!!
S!PVDDQ_ABC!U5D1!B47!@baseboard_fab2_lib.baseboard_fab2(sch_1):page38_i33@chpset_lib.skx_ext_b(chips)!SKX_EXT_B_BGA1-IC,TBD!!!F82!VCCD012(51)!!!!
S!PVDDQ_DEF!U5D1!EF59!@baseboard_fab2_lib.baseboard_fab2(sch_1):page38_i33@chpset_lib.skx_ext_b(chips)!SKX_EXT_B_BGA1-IC,TBD!!!F82!VCCD345(0)!!!!
S!PVDDQ_DEF!U5D1!EC48!@baseboard_fab2_lib.baseboard_fab2(sch_1):page38_i33@chpset_lib.skx_ext_b(chips)!SKX_EXT_B_BGA1-IC,TBD!!!F82!VCCD345(10)!!!!
S!PVDDQ_DEF!U5D1!EC46!@baseboard_fab2_lib.baseboard_fab2(sch_1):page38_i33@chpset_lib.skx_ext_b(chips)!SKX_EXT_B_BGA1-IC,TBD!!!F82!VCCD345(11)!!!!
S!PVDDQ_DEF!U5D1!DU64!@baseboard_fab2_lib.baseboard_fab2(sch_1):page38_i33@chpset_lib.skx_ext_b(chips)!SKX_EXT_B_BGA1-IC,TBD!!!F82!VCCD345(12)!!!!
S!PVDDQ_DEF!U5D1!DU62!@baseboard_fab2_lib.baseboard_fab2(sch_1):page38_i33@chpset_lib.skx_ext_b(chips)!SKX_EXT_B_BGA1-IC,TBD!!!F82!VCCD345(13)!!!!
S!PVDDQ_DEF!U5D1!DU60!@baseboard_fab2_lib.baseboard_fab2(sch_1):page38_i33@chpset_lib.skx_ext_b(chips)!SKX_EXT_B_BGA1-IC,TBD!!!F82!VCCD345(14)!!!!
S!PVDDQ_DEF!U5D1!DU58!@baseboard_fab2_lib.baseboard_fab2(sch_1):page38_i33@chpset_lib.skx_ext_b(chips)!SKX_EXT_B_BGA1-IC,TBD!!!F82!VCCD345(15)!!!!
S!PVDDQ_DEF!U5D1!DU56!@baseboard_fab2_lib.baseboard_fab2(sch_1):page38_i33@chpset_lib.skx_ext_b(chips)!SKX_EXT_B_BGA1-IC,TBD!!!F82!VCCD345(16)!!!!
S!PVDDQ_DEF!U5D1!DU54!@baseboard_fab2_lib.baseboard_fab2(sch_1):page38_i33@chpset_lib.skx_ext_b(chips)!SKX_EXT_B_BGA1-IC,TBD!!!F82!VCCD345(17)!!!!
S!PVDDQ_DEF!U5D1!DU52!@baseboard_fab2_lib.baseboard_fab2(sch_1):page38_i33@chpset_lib.skx_ext_b(chips)!SKX_EXT_B_BGA1-IC,TBD!!!F82!VCCD345(18)!!!!
S!PVDDQ_DEF!U5D1!DU50!@baseboard_fab2_lib.baseboard_fab2(sch_1):page38_i33@chpset_lib.skx_ext_b(chips)!SKX_EXT_B_BGA1-IC,TBD!!!F82!VCCD345(19)!!!!
S!PVDDQ_DEF!U5D1!EF53!@baseboard_fab2_lib.baseboard_fab2(sch_1):page38_i33@chpset_lib.skx_ext_b(chips)!SKX_EXT_B_BGA1-IC,TBD!!!F82!VCCD345(1)!!!!
S!PVDDQ_DEF!U5D1!DU48!@baseboard_fab2_lib.baseboard_fab2(sch_1):page38_i33@chpset_lib.skx_ext_b(chips)!SKX_EXT_B_BGA1-IC,TBD!!!F82!VCCD345(20)!!!!
S!PVDDQ_DEF!U5D1!DU46!@baseboard_fab2_lib.baseboard_fab2(sch_1):page38_i33@chpset_lib.skx_ext_b(chips)!SKX_EXT_B_BGA1-IC,TBD!!!F82!VCCD345(21)!!!!
S!PVDDQ_DEF!U5D1!DL62!@baseboard_fab2_lib.baseboard_fab2(sch_1):page38_i33@chpset_lib.skx_ext_b(chips)!SKX_EXT_B_BGA1-IC,TBD!!!F82!VCCD345(22)!!!!
S!PVDDQ_DEF!U5D1!DL60!@baseboard_fab2_lib.baseboard_fab2(sch_1):page38_i33@chpset_lib.skx_ext_b(chips)!SKX_EXT_B_BGA1-IC,TBD!!!F82!VCCD345(23)!!!!
S!PVDDQ_DEF!U5D1!DL58!@baseboard_fab2_lib.baseboard_fab2(sch_1):page38_i33@chpset_lib.skx_ext_b(chips)!SKX_EXT_B_BGA1-IC,TBD!!!F82!VCCD345(24)!!!!
S!PVDDQ_DEF!U5D1!DL56!@baseboard_fab2_lib.baseboard_fab2(sch_1):page38_i33@chpset_lib.skx_ext_b(chips)!SKX_EXT_B_BGA1-IC,TBD!!!F82!VCCD345(25)!!!!
S!PVDDQ_DEF!U5D1!DL54!@baseboard_fab2_lib.baseboard_fab2(sch_1):page38_i33@chpset_lib.skx_ext_b(chips)!SKX_EXT_B_BGA1-IC,TBD!!!F82!VCCD345(26)!!!!
S!PVDDQ_DEF!U5D1!DL52!@baseboard_fab2_lib.baseboard_fab2(sch_1):page38_i33@chpset_lib.skx_ext_b(chips)!SKX_EXT_B_BGA1-IC,TBD!!!F82!VCCD345(27)!!!!
S!PVDDQ_DEF!U5D1!DL50!@baseboard_fab2_lib.baseboard_fab2(sch_1):page38_i33@chpset_lib.skx_ext_b(chips)!SKX_EXT_B_BGA1-IC,TBD!!!F82!VCCD345(28)!!!!
S!PVDDQ_DEF!U5D1!DL48!@baseboard_fab2_lib.baseboard_fab2(sch_1):page38_i33@chpset_lib.skx_ext_b(chips)!SKX_EXT_B_BGA1-IC,TBD!!!F82!VCCD345(29)!!!!
S!PVDDQ_DEF!U5D1!EF49!@baseboard_fab2_lib.baseboard_fab2(sch_1):page38_i33@chpset_lib.skx_ext_b(chips)!SKX_EXT_B_BGA1-IC,TBD!!!F82!VCCD345(2)!!!!
S!PVDDQ_DEF!U5D1!DL46!@baseboard_fab2_lib.baseboard_fab2(sch_1):page38_i33@chpset_lib.skx_ext_b(chips)!SKX_EXT_B_BGA1-IC,TBD!!!F82!VCCD345(30)!!!!
S!PVDDQ_DEF!U5D1!DJ64!@baseboard_fab2_lib.baseboard_fab2(sch_1):page38_i33@chpset_lib.skx_ext_b(chips)!SKX_EXT_B_BGA1-IC,TBD!!!F82!VCCD345(31)!!!!
S!PVDDQ_DEF!U5D1!DH63!@baseboard_fab2_lib.baseboard_fab2(sch_1):page38_i33@chpset_lib.skx_ext_b(chips)!SKX_EXT_B_BGA1-IC,TBD!!!F82!VCCD345(32)!!!!
S!PVDDQ_DEF!U5D1!DH61!@baseboard_fab2_lib.baseboard_fab2(sch_1):page38_i33@chpset_lib.skx_ext_b(chips)!SKX_EXT_B_BGA1-IC,TBD!!!F82!VCCD345(33)!!!!
S!PVDDQ_DEF!U5D1!DH59!@baseboard_fab2_lib.baseboard_fab2(sch_1):page38_i33@chpset_lib.skx_ext_b(chips)!SKX_EXT_B_BGA1-IC,TBD!!!F82!VCCD345(34)!!!!
S!PVDDQ_DEF!U5D1!DH57!@baseboard_fab2_lib.baseboard_fab2(sch_1):page38_i33@chpset_lib.skx_ext_b(chips)!SKX_EXT_B_BGA1-IC,TBD!!!F82!VCCD345(35)!!!!
S!PVDDQ_DEF!U5D1!DH55!@baseboard_fab2_lib.baseboard_fab2(sch_1):page38_i33@chpset_lib.skx_ext_b(chips)!SKX_EXT_B_BGA1-IC,TBD!!!F82!VCCD345(36)!!!!
S!PVDDQ_DEF!U5D1!DH53!@baseboard_fab2_lib.baseboard_fab2(sch_1):page38_i33@chpset_lib.skx_ext_b(chips)!SKX_EXT_B_BGA1-IC,TBD!!!F82!VCCD345(37)!!!!
S!PVDDQ_DEF!U5D1!DH51!@baseboard_fab2_lib.baseboard_fab2(sch_1):page38_i33@chpset_lib.skx_ext_b(chips)!SKX_EXT_B_BGA1-IC,TBD!!!F82!VCCD345(38)!!!!
S!PVDDQ_DEF!U5D1!DH49!@baseboard_fab2_lib.baseboard_fab2(sch_1):page38_i33@chpset_lib.skx_ext_b(chips)!SKX_EXT_B_BGA1-IC,TBD!!!F82!VCCD345(39)!!!!
S!PVDDQ_DEF!U5D1!EC62!@baseboard_fab2_lib.baseboard_fab2(sch_1):page38_i33@chpset_lib.skx_ext_b(chips)!SKX_EXT_B_BGA1-IC,TBD!!!F82!VCCD345(3)!!!!
S!PVDDQ_DEF!U5D1!DH47!@baseboard_fab2_lib.baseboard_fab2(sch_1):page38_i33@chpset_lib.skx_ext_b(chips)!SKX_EXT_B_BGA1-IC,TBD!!!F82!VCCD345(40)!!!!
S!PVDDQ_DEF!U5D1!DH45!@baseboard_fab2_lib.baseboard_fab2(sch_1):page38_i33@chpset_lib.skx_ext_b(chips)!SKX_EXT_B_BGA1-IC,TBD!!!F82!VCCD345(41)!!!!
S!PVDDQ_DEF!U5D1!DD45!@baseboard_fab2_lib.baseboard_fab2(sch_1):page38_i33@chpset_lib.skx_ext_b(chips)!SKX_EXT_B_BGA1-IC,TBD!!!F82!VCCD345(42)!!!!
S!PVDDQ_DEF!U5D1!DB63!@baseboard_fab2_lib.baseboard_fab2(sch_1):page38_i33@chpset_lib.skx_ext_b(chips)!SKX_EXT_B_BGA1-IC,TBD!!!F82!VCCD345(43)!!!!
S!PVDDQ_DEF!U5D1!DB61!@baseboard_fab2_lib.baseboard_fab2(sch_1):page38_i33@chpset_lib.skx_ext_b(chips)!SKX_EXT_B_BGA1-IC,TBD!!!F82!VCCD345(44)!!!!
S!PVDDQ_DEF!U5D1!DB59!@baseboard_fab2_lib.baseboard_fab2(sch_1):page38_i33@chpset_lib.skx_ext_b(chips)!SKX_EXT_B_BGA1-IC,TBD!!!F82!VCCD345(45)!!!!
S!PVDDQ_DEF!U5D1!DB57!@baseboard_fab2_lib.baseboard_fab2(sch_1):page38_i33@chpset_lib.skx_ext_b(chips)!SKX_EXT_B_BGA1-IC,TBD!!!F82!VCCD345(46)!!!!
S!PVDDQ_DEF!U5D1!DB55!@baseboard_fab2_lib.baseboard_fab2(sch_1):page38_i33@chpset_lib.skx_ext_b(chips)!SKX_EXT_B_BGA1-IC,TBD!!!F82!VCCD345(47)!!!!
S!PVDDQ_DEF!U5D1!DB53!@baseboard_fab2_lib.baseboard_fab2(sch_1):page38_i33@chpset_lib.skx_ext_b(chips)!SKX_EXT_B_BGA1-IC,TBD!!!F82!VCCD345(48)!!!!
S!PVDDQ_DEF!U5D1!EC60!@baseboard_fab2_lib.baseboard_fab2(sch_1):page38_i33@chpset_lib.skx_ext_b(chips)!SKX_EXT_B_BGA1-IC,TBD!!!F82!VCCD345(4)!!!!
S!PVDDQ_DEF!U5D1!EC58!@baseboard_fab2_lib.baseboard_fab2(sch_1):page38_i33@chpset_lib.skx_ext_b(chips)!SKX_EXT_B_BGA1-IC,TBD!!!F82!VCCD345(5)!!!!
S!PVDDQ_DEF!U5D1!EC56!@baseboard_fab2_lib.baseboard_fab2(sch_1):page38_i33@chpset_lib.skx_ext_b(chips)!SKX_EXT_B_BGA1-IC,TBD!!!F82!VCCD345(6)!!!!
S!PVDDQ_DEF!U5D1!EC54!@baseboard_fab2_lib.baseboard_fab2(sch_1):page38_i33@chpset_lib.skx_ext_b(chips)!SKX_EXT_B_BGA1-IC,TBD!!!F82!VCCD345(7)!!!!
S!PVDDQ_DEF!U5D1!EC52!@baseboard_fab2_lib.baseboard_fab2(sch_1):page38_i33@chpset_lib.skx_ext_b(chips)!SKX_EXT_B_BGA1-IC,TBD!!!F82!VCCD345(8)!!!!
S!PVDDQ_DEF!U5D1!EC50!@baseboard_fab2_lib.baseboard_fab2(sch_1):page38_i33@chpset_lib.skx_ext_b(chips)!SKX_EXT_B_BGA1-IC,TBD!!!F82!VCCD345(9)!!!!
S!PVDDQ_DEF!U5D1!EF45!@baseboard_fab2_lib.baseboard_fab2(sch_1):page38_i33@chpset_lib.skx_ext_b(chips)!SKX_EXT_B_BGA1-IC,TBD!!!F82!VCCD345(49)!!!!
S!PVDDQ_DEF!U5D1!EE44!@baseboard_fab2_lib.baseboard_fab2(sch_1):page38_i33@chpset_lib.skx_ext_b(chips)!SKX_EXT_B_BGA1-IC,TBD!!!F82!VCCD345(50)!!!!
S!PVCCIOMCP_CPU0!U5D1!BT11!@baseboard_fab2_lib.baseboard_fab2(sch_1):page38_i34@chpset_lib.skx_ext_b(chips)!SKX_EXT_B_BGA1-IC,TBD!!!F81!CD_VCCP(7)!!!!
S!PVCCIOMCP_CPU0!U5D1!BR12!@baseboard_fab2_lib.baseboard_fab2(sch_1):page38_i34@chpset_lib.skx_ext_b(chips)!SKX_EXT_B_BGA1-IC,TBD!!!F81!CD_VCCP(9)!!!!
S!PVCCIOMCP_CPU0!U5D1!BP13!@baseboard_fab2_lib.baseboard_fab2(sch_1):page38_i34@chpset_lib.skx_ext_b(chips)!SKX_EXT_B_BGA1-IC,TBD!!!F81!CD_VCCP(11)!!!!
S!PVCCIOMCP_CPU0!U5D1!BP11!@baseboard_fab2_lib.baseboard_fab2(sch_1):page38_i34@chpset_lib.skx_ext_b(chips)!SKX_EXT_B_BGA1-IC,TBD!!!F81!CD_VCCP(12)!!!!
S!PVCCIOMCP_CPU0!U5D1!BN12!@baseboard_fab2_lib.baseboard_fab2(sch_1):page38_i34@chpset_lib.skx_ext_b(chips)!SKX_EXT_B_BGA1-IC,TBD!!!F81!CD_VCCP(14)!!!!
S!PVCCIOMCP_CPU0!U5D1!BM11!@baseboard_fab2_lib.baseboard_fab2(sch_1):page38_i34@chpset_lib.skx_ext_b(chips)!SKX_EXT_B_BGA1-IC,TBD!!!F81!CD_VCCP(15)!!!!
S!P1V8_MCP_CPU0!U5D1!BY27!@baseboard_fab2_lib.baseboard_fab2(sch_1):page38_i34@chpset_lib.skx_ext_b(chips)!SKX_EXT_B_BGA1-IC,TBD!!!F81!CD_VCCIN(3)!!!!
S!P1V8_MCP_CPU0!U5D1!BV27!@baseboard_fab2_lib.baseboard_fab2(sch_1):page38_i34@chpset_lib.skx_ext_b(chips)!SKX_EXT_B_BGA1-IC,TBD!!!F81!CD_VCCIN(2)!!!!
S!P1V8_MCP_CPU0!U5D1!BU26!@baseboard_fab2_lib.baseboard_fab2(sch_1):page38_i34@chpset_lib.skx_ext_b(chips)!SKX_EXT_B_BGA1-IC,TBD!!!F81!CD_VCCIN(1)!!!!
S!P1V8_MCP_CPU0!U5D1!BT27!@baseboard_fab2_lib.baseboard_fab2(sch_1):page38_i34@chpset_lib.skx_ext_b(chips)!SKX_EXT_B_BGA1-IC,TBD!!!F81!CD_VCCIN(0)!!!!
S!PVPP_ABC!U5D1!B11!@baseboard_fab2_lib.baseboard_fab2(sch_1):page38_i34@chpset_lib.skx_ext_b(chips)!SKX_EXT_B_BGA1-IC,TBD!!!F81!CD_VPP(0)!!!!
S!PVPP_ABC!U5D1!A8!@baseboard_fab2_lib.baseboard_fab2(sch_1):page38_i34@chpset_lib.skx_ext_b(chips)!SKX_EXT_B_BGA1-IC,TBD!!!F81!CD_VPP(3)!!!!
S!PVPP_ABC!U5D1!A12!@baseboard_fab2_lib.baseboard_fab2(sch_1):page38_i34@chpset_lib.skx_ext_b(chips)!SKX_EXT_B_BGA1-IC,TBD!!!F81!CD_VPP(1)!!!!
S!PVPP_ABC!U5D1!A10!@baseboard_fab2_lib.baseboard_fab2(sch_1):page38_i34@chpset_lib.skx_ext_b(chips)!SKX_EXT_B_BGA1-IC,TBD!!!F81!CD_VPP(2)!!!!
S!PVCCIOMCP_CPU0!U5D1!BV15!@baseboard_fab2_lib.baseboard_fab2(sch_1):page38_i34@chpset_lib.skx_ext_b(chips)!SKX_EXT_B_BGA1-IC,TBD!!!F81!CD_VCCP(0)!!!!
S!PVCCIOMCP_CPU0!U5D1!BV13!@baseboard_fab2_lib.baseboard_fab2(sch_1):page38_i34@chpset_lib.skx_ext_b(chips)!SKX_EXT_B_BGA1-IC,TBD!!!F81!CD_VCCP(1)!!!!
S!PVCCIOMCP_CPU0!U5D1!BV11!@baseboard_fab2_lib.baseboard_fab2(sch_1):page38_i34@chpset_lib.skx_ext_b(chips)!SKX_EXT_B_BGA1-IC,TBD!!!F81!CD_VCCP(2)!!!!
S!PVCCIOMCP_CPU0!U5D1!BU14!@baseboard_fab2_lib.baseboard_fab2(sch_1):page38_i34@chpset_lib.skx_ext_b(chips)!SKX_EXT_B_BGA1-IC,TBD!!!F81!CD_VCCP(3)!!!!
S!PVCCIOMCP_CPU0!U5D1!BU12!@baseboard_fab2_lib.baseboard_fab2(sch_1):page38_i34@chpset_lib.skx_ext_b(chips)!SKX_EXT_B_BGA1-IC,TBD!!!F81!CD_VCCP(4)!!!!
S!PVCCIOMCP_CPU0!U5D1!BT15!@baseboard_fab2_lib.baseboard_fab2(sch_1):page38_i34@chpset_lib.skx_ext_b(chips)!SKX_EXT_B_BGA1-IC,TBD!!!F81!CD_VCCP(5)!!!!
S!PVCCIOMCP_CPU0!U5D1!BT13!@baseboard_fab2_lib.baseboard_fab2(sch_1):page38_i34@chpset_lib.skx_ext_b(chips)!SKX_EXT_B_BGA1-IC,TBD!!!F81!CD_VCCP(6)!!!!
S!PVCCIOMCP_CPU0!U5D1!BR14!@baseboard_fab2_lib.baseboard_fab2(sch_1):page38_i34@chpset_lib.skx_ext_b(chips)!SKX_EXT_B_BGA1-IC,TBD!!!F81!CD_VCCP(8)!!!!
S!PVCCIOMCP_CPU0!U5D1!BP15!@baseboard_fab2_lib.baseboard_fab2(sch_1):page38_i34@chpset_lib.skx_ext_b(chips)!SKX_EXT_B_BGA1-IC,TBD!!!F81!CD_VCCP(10)!!!!
S!PVCCIOMCP_CPU0!U5D1!BN14!@baseboard_fab2_lib.baseboard_fab2(sch_1):page38_i34@chpset_lib.skx_ext_b(chips)!SKX_EXT_B_BGA1-IC,TBD!!!F81!CD_VCCP(13)!!!!
S!PVCCMCP_CPU0!U5D1!BL14!@baseboard_fab2_lib.baseboard_fab2(sch_1):page38_i34@chpset_lib.skx_ext_b(chips)!SKX_EXT_B_BGA1-IC,TBD!!!F81!CD_VCC_CORE(0)!!!!
S!PVCCMCP_CPU0!U5D1!BE14!@baseboard_fab2_lib.baseboard_fab2(sch_1):page38_i34@chpset_lib.skx_ext_b(chips)!SKX_EXT_B_BGA1-IC,TBD!!!F81!CD_VCC_CORE(10)!!!!
S!PVCCMCP_CPU0!U5D1!BE12!@baseboard_fab2_lib.baseboard_fab2(sch_1):page38_i34@chpset_lib.skx_ext_b(chips)!SKX_EXT_B_BGA1-IC,TBD!!!F81!CD_VCC_CORE(11)!!!!
S!PVCCMCP_CPU0!U5D1!BD13!@baseboard_fab2_lib.baseboard_fab2(sch_1):page38_i34@chpset_lib.skx_ext_b(chips)!SKX_EXT_B_BGA1-IC,TBD!!!F81!CD_VCC_CORE(12)!!!!
S!PVCCMCP_CPU0!U5D1!BK15!@baseboard_fab2_lib.baseboard_fab2(sch_1):page38_i34@chpset_lib.skx_ext_b(chips)!SKX_EXT_B_BGA1-IC,TBD!!!F81!CD_VCC_CORE(1)!!!!
S!PVCCMCP_CPU0!U5D1!BK13!@baseboard_fab2_lib.baseboard_fab2(sch_1):page38_i34@chpset_lib.skx_ext_b(chips)!SKX_EXT_B_BGA1-IC,TBD!!!F81!CD_VCC_CORE(2)!!!!
S!PVCCMCP_CPU0!U5D1!BJ14!@baseboard_fab2_lib.baseboard_fab2(sch_1):page38_i34@chpset_lib.skx_ext_b(chips)!SKX_EXT_B_BGA1-IC,TBD!!!F81!CD_VCC_CORE(3)!!!!
S!PVCCMCP_CPU0!U5D1!BJ12!@baseboard_fab2_lib.baseboard_fab2(sch_1):page38_i34@chpset_lib.skx_ext_b(chips)!SKX_EXT_B_BGA1-IC,TBD!!!F81!CD_VCC_CORE(4)!!!!
S!PVCCMCP_CPU0!U5D1!BH13!@baseboard_fab2_lib.baseboard_fab2(sch_1):page38_i34@chpset_lib.skx_ext_b(chips)!SKX_EXT_B_BGA1-IC,TBD!!!F81!CD_VCC_CORE(5)!!!!
S!PVCCMCP_CPU0!U5D1!BG14!@baseboard_fab2_lib.baseboard_fab2(sch_1):page38_i34@chpset_lib.skx_ext_b(chips)!SKX_EXT_B_BGA1-IC,TBD!!!F81!CD_VCC_CORE(6)!!!!
S!PVCCMCP_CPU0!U5D1!BG12!@baseboard_fab2_lib.baseboard_fab2(sch_1):page38_i34@chpset_lib.skx_ext_b(chips)!SKX_EXT_B_BGA1-IC,TBD!!!F81!CD_VCC_CORE(7)!!!!
S!PVCCMCP_CPU0!U5D1!BF13!@baseboard_fab2_lib.baseboard_fab2(sch_1):page38_i34@chpset_lib.skx_ext_b(chips)!SKX_EXT_B_BGA1-IC,TBD!!!F81!CD_VCC_CORE(8)!!!!
S!PVCCMCP_CPU0!U5D1!BF11!@baseboard_fab2_lib.baseboard_fab2(sch_1):page38_i34@chpset_lib.skx_ext_b(chips)!SKX_EXT_B_BGA1-IC,TBD!!!F81!CD_VCC_CORE(9)!!!!
S!PVCCIO_CPU0!U5D1!BC26!@baseboard_fab2_lib.baseboard_fab2(sch_1):page38_i34@chpset_lib.skx_ext_b(chips)!SKX_EXT_B_BGA1-IC,TBD!!!F81!VCCIO(75)!!!!
S!PVCCIO_CPU0!U5D1!BB27!@baseboard_fab2_lib.baseboard_fab2(sch_1):page38_i34@chpset_lib.skx_ext_b(chips)!SKX_EXT_B_BGA1-IC,TBD!!!F81!VCCIO(76)!!!!
S!PVCCIO_CPU0!U5D1!BA26!@baseboard_fab2_lib.baseboard_fab2(sch_1):page38_i34@chpset_lib.skx_ext_b(chips)!SKX_EXT_B_BGA1-IC,TBD!!!F81!VCCIO(77)!!!!
S!PVCCIO_CPU0!U5D1!AY27!@baseboard_fab2_lib.baseboard_fab2(sch_1):page38_i34@chpset_lib.skx_ext_b(chips)!SKX_EXT_B_BGA1-IC,TBD!!!F81!VCCIO(78)!!!!
S!PVCCIO_CPU0!U5D1!AW26!@baseboard_fab2_lib.baseboard_fab2(sch_1):page38_i34@chpset_lib.skx_ext_b(chips)!SKX_EXT_B_BGA1-IC,TBD!!!F81!VCCIO(79)!!!!
S!PVCCIO_CPU0!U5D1!AV27!@baseboard_fab2_lib.baseboard_fab2(sch_1):page38_i34@chpset_lib.skx_ext_b(chips)!SKX_EXT_B_BGA1-IC,TBD!!!F81!VCCIO(80)!!!!
S!PVCCIO_CPU0!U5D1!CF27!@baseboard_fab2_lib.baseboard_fab2(sch_1):page38_i34@chpset_lib.skx_ext_b(chips)!SKX_EXT_B_BGA1-IC,TBD!!!F81!VCCIO(81)!!!!
S!PVCCIO_CPU0!U5D1!CD27!@baseboard_fab2_lib.baseboard_fab2(sch_1):page38_i34@chpset_lib.skx_ext_b(chips)!SKX_EXT_B_BGA1-IC,TBD!!!F81!VCCIO(82)!!!!
S!PVCCIO_CPU0!U5D1!CC26!@baseboard_fab2_lib.baseboard_fab2(sch_1):page38_i34@chpset_lib.skx_ext_b(chips)!SKX_EXT_B_BGA1-IC,TBD!!!F81!VCCIO(83)!!!!
S!P3V3_STBY!U5D1!CY55!@baseboard_fab2_lib.baseboard_fab2(sch_1):page38_i34@chpset_lib.skx_ext_b(chips)!SKX_EXT_B_BGA1-IC,TBD!!!F81!VCC33!!!!
S!PVCCIO_CPU0!U5D1!EE10!@baseboard_fab2_lib.baseboard_fab2(sch_1):page39_i127@chpset_lib.skx_ext_b(chips)!SKX_EXT_B_BGA1-IC,TBD!!!F80!VCCIO(0)!!!!
S!PVCCIO_CPU0!U5D1!CG14!@baseboard_fab2_lib.baseboard_fab2(sch_1):page39_i127@chpset_lib.skx_ext_b(chips)!SKX_EXT_B_BGA1-IC,TBD!!!F80!VCCIO(10)!!!!
S!PVCCIO_CPU0!U5D1!CL20!@baseboard_fab2_lib.baseboard_fab2(sch_1):page39_i127@chpset_lib.skx_ext_b(chips)!SKX_EXT_B_BGA1-IC,TBD!!!F80!VCCIO(11)!!!!
S!PVCCIO_CPU0!U5D1!CP13!@baseboard_fab2_lib.baseboard_fab2(sch_1):page39_i127@chpset_lib.skx_ext_b(chips)!SKX_EXT_B_BGA1-IC,TBD!!!F80!VCCIO(12)!!!!
S!PVCCIO_CPU0!U5D1!DE14!@baseboard_fab2_lib.baseboard_fab2(sch_1):page39_i127@chpset_lib.skx_ext_b(chips)!SKX_EXT_B_BGA1-IC,TBD!!!F80!VCCIO(13)!!!!
S!PVCCIO_CPU0!U5D1!DC18!@baseboard_fab2_lib.baseboard_fab2(sch_1):page39_i127@chpset_lib.skx_ext_b(chips)!SKX_EXT_B_BGA1-IC,TBD!!!F80!VCCIO(14)!!!!
S!PVCCIO_CPU0!U5D1!CY17!@baseboard_fab2_lib.baseboard_fab2(sch_1):page39_i127@chpset_lib.skx_ext_b(chips)!SKX_EXT_B_BGA1-IC,TBD!!!F80!VCCIO(15)!!!!
S!PVCCIO_CPU0!U5D1!CU18!@baseboard_fab2_lib.baseboard_fab2(sch_1):page39_i127@chpset_lib.skx_ext_b(chips)!SKX_EXT_B_BGA1-IC,TBD!!!F80!VCCIO(16)!!!!
S!PVCCIO_CPU0!U5D1!CV21!@baseboard_fab2_lib.baseboard_fab2(sch_1):page39_i127@chpset_lib.skx_ext_b(chips)!SKX_EXT_B_BGA1-IC,TBD!!!F80!VCCIO(17)!!!!
S!PVCCIO_CPU0!U5D1!CU12!@baseboard_fab2_lib.baseboard_fab2(sch_1):page39_i127@chpset_lib.skx_ext_b(chips)!SKX_EXT_B_BGA1-IC,TBD!!!F80!VCCIO(18)!!!!
S!PVCCIO_CPU0!U5D1!CN6!@baseboard_fab2_lib.baseboard_fab2(sch_1):page39_i127@chpset_lib.skx_ext_b(chips)!SKX_EXT_B_BGA1-IC,TBD!!!F80!VCCIO(19)!!!!
S!PVCCIO_CPU0!U5D1!AE10!@baseboard_fab2_lib.baseboard_fab2(sch_1):page39_i127@chpset_lib.skx_ext_b(chips)!SKX_EXT_B_BGA1-IC,TBD!!!F80!VCCIO(1)!!!!
S!PVCCIO_CPU0!U5D1!CM15!@baseboard_fab2_lib.baseboard_fab2(sch_1):page38_i34@chpset_lib.skx_ext_b(chips)!SKX_EXT_B_BGA1-IC,TBD!!!F81!VCCIO(20)!!!!
S!PVCCIO_CPU0!U5D1!CL12!@baseboard_fab2_lib.baseboard_fab2(sch_1):page38_i34@chpset_lib.skx_ext_b(chips)!SKX_EXT_B_BGA1-IC,TBD!!!F81!VCCIO(21)!!!!
S!PVCCIO_CPU0!U5D1!CK5!@baseboard_fab2_lib.baseboard_fab2(sch_1):page38_i34@chpset_lib.skx_ext_b(chips)!SKX_EXT_B_BGA1-IC,TBD!!!F81!VCCIO(22)!!!!
S!PVCCIO_CPU0!U5D1!CV7!@baseboard_fab2_lib.baseboard_fab2(sch_1):page38_i34@chpset_lib.skx_ext_b(chips)!SKX_EXT_B_BGA1-IC,TBD!!!F81!VCCIO(23)!!!!
S!PVCCIO_CPU0!U5D1!CH9!@baseboard_fab2_lib.baseboard_fab2(sch_1):page38_i34@chpset_lib.skx_ext_b(chips)!SKX_EXT_B_BGA1-IC,TBD!!!F81!VCCIO(24)!!!!
S!PVCCIO_CPU0!U5D1!D7!@baseboard_fab2_lib.baseboard_fab2(sch_1):page38_i34@chpset_lib.skx_ext_b(chips)!SKX_EXT_B_BGA1-IC,TBD!!!F81!VCCIO(25)!!!!
S!PVCCIO_CPU0!U5D1!CE18!@baseboard_fab2_lib.baseboard_fab2(sch_1):page38_i34@chpset_lib.skx_ext_b(chips)!SKX_EXT_B_BGA1-IC,TBD!!!F81!VCCIO(26)!!!!
S!PVCCIO_CPU0!U5D1!CD9!@baseboard_fab2_lib.baseboard_fab2(sch_1):page38_i34@chpset_lib.skx_ext_b(chips)!SKX_EXT_B_BGA1-IC,TBD!!!F81!VCCIO(27)!!!!
S!PVCCIO_CPU0!U5D1!CB17!@baseboard_fab2_lib.baseboard_fab2(sch_1):page38_i34@chpset_lib.skx_ext_b(chips)!SKX_EXT_B_BGA1-IC,TBD!!!F81!VCCIO(28)!!!!
S!PVCCIO_CPU0!U5D1!CB13!@baseboard_fab2_lib.baseboard_fab2(sch_1):page38_i34@chpset_lib.skx_ext_b(chips)!SKX_EXT_B_BGA1-IC,TBD!!!F81!VCCIO(29)!!!!
S!PVCCIO_CPU0!U5D1!AF5!@baseboard_fab2_lib.baseboard_fab2(sch_1):page39_i127@chpset_lib.skx_ext_b(chips)!SKX_EXT_B_BGA1-IC,TBD!!!F80!VCCIO(2)!!!!
S!PVCCIO_CPU0!U5D1!BP25!@baseboard_fab2_lib.baseboard_fab2(sch_1):page38_i34@chpset_lib.skx_ext_b(chips)!SKX_EXT_B_BGA1-IC,TBD!!!F81!VCCIO(30)!!!!
S!PVCCIO_CPU0!U5D1!BJ24!@baseboard_fab2_lib.baseboard_fab2(sch_1):page38_i34@chpset_lib.skx_ext_b(chips)!SKX_EXT_B_BGA1-IC,TBD!!!F81!VCCIO(31)!!!!
S!PVCCIO_CPU0!U5D1!BF23!@baseboard_fab2_lib.baseboard_fab2(sch_1):page38_i34@chpset_lib.skx_ext_b(chips)!SKX_EXT_B_BGA1-IC,TBD!!!F81!VCCIO(32)!!!!
S!PVCCIO_CPU0!U5D1!DA14!@baseboard_fab2_lib.baseboard_fab2(sch_1):page38_i34@chpset_lib.skx_ext_b(chips)!SKX_EXT_B_BGA1-IC,TBD!!!F81!VCCIO(33)!!!!
S!PVCCIO_CPU0!U5D1!BB5!@baseboard_fab2_lib.baseboard_fab2(sch_1):page38_i34@chpset_lib.skx_ext_b(chips)!SKX_EXT_B_BGA1-IC,TBD!!!F81!VCCIO(34)!!!!
S!PVCCIO_CPU0!U5D1!BA24!@baseboard_fab2_lib.baseboard_fab2(sch_1):page38_i34@chpset_lib.skx_ext_b(chips)!SKX_EXT_B_BGA1-IC,TBD!!!F81!VCCIO(35)!!!!
S!PVCCIO_CPU0!U5D1!AY11!@baseboard_fab2_lib.baseboard_fab2(sch_1):page38_i34@chpset_lib.skx_ext_b(chips)!SKX_EXT_B_BGA1-IC,TBD!!!F81!VCCIO(36)!!!!
S!PVCCIO_CPU0!U5D1!AW6!@baseboard_fab2_lib.baseboard_fab2(sch_1):page38_i34@chpset_lib.skx_ext_b(chips)!SKX_EXT_B_BGA1-IC,TBD!!!F81!VCCIO(37)!!!!
S!PVCCIO_CPU0!U5D1!AT11!@baseboard_fab2_lib.baseboard_fab2(sch_1):page38_i34@chpset_lib.skx_ext_b(chips)!SKX_EXT_B_BGA1-IC,TBD!!!F81!VCCIO(38)!!!!
S!PVCCIO_CPU0!U5D1!DD7!@baseboard_fab2_lib.baseboard_fab2(sch_1):page38_i34@chpset_lib.skx_ext_b(chips)!SKX_EXT_B_BGA1-IC,TBD!!!F81!VCCIO(39)!!!!
S!PVCCIO_CPU0!U5D1!DV11!@baseboard_fab2_lib.baseboard_fab2(sch_1):page39_i127@chpset_lib.skx_ext_b(chips)!SKX_EXT_B_BGA1-IC,TBD!!!F80!VCCIO(3)!!!!
S!PVCCIO_CPU0!U5D1!AN10!@baseboard_fab2_lib.baseboard_fab2(sch_1):page38_i34@chpset_lib.skx_ext_b(chips)!SKX_EXT_B_BGA1-IC,TBD!!!F81!VCCIO(40)!!!!
S!PVCCIO_CPU0!U5D1!DF13!@baseboard_fab2_lib.baseboard_fab2(sch_1):page38_i34@chpset_lib.skx_ext_b(chips)!SKX_EXT_B_BGA1-IC,TBD!!!F81!VCCIO(41)!!!!
S!PVCCIO_CPU0!U5D1!AH9!@baseboard_fab2_lib.baseboard_fab2(sch_1):page38_i34@chpset_lib.skx_ext_b(chips)!SKX_EXT_B_BGA1-IC,TBD!!!F81!VCCIO(42)!!!!
S!PVCCIO_CPU0!U5D1!AC4!@baseboard_fab2_lib.baseboard_fab2(sch_1):page38_i34@chpset_lib.skx_ext_b(chips)!SKX_EXT_B_BGA1-IC,TBD!!!F81!VCCIO(43)!!!!
S!PVCCIO_CPU0!U5D1!AC20!@baseboard_fab2_lib.baseboard_fab2(sch_1):page38_i34@chpset_lib.skx_ext_b(chips)!SKX_EXT_B_BGA1-IC,TBD!!!F81!VCCIO(44)!!!!
S!PVCCIO_CPU0!U5D1!AA10!@baseboard_fab2_lib.baseboard_fab2(sch_1):page38_i34@chpset_lib.skx_ext_b(chips)!SKX_EXT_B_BGA1-IC,TBD!!!F81!VCCIO(45)!!!!
S!PVCCIO_CPU0!U5D1!W6!@baseboard_fab2_lib.baseboard_fab2(sch_1):page38_i34@chpset_lib.skx_ext_b(chips)!SKX_EXT_B_BGA1-IC,TBD!!!F81!VCCIO(46)!!!!
S!PVCCIO_CPU0!U5D1!W4!@baseboard_fab2_lib.baseboard_fab2(sch_1):page38_i34@chpset_lib.skx_ext_b(chips)!SKX_EXT_B_BGA1-IC,TBD!!!F81!VCCIO(47)!!!!
S!PVCCIO_CPU0!U5D1!DF21!@baseboard_fab2_lib.baseboard_fab2(sch_1):page38_i34@chpset_lib.skx_ext_b(chips)!SKX_EXT_B_BGA1-IC,TBD!!!F81!VCCIO(48)!!!!
S!PVCCIO_CPU0!U5D1!U14!@baseboard_fab2_lib.baseboard_fab2(sch_1):page38_i34@chpset_lib.skx_ext_b(chips)!SKX_EXT_B_BGA1-IC,TBD!!!F81!VCCIO(49)!!!!
S!PVCCIO_CPU0!U5D1!AM5!@baseboard_fab2_lib.baseboard_fab2(sch_1):page39_i127@chpset_lib.skx_ext_b(chips)!SKX_EXT_B_BGA1-IC,TBD!!!F80!VCCIO(4)!!!!
S!PVCCIO_CPU0!U5D1!T3!@baseboard_fab2_lib.baseboard_fab2(sch_1):page38_i34@chpset_lib.skx_ext_b(chips)!SKX_EXT_B_BGA1-IC,TBD!!!F81!VCCIO(50)!!!!
S!PVCCIO_CPU0!U5D1!P5!@baseboard_fab2_lib.baseboard_fab2(sch_1):page38_i34@chpset_lib.skx_ext_b(chips)!SKX_EXT_B_BGA1-IC,TBD!!!F81!VCCIO(51)!!!!
S!PVCCIO_CPU0!U5D1!M21!@baseboard_fab2_lib.baseboard_fab2(sch_1):page38_i34@chpset_lib.skx_ext_b(chips)!SKX_EXT_B_BGA1-IC,TBD!!!F81!VCCIO(52)!!!!
S!PVCCIO_CPU0!U5D1!M11!@baseboard_fab2_lib.baseboard_fab2(sch_1):page38_i34@chpset_lib.skx_ext_b(chips)!SKX_EXT_B_BGA1-IC,TBD!!!F81!VCCIO(53)!!!!
S!PVCCIO_CPU0!U5D1!DG8!@baseboard_fab2_lib.baseboard_fab2(sch_1):page38_i34@chpset_lib.skx_ext_b(chips)!SKX_EXT_B_BGA1-IC,TBD!!!F81!VCCIO(54)!!!!
S!PVCCIO_CPU0!U5D1!DH7!@baseboard_fab2_lib.baseboard_fab2(sch_1):page38_i34@chpset_lib.skx_ext_b(chips)!SKX_EXT_B_BGA1-IC,TBD!!!F81!VCCIO(55)!!!!
S!PVCCIO_CPU0!U5D1!L16!@baseboard_fab2_lib.baseboard_fab2(sch_1):page38_i34@chpset_lib.skx_ext_b(chips)!SKX_EXT_B_BGA1-IC,TBD!!!F81!VCCIO(56)!!!!
S!PVCCIO_CPU0!U5D1!L14!@baseboard_fab2_lib.baseboard_fab2(sch_1):page38_i34@chpset_lib.skx_ext_b(chips)!SKX_EXT_B_BGA1-IC,TBD!!!F81!VCCIO(57)!!!!
S!PVCCIO_CPU0!U5D1!J10!@baseboard_fab2_lib.baseboard_fab2(sch_1):page38_i34@chpset_lib.skx_ext_b(chips)!SKX_EXT_B_BGA1-IC,TBD!!!F81!VCCIO(58)!!!!
S!PVCCIO_CPU0!U5D1!H13!@baseboard_fab2_lib.baseboard_fab2(sch_1):page38_i34@chpset_lib.skx_ext_b(chips)!SKX_EXT_B_BGA1-IC,TBD!!!F81!VCCIO(59)!!!!
S!PVCCIO_CPU0!U5D1!AT5!@baseboard_fab2_lib.baseboard_fab2(sch_1):page39_i127@chpset_lib.skx_ext_b(chips)!SKX_EXT_B_BGA1-IC,TBD!!!F80!VCCIO(5)!!!!
S!PVCCIO_CPU0!U5D1!DJ16!@baseboard_fab2_lib.baseboard_fab2(sch_1):page38_i34@chpset_lib.skx_ext_b(chips)!SKX_EXT_B_BGA1-IC,TBD!!!F81!VCCIO(60)!!!!
S!PVCCIO_CPU0!U5D1!DM17!@baseboard_fab2_lib.baseboard_fab2(sch_1):page38_i34@chpset_lib.skx_ext_b(chips)!SKX_EXT_B_BGA1-IC,TBD!!!F81!VCCIO(61)!!!!
S!PVCCIO_CPU0!U5D1!DN8!@baseboard_fab2_lib.baseboard_fab2(sch_1):page38_i34@chpset_lib.skx_ext_b(chips)!SKX_EXT_B_BGA1-IC,TBD!!!F81!VCCIO(62)!!!!
S!PVCCIO_CPU0!U5D1!DP19!@baseboard_fab2_lib.baseboard_fab2(sch_1):page38_i34@chpset_lib.skx_ext_b(chips)!SKX_EXT_B_BGA1-IC,TBD!!!F81!VCCIO(63)!!!!
S!PVCCIO_CPU0!U5D1!DR10!@baseboard_fab2_lib.baseboard_fab2(sch_1):page38_i34@chpset_lib.skx_ext_b(chips)!SKX_EXT_B_BGA1-IC,TBD!!!F81!VCCIO(64)!!!!
S!PVCCIO_CPU0!U5D1!DR2!@baseboard_fab2_lib.baseboard_fab2(sch_1):page38_i34@chpset_lib.skx_ext_b(chips)!SKX_EXT_B_BGA1-IC,TBD!!!F81!VCCIO(65)!!!!
S!PVCCIO_CPU0!U5D1!DU20!@baseboard_fab2_lib.baseboard_fab2(sch_1):page38_i34@chpset_lib.skx_ext_b(chips)!SKX_EXT_B_BGA1-IC,TBD!!!F81!VCCIO(66)!!!!
S!PVCCIO_CPU0!U5D1!EA12!@baseboard_fab2_lib.baseboard_fab2(sch_1):page38_i34@chpset_lib.skx_ext_b(chips)!SKX_EXT_B_BGA1-IC,TBD!!!F81!VCCIO(67)!!!!
S!PVCCIO_CPU0!U5D1!EB15!@baseboard_fab2_lib.baseboard_fab2(sch_1):page38_i34@chpset_lib.skx_ext_b(chips)!SKX_EXT_B_BGA1-IC,TBD!!!F81!VCCIO(68)!!!!
S!PVCCIO_CPU0!U5D1!J2!@baseboard_fab2_lib.baseboard_fab2(sch_1):page38_i34@chpset_lib.skx_ext_b(chips)!SKX_EXT_B_BGA1-IC,TBD!!!F81!VCCIO(69)!!!!
S!PVCCIO_CPU0!U5D1!AT7!@baseboard_fab2_lib.baseboard_fab2(sch_1):page39_i127@chpset_lib.skx_ext_b(chips)!SKX_EXT_B_BGA1-IC,TBD!!!F80!VCCIO(6)!!!!
S!PVCCIO_CPU0!U5D1!K15!@baseboard_fab2_lib.baseboard_fab2(sch_1):page38_i34@chpset_lib.skx_ext_b(chips)!SKX_EXT_B_BGA1-IC,TBD!!!F81!VCCIO(70)!!!!
S!PVCCIO_CPU0!U5D1!M7!@baseboard_fab2_lib.baseboard_fab2(sch_1):page38_i34@chpset_lib.skx_ext_b(chips)!SKX_EXT_B_BGA1-IC,TBD!!!F81!VCCIO(71)!!!!
S!PVCCIO_CPU0!U5D1!M9!@baseboard_fab2_lib.baseboard_fab2(sch_1):page38_i34@chpset_lib.skx_ext_b(chips)!SKX_EXT_B_BGA1-IC,TBD!!!F81!VCCIO(72)!!!!
S!PVCCIO_CPU0!U5D1!N18!@baseboard_fab2_lib.baseboard_fab2(sch_1):page38_i34@chpset_lib.skx_ext_b(chips)!SKX_EXT_B_BGA1-IC,TBD!!!F81!VCCIO(73)!!!!
S!PVCCIO_CPU0!U5D1!W10!@baseboard_fab2_lib.baseboard_fab2(sch_1):page38_i34@chpset_lib.skx_ext_b(chips)!SKX_EXT_B_BGA1-IC,TBD!!!F81!VCCIO(74)!!!!
S!PVCCIO_CPU0!U5D1!BE24!@baseboard_fab2_lib.baseboard_fab2(sch_1):page39_i127@chpset_lib.skx_ext_b(chips)!SKX_EXT_B_BGA1-IC,TBD!!!F80!VCCIO(7)!!!!
S!PVCCIO_CPU0!U5D1!DK21!@baseboard_fab2_lib.baseboard_fab2(sch_1):page39_i127@chpset_lib.skx_ext_b(chips)!SKX_EXT_B_BGA1-IC,TBD!!!F80!VCCIO(8)!!!!
S!PVCCIO_CPU0!U5D1!CF5!@baseboard_fab2_lib.baseboard_fab2(sch_1):page39_i127@chpset_lib.skx_ext_b(chips)!SKX_EXT_B_BGA1-IC,TBD!!!F80!VCCIO(9)!!!!
S!PVSA_CPU0!U5D1!CJ66!@baseboard_fab2_lib.baseboard_fab2(sch_1):page38_i34@chpset_lib.skx_ext_b(chips)!SKX_EXT_B_BGA1-IC,TBD!!!F81!VCCSA(0)!!!!
S!PVSA_CPU0!U5D1!CF65!@baseboard_fab2_lib.baseboard_fab2(sch_1):page38_i34@chpset_lib.skx_ext_b(chips)!SKX_EXT_B_BGA1-IC,TBD!!!F81!VCCSA(10)!!!!
S!PVSA_CPU0!U5D1!CE74!@baseboard_fab2_lib.baseboard_fab2(sch_1):page38_i34@chpset_lib.skx_ext_b(chips)!SKX_EXT_B_BGA1-IC,TBD!!!F81!VCCSA(11)!!!!
S!PVSA_CPU0!U5D1!CE72!@baseboard_fab2_lib.baseboard_fab2(sch_1):page38_i34@chpset_lib.skx_ext_b(chips)!SKX_EXT_B_BGA1-IC,TBD!!!F81!VCCSA(12)!!!!
S!PVSA_CPU0!U5D1!CE68!@baseboard_fab2_lib.baseboard_fab2(sch_1):page38_i34@chpset_lib.skx_ext_b(chips)!SKX_EXT_B_BGA1-IC,TBD!!!F81!VCCSA(13)!!!!
S!PVSA_CPU0!U5D1!CE66!@baseboard_fab2_lib.baseboard_fab2(sch_1):page38_i34@chpset_lib.skx_ext_b(chips)!SKX_EXT_B_BGA1-IC,TBD!!!F81!VCCSA(14)!!!!
S!PVSA_CPU0!U5D1!CE64!@baseboard_fab2_lib.baseboard_fab2(sch_1):page38_i34@chpset_lib.skx_ext_b(chips)!SKX_EXT_B_BGA1-IC,TBD!!!F81!VCCSA(15)!!!!
S!PVSA_CPU0!U5D1!CD71!@baseboard_fab2_lib.baseboard_fab2(sch_1):page38_i34@chpset_lib.skx_ext_b(chips)!SKX_EXT_B_BGA1-IC,TBD!!!F81!VCCSA(16)!!!!
S!PVSA_CPU0!U5D1!CD69!@baseboard_fab2_lib.baseboard_fab2(sch_1):page38_i34@chpset_lib.skx_ext_b(chips)!SKX_EXT_B_BGA1-IC,TBD!!!F81!VCCSA(17)!!!!
S!PVSA_CPU0!U5D1!CD67!@baseboard_fab2_lib.baseboard_fab2(sch_1):page38_i34@chpset_lib.skx_ext_b(chips)!SKX_EXT_B_BGA1-IC,TBD!!!F81!VCCSA(18)!!!!
S!PVSA_CPU0!U5D1!CD65!@baseboard_fab2_lib.baseboard_fab2(sch_1):page38_i34@chpset_lib.skx_ext_b(chips)!SKX_EXT_B_BGA1-IC,TBD!!!F81!VCCSA(19)!!!!
S!PVSA_CPU0!U5D1!CJ64!@baseboard_fab2_lib.baseboard_fab2(sch_1):page38_i34@chpset_lib.skx_ext_b(chips)!SKX_EXT_B_BGA1-IC,TBD!!!F81!VCCSA(1)!!!!
S!PVSA_CPU0!U5D1!CC70!@baseboard_fab2_lib.baseboard_fab2(sch_1):page38_i34@chpset_lib.skx_ext_b(chips)!SKX_EXT_B_BGA1-IC,TBD!!!F81!VCCSA(20)!!!!
S!PVSA_CPU0!U5D1!CC68!@baseboard_fab2_lib.baseboard_fab2(sch_1):page38_i34@chpset_lib.skx_ext_b(chips)!SKX_EXT_B_BGA1-IC,TBD!!!F81!VCCSA(21)!!!!
S!PVSA_CPU0!U5D1!CC66!@baseboard_fab2_lib.baseboard_fab2(sch_1):page38_i34@chpset_lib.skx_ext_b(chips)!SKX_EXT_B_BGA1-IC,TBD!!!F81!VCCSA(22)!!!!
S!PVSA_CPU0!U5D1!CB69!@baseboard_fab2_lib.baseboard_fab2(sch_1):page38_i34@chpset_lib.skx_ext_b(chips)!SKX_EXT_B_BGA1-IC,TBD!!!F81!VCCSA(23)!!!!
S!PVSA_CPU0!U5D1!CB67!@baseboard_fab2_lib.baseboard_fab2(sch_1):page38_i34@chpset_lib.skx_ext_b(chips)!SKX_EXT_B_BGA1-IC,TBD!!!F81!VCCSA(24)!!!!
S!PVSA_CPU0!U5D1!CB65!@baseboard_fab2_lib.baseboard_fab2(sch_1):page38_i34@chpset_lib.skx_ext_b(chips)!SKX_EXT_B_BGA1-IC,TBD!!!F81!VCCSA(25)!!!!
S!PVSA_CPU0!U5D1!CH75!@baseboard_fab2_lib.baseboard_fab2(sch_1):page38_i34@chpset_lib.skx_ext_b(chips)!SKX_EXT_B_BGA1-IC,TBD!!!F81!VCCSA(2)!!!!
S!PVSA_CPU0!U5D1!CH65!@baseboard_fab2_lib.baseboard_fab2(sch_1):page38_i34@chpset_lib.skx_ext_b(chips)!SKX_EXT_B_BGA1-IC,TBD!!!F81!VCCSA(3)!!!!
S!PVSA_CPU0!U5D1!CG74!@baseboard_fab2_lib.baseboard_fab2(sch_1):page38_i34@chpset_lib.skx_ext_b(chips)!SKX_EXT_B_BGA1-IC,TBD!!!F81!VCCSA(4)!!!!
S!PVSA_CPU0!U5D1!CG66!@baseboard_fab2_lib.baseboard_fab2(sch_1):page38_i34@chpset_lib.skx_ext_b(chips)!SKX_EXT_B_BGA1-IC,TBD!!!F81!VCCSA(5)!!!!
S!PVSA_CPU0!U5D1!CG64!@baseboard_fab2_lib.baseboard_fab2(sch_1):page38_i34@chpset_lib.skx_ext_b(chips)!SKX_EXT_B_BGA1-IC,TBD!!!F81!VCCSA(6)!!!!
S!PVSA_CPU0!U5D1!CF75!@baseboard_fab2_lib.baseboard_fab2(sch_1):page38_i34@chpset_lib.skx_ext_b(chips)!SKX_EXT_B_BGA1-IC,TBD!!!F81!VCCSA(7)!!!!
S!PVSA_CPU0!U5D1!CF73!@baseboard_fab2_lib.baseboard_fab2(sch_1):page38_i34@chpset_lib.skx_ext_b(chips)!SKX_EXT_B_BGA1-IC,TBD!!!F81!VCCSA(8)!!!!
S!PVSA_CPU0!U5D1!CF67!@baseboard_fab2_lib.baseboard_fab2(sch_1):page38_i34@chpset_lib.skx_ext_b(chips)!SKX_EXT_B_BGA1-IC,TBD!!!F81!VCCSA(9)!!!!
S!VSENSE_PVCCIOMCP_CPU0_SKT_VSEN!U5D1!BT17!@baseboard_fab2_lib.baseboard_fab2(sch_1):page39_i127@chpset_lib.skx_ext_b(chips)!SKX_EXT_B_BGA1-IC,TBD!!!F80!CD_VCCP_SENSE(1)!!!!
S!VSENSE_PVCCMCP_CPU0_SKT_VSEN!U5D1!BN16!@baseboard_fab2_lib.baseboard_fab2(sch_1):page39_i127@chpset_lib.skx_ext_b(chips)!SKX_EXT_B_BGA1-IC,TBD!!!F80!CD_VCC_CORE_SENSE!!!!
S!VSENSE_PVCCIOMCP_CPU0_SKT_VRTN!U5D1!BU16!@baseboard_fab2_lib.baseboard_fab2(sch_1):page39_i127@chpset_lib.skx_ext_b(chips)!SKX_EXT_B_BGA1-IC,TBD!!!F80!CD_VCCP_SENSE(0)!!!!
S!VSENSE_PVCCMCP_CPU0_SKT_VRTN!U5D1!BL16!@baseboard_fab2_lib.baseboard_fab2(sch_1):page39_i127@chpset_lib.skx_ext_b(chips)!SKX_EXT_B_BGA1-IC,TBD!!!F80!CD_VSS_VCC_CORE_SENSE!!!!
S!PVCCIO_CPU0!U5D1!CJ28!@baseboard_fab2_lib.baseboard_fab2(sch_1):page38_i34@chpset_lib.skx_ext_b(chips)!SKX_EXT_B_BGA1-IC,TBD!!!F81!VCCIO(84)!!!!
S!PVCCIO_CPU0!U5D1!BF27!@baseboard_fab2_lib.baseboard_fab2(sch_1):page38_i34@chpset_lib.skx_ext_b(chips)!SKX_EXT_B_BGA1-IC,TBD!!!F81!VCCIO(94)!!!!
S!PVCCIO_CPU0!U5D1!CH27!@baseboard_fab2_lib.baseboard_fab2(sch_1):page38_i34@chpset_lib.skx_ext_b(chips)!SKX_EXT_B_BGA1-IC,TBD!!!F81!VCCIO(85)!!!!
S!PVCCIO_CPU0!U5D1!BM27!@baseboard_fab2_lib.baseboard_fab2(sch_1):page38_i34@chpset_lib.skx_ext_b(chips)!SKX_EXT_B_BGA1-IC,TBD!!!F81!VCCIO(86)!!!!
S!PVCCIO_CPU0!U5D1!BL26!@baseboard_fab2_lib.baseboard_fab2(sch_1):page38_i34@chpset_lib.skx_ext_b(chips)!SKX_EXT_B_BGA1-IC,TBD!!!F81!VCCIO(87)!!!!
S!PVCCIO_CPU0!U5D1!BK27!@baseboard_fab2_lib.baseboard_fab2(sch_1):page38_i34@chpset_lib.skx_ext_b(chips)!SKX_EXT_B_BGA1-IC,TBD!!!F81!VCCIO(88)!!!!
S!PVCCIO_CPU0!U5D1!BK25!@baseboard_fab2_lib.baseboard_fab2(sch_1):page38_i34@chpset_lib.skx_ext_b(chips)!SKX_EXT_B_BGA1-IC,TBD!!!F81!VCCIO(89)!!!!
S!PVCCIO_CPU0!U5D1!BJ26!@baseboard_fab2_lib.baseboard_fab2(sch_1):page38_i34@chpset_lib.skx_ext_b(chips)!SKX_EXT_B_BGA1-IC,TBD!!!F81!VCCIO(90)!!!!
S!PVCCIO_CPU0!U5D1!BH27!@baseboard_fab2_lib.baseboard_fab2(sch_1):page38_i34@chpset_lib.skx_ext_b(chips)!SKX_EXT_B_BGA1-IC,TBD!!!F81!VCCIO(91)!!!!
S!PVCCIO_CPU0!U5D1!BH25!@baseboard_fab2_lib.baseboard_fab2(sch_1):page38_i34@chpset_lib.skx_ext_b(chips)!SKX_EXT_B_BGA1-IC,TBD!!!F81!VCCIO(92)!!!!
S!PVCCIO_CPU0!U5D1!BG26!@baseboard_fab2_lib.baseboard_fab2(sch_1):page38_i34@chpset_lib.skx_ext_b(chips)!SKX_EXT_B_BGA1-IC,TBD!!!F81!VCCIO(93)!!!!
S!P1V8_MCP_CPU0!U5D1!B17!@baseboard_fab2_lib.baseboard_fab2(sch_1):page22_i204@chpset_lib.skx_ext_b(chips)!SKX_EXT_B_BGA1-IC,TBD!!!F100!RSVD(294)!!!!
S!P1V8_MCP_CPU0!U5D1!B15!@baseboard_fab2_lib.baseboard_fab2(sch_1):page22_i204@chpset_lib.skx_ext_b(chips)!SKX_EXT_B_BGA1-IC,TBD!!!F100!RSVD(295)!!!!
S!P1V8_MCP_CPU0!U5D1!B13!@baseboard_fab2_lib.baseboard_fab2(sch_1):page22_i204@chpset_lib.skx_ext_b(chips)!SKX_EXT_B_BGA1-IC,TBD!!!F100!RSVD(296)!!!!
S!P1V8_MCP_CPU0!U5D1!A16!@baseboard_fab2_lib.baseboard_fab2(sch_1):page22_i204@chpset_lib.skx_ext_b(chips)!SKX_EXT_B_BGA1-IC,TBD!!!F100!RSVD(301)!!!!
S!P1V8_MCP_CPU0!U5D1!A14!@baseboard_fab2_lib.baseboard_fab2(sch_1):page22_i204@chpset_lib.skx_ext_b(chips)!SKX_EXT_B_BGA1-IC,TBD!!!F100!RSVD(302)!!!!
S!PVCCMCP_CPU0!U5D1!DA24!@baseboard_fab2_lib.baseboard_fab2(sch_1):page39_i127@chpset_lib.skx_ext_b(chips)!SKX_EXT_B_BGA1-IC,TBD!!!F80!RSVD(52)!!!!
S!PVCCMCP_CPU0!U5D1!CL26!@baseboard_fab2_lib.baseboard_fab2(sch_1):page39_i127@chpset_lib.skx_ext_b(chips)!SKX_EXT_B_BGA1-IC,TBD!!!F80!RSVD(80)!!!!
S!PVCCMCP_CPU0!U5D1!CL24!@baseboard_fab2_lib.baseboard_fab2(sch_1):page36_i16@chpset_lib.skx_ext_b(chips)!SKX_EXT_B_BGA1-IC,TBD!!!F85!RSVD(81)!!!!
S!PVCCMCP_CPU0!U5D1!CK25!@baseboard_fab2_lib.baseboard_fab2(sch_1):page36_i16@chpset_lib.skx_ext_b(chips)!SKX_EXT_B_BGA1-IC,TBD!!!F85!RSVD(83)!!!!
S!PVCCMCP_CPU0!U5D1!CK23!@baseboard_fab2_lib.baseboard_fab2(sch_1):page36_i16@chpset_lib.skx_ext_b(chips)!SKX_EXT_B_BGA1-IC,TBD!!!F85!RSVD(84)!!!!
S!PVCCMCP_CPU0!U5D1!CJ26!@baseboard_fab2_lib.baseboard_fab2(sch_1):page36_i16@chpset_lib.skx_ext_b(chips)!SKX_EXT_B_BGA1-IC,TBD!!!F85!RSVD(86)!!!!
S!PVCCMCP_CPU0!U5D1!CJ24!@baseboard_fab2_lib.baseboard_fab2(sch_1):page36_i16@chpset_lib.skx_ext_b(chips)!SKX_EXT_B_BGA1-IC,TBD!!!F85!RSVD(87)!!!!
S!PVCCMCP_CPU0!U5D1!CJ22!@baseboard_fab2_lib.baseboard_fab2(sch_1):page36_i16@chpset_lib.skx_ext_b(chips)!SKX_EXT_B_BGA1-IC,TBD!!!F85!RSVD(88)!!!!
S!PVCCMCP_CPU0!U5D1!CJ20!@baseboard_fab2_lib.baseboard_fab2(sch_1):page36_i16@chpset_lib.skx_ext_b(chips)!SKX_EXT_B_BGA1-IC,TBD!!!F85!RSVD(89)!!!!
S!PVCCMCP_CPU0!U5D1!CH23!@baseboard_fab2_lib.baseboard_fab2(sch_1):page36_i15@chpset_lib.skx_ext_b(chips)!SKX_EXT_B_BGA1-IC,TBD!!!F86!RSVD(92)!!!!
S!PVCCMCP_CPU0!U5D1!CH21!@baseboard_fab2_lib.baseboard_fab2(sch_1):page36_i15@chpset_lib.skx_ext_b(chips)!SKX_EXT_B_BGA1-IC,TBD!!!F86!RSVD(93)!!!!
S!PVCCMCP_CPU0!U5D1!CY25!@baseboard_fab2_lib.baseboard_fab2(sch_1):page39_i127@chpset_lib.skx_ext_b(chips)!SKX_EXT_B_BGA1-IC,TBD!!!F80!RSVD(58)!!!!
S!PVCCMCP_CPU0!U5D1!CG26!@baseboard_fab2_lib.baseboard_fab2(sch_1):page36_i15@chpset_lib.skx_ext_b(chips)!SKX_EXT_B_BGA1-IC,TBD!!!F86!RSVD(96)!!!!
S!PVCCMCP_CPU0!U5D1!CG20!@baseboard_fab2_lib.baseboard_fab2(sch_1):page36_i15@chpset_lib.skx_ext_b(chips)!SKX_EXT_B_BGA1-IC,TBD!!!F86!RSVD(98)!!!!
S!PVCCMCP_CPU0!U5D1!CF23!@baseboard_fab2_lib.baseboard_fab2(sch_1):page36_i15@chpset_lib.skx_ext_b(chips)!SKX_EXT_B_BGA1-IC,TBD!!!F86!RSVD(102)!!!!
S!PVCCMCP_CPU0!U5D1!CF21!@baseboard_fab2_lib.baseboard_fab2(sch_1):page36_i15@chpset_lib.skx_ext_b(chips)!SKX_EXT_B_BGA1-IC,TBD!!!F86!RSVD(103)!!!!
S!PVCCMCP_CPU0!U5D1!CF19!@baseboard_fab2_lib.baseboard_fab2(sch_1):page36_i15@chpset_lib.skx_ext_b(chips)!SKX_EXT_B_BGA1-IC,TBD!!!F86!RSVD(104)!!!!
S!PVCCMCP_CPU0!U5D1!CE22!@baseboard_fab2_lib.baseboard_fab2(sch_1):page36_i15@chpset_lib.skx_ext_b(chips)!SKX_EXT_B_BGA1-IC,TBD!!!F86!RSVD(107)!!!!
S!PVCCMCP_CPU0!U5D1!CD21!@baseboard_fab2_lib.baseboard_fab2(sch_1):page36_i15@chpset_lib.skx_ext_b(chips)!SKX_EXT_B_BGA1-IC,TBD!!!F86!RSVD(109)!!!!
S!PVCCMCP_CPU0!U5D1!CD19!@baseboard_fab2_lib.baseboard_fab2(sch_1):page36_i15@chpset_lib.skx_ext_b(chips)!SKX_EXT_B_BGA1-IC,TBD!!!F86!RSVD(110)!!!!
S!PVCCMCP_CPU0!U5D1!CC20!@baseboard_fab2_lib.baseboard_fab2(sch_1):page36_i15@chpset_lib.skx_ext_b(chips)!SKX_EXT_B_BGA1-IC,TBD!!!F86!RSVD(112)!!!!
S!PVCCMCP_CPU0!U5D1!CB21!@baseboard_fab2_lib.baseboard_fab2(sch_1):page36_i15@chpset_lib.skx_ext_b(chips)!SKX_EXT_B_BGA1-IC,TBD!!!F86!RSVD(115)!!!!
S!PVCCMCP_CPU0!U5D1!CW24!@baseboard_fab2_lib.baseboard_fab2(sch_1):page39_i127@chpset_lib.skx_ext_b(chips)!SKX_EXT_B_BGA1-IC,TBD!!!F80!RSVD(62)!!!!
S!PVCCMCP_CPU0!U5D1!CB19!@baseboard_fab2_lib.baseboard_fab2(sch_1):page36_i15@chpset_lib.skx_ext_b(chips)!SKX_EXT_B_BGA1-IC,TBD!!!F86!RSVD(116)!!!!
S!PVCCMCP_CPU0!U5D1!CA22!@baseboard_fab2_lib.baseboard_fab2(sch_1):page36_i15@chpset_lib.skx_ext_b(chips)!SKX_EXT_B_BGA1-IC,TBD!!!F86!RSVD(118)!!!!
S!PVCCMCP_CPU0!U5D1!BY19!@baseboard_fab2_lib.baseboard_fab2(sch_1):page36_i15@chpset_lib.skx_ext_b(chips)!SKX_EXT_B_BGA1-IC,TBD!!!F86!RSVD(120)!!!!
S!PVCCMCP_CPU0!U5D1!BW20!@baseboard_fab2_lib.baseboard_fab2(sch_1):page36_i15@chpset_lib.skx_ext_b(chips)!SKX_EXT_B_BGA1-IC,TBD!!!F86!RSVD(122)!!!!
S!PVCCMCP_CPU0!U5D1!BV21!@baseboard_fab2_lib.baseboard_fab2(sch_1):page36_i15@chpset_lib.skx_ext_b(chips)!SKX_EXT_B_BGA1-IC,TBD!!!F86!RSVD(125)!!!!
S!PVCCMCP_CPU0!U5D1!BV19!@baseboard_fab2_lib.baseboard_fab2(sch_1):page36_i15@chpset_lib.skx_ext_b(chips)!SKX_EXT_B_BGA1-IC,TBD!!!F86!RSVD(126)!!!!
S!PVCCMCP_CPU0!U5D1!BU22!@baseboard_fab2_lib.baseboard_fab2(sch_1):page36_i15@chpset_lib.skx_ext_b(chips)!SKX_EXT_B_BGA1-IC,TBD!!!F86!RSVD(127)!!!!
S!PVCCMCP_CPU0!U5D1!BU20!@baseboard_fab2_lib.baseboard_fab2(sch_1):page36_i15@chpset_lib.skx_ext_b(chips)!SKX_EXT_B_BGA1-IC,TBD!!!F86!RSVD(128)!!!!
S!PVCCMCP_CPU0!U5D1!BU18!@baseboard_fab2_lib.baseboard_fab2(sch_1):page36_i15@chpset_lib.skx_ext_b(chips)!SKX_EXT_B_BGA1-IC,TBD!!!F86!RSVD(129)!!!!
S!PVCCMCP_CPU0!U5D1!BR24!@baseboard_fab2_lib.baseboard_fab2(sch_1):page36_i15@chpset_lib.skx_ext_b(chips)!SKX_EXT_B_BGA1-IC,TBD!!!F86!RSVD(130)!!!!
S!PVCCMCP_CPU0!U5D1!CV23!@baseboard_fab2_lib.baseboard_fab2(sch_1):page39_i127@chpset_lib.skx_ext_b(chips)!SKX_EXT_B_BGA1-IC,TBD!!!F80!RSVD(65)!!!!
S!PVCCMCP_CPU0!U5D1!BR22!@baseboard_fab2_lib.baseboard_fab2(sch_1):page36_i15@chpset_lib.skx_ext_b(chips)!SKX_EXT_B_BGA1-IC,TBD!!!F86!RSVD(131)!!!!
S!PVCCMCP_CPU0!U5D1!BP21!@baseboard_fab2_lib.baseboard_fab2(sch_1):page36_i15@chpset_lib.skx_ext_b(chips)!SKX_EXT_B_BGA1-IC,TBD!!!F86!RSVD(132)!!!!
S!PVCCMCP_CPU0!U5D1!BP17!@baseboard_fab2_lib.baseboard_fab2(sch_1):page36_i15@chpset_lib.skx_ext_b(chips)!SKX_EXT_B_BGA1-IC,TBD!!!F86!RSVD(133)!!!!
S!PVCCMCP_CPU0!U5D1!BN18!@baseboard_fab2_lib.baseboard_fab2(sch_1):page36_i15@chpset_lib.skx_ext_b(chips)!SKX_EXT_B_BGA1-IC,TBD!!!F86!RSVD(134)!!!!
S!PVCCMCP_CPU0!U5D1!BM19!@baseboard_fab2_lib.baseboard_fab2(sch_1):page36_i15@chpset_lib.skx_ext_b(chips)!SKX_EXT_B_BGA1-IC,TBD!!!F86!RSVD(135)!!!!
S!PVCCMCP_CPU0!U5D1!BM17!@baseboard_fab2_lib.baseboard_fab2(sch_1):page36_i15@chpset_lib.skx_ext_b(chips)!SKX_EXT_B_BGA1-IC,TBD!!!F86!RSVD(136)!!!!
S!PVCCMCP_CPU0!U5D1!BL20!@baseboard_fab2_lib.baseboard_fab2(sch_1):page36_i15@chpset_lib.skx_ext_b(chips)!SKX_EXT_B_BGA1-IC,TBD!!!F86!RSVD(137)!!!!
S!PVCCMCP_CPU0!U5D1!BL18!@baseboard_fab2_lib.baseboard_fab2(sch_1):page36_i15@chpset_lib.skx_ext_b(chips)!SKX_EXT_B_BGA1-IC,TBD!!!F86!RSVD(138)!!!!
S!PVCCMCP_CPU0!U5D1!BK17!@baseboard_fab2_lib.baseboard_fab2(sch_1):page36_i15@chpset_lib.skx_ext_b(chips)!SKX_EXT_B_BGA1-IC,TBD!!!F86!RSVD(139)!!!!
S!PVCCMCP_CPU0!U5D1!BJ20!@baseboard_fab2_lib.baseboard_fab2(sch_1):page36_i15@chpset_lib.skx_ext_b(chips)!SKX_EXT_B_BGA1-IC,TBD!!!F86!RSVD(140)!!!!
S!PVCCMCP_CPU0!U5D1!CU24!@baseboard_fab2_lib.baseboard_fab2(sch_1):page39_i127@chpset_lib.skx_ext_b(chips)!SKX_EXT_B_BGA1-IC,TBD!!!F80!RSVD(68)!!!!
S!PVCCMCP_CPU0!U5D1!BJ18!@baseboard_fab2_lib.baseboard_fab2(sch_1):page36_i15@chpset_lib.skx_ext_b(chips)!SKX_EXT_B_BGA1-IC,TBD!!!F86!RSVD(141)!!!!
S!PVCCMCP_CPU0!U5D1!BJ16!@baseboard_fab2_lib.baseboard_fab2(sch_1):page36_i15@chpset_lib.skx_ext_b(chips)!SKX_EXT_B_BGA1-IC,TBD!!!F86!RSVD(142)!!!!
S!PVCCMCP_CPU0!U5D1!BH19!@baseboard_fab2_lib.baseboard_fab2(sch_1):page36_i15@chpset_lib.skx_ext_b(chips)!SKX_EXT_B_BGA1-IC,TBD!!!F86!RSVD(143)!!!!
S!PVCCMCP_CPU0!U5D1!CT23!@baseboard_fab2_lib.baseboard_fab2(sch_1):page39_i127@chpset_lib.skx_ext_b(chips)!SKX_EXT_B_BGA1-IC,TBD!!!F80!RSVD(71)!!!!
S!PVCCMCP_CPU0!U5D1!CP23!@baseboard_fab2_lib.baseboard_fab2(sch_1):page39_i127@chpset_lib.skx_ext_b(chips)!SKX_EXT_B_BGA1-IC,TBD!!!F80!RSVD(74)!!!!
S!PVCCMCP_CPU0!U5D1!CN24!@baseboard_fab2_lib.baseboard_fab2(sch_1):page39_i127@chpset_lib.skx_ext_b(chips)!SKX_EXT_B_BGA1-IC,TBD!!!F80!RSVD(76)!!!!
S!PVCCMCP_CPU0!U5D1!CM25!@baseboard_fab2_lib.baseboard_fab2(sch_1):page39_i127@chpset_lib.skx_ext_b(chips)!SKX_EXT_B_BGA1-IC,TBD!!!F80!RSVD(78)!!!!
S!PVCCMCP_CPU0!U5D1!CM23!@baseboard_fab2_lib.baseboard_fab2(sch_1):page39_i127@chpset_lib.skx_ext_b(chips)!SKX_EXT_B_BGA1-IC,TBD!!!F80!RSVD(79)!!!!
S!PVCCMCP_CPU0!U5D1!AT25!@baseboard_fab2_lib.baseboard_fab2(sch_1):page29_i61@chpset_lib.skx_ext_b(chips)!SKX_EXT_B_BGA1-IC,TBD!!!F93!RSVD(187)!!!!
S!PVCCMCP_CPU0!U5D1!AN18!@baseboard_fab2_lib.baseboard_fab2(sch_1):page22_i204@chpset_lib.skx_ext_b(chips)!SKX_EXT_B_BGA1-IC,TBD!!!F100!RSVD(203)!!!!
S!PVCCMCP_CPU0!U5D1!AM25!@baseboard_fab2_lib.baseboard_fab2(sch_1):page22_i204@chpset_lib.skx_ext_b(chips)!SKX_EXT_B_BGA1-IC,TBD!!!F100!RSVD(207)!!!!
S!PVCCMCP_CPU0!U5D1!AM21!@baseboard_fab2_lib.baseboard_fab2(sch_1):page22_i204@chpset_lib.skx_ext_b(chips)!SKX_EXT_B_BGA1-IC,TBD!!!F100!RSVD(209)!!!!
S!VSENSE_P1V8MCP_CPU0_SKT_VRTN!U5D1!AL20!@baseboard_fab2_lib.baseboard_fab2(sch_1):page22_i204@chpset_lib.skx_ext_b(chips)!SKX_EXT_B_BGA1-IC,TBD!!!F100!RSVD(215)!!!!
S!VSENSE_P1V8MCP_CPU0_SKT_VSEN!U5D1!AK21!@baseboard_fab2_lib.baseboard_fab2(sch_1):page22_i204@chpset_lib.skx_ext_b(chips)!SKX_EXT_B_BGA1-IC,TBD!!!F100!RSVD(221)!!!!
S!PVCCMCP_CPU0!U5D1!AT23!@baseboard_fab2_lib.baseboard_fab2(sch_1):page29_i61@chpset_lib.skx_ext_b(chips)!SKX_EXT_B_BGA1-IC,TBD!!!F93!RSVD(188)!!!!
S!PVCCMCP_CPU0!U5D1!AR26!@baseboard_fab2_lib.baseboard_fab2(sch_1):page29_i61@chpset_lib.skx_ext_b(chips)!SKX_EXT_B_BGA1-IC,TBD!!!F93!RSVD(191)!!!!
S!PVCCMCP_CPU0!U5D1!AR22!@baseboard_fab2_lib.baseboard_fab2(sch_1):page29_i61@chpset_lib.skx_ext_b(chips)!SKX_EXT_B_BGA1-IC,TBD!!!F93!RSVD(192)!!!!
S!PVCCMCP_CPU0!U5D1!AR20!@baseboard_fab2_lib.baseboard_fab2(sch_1):page29_i61@chpset_lib.skx_ext_b(chips)!SKX_EXT_B_BGA1-IC,TBD!!!F93!RSVD(193)!!!!
S!PVCCMCP_CPU0!U5D1!AP25!@baseboard_fab2_lib.baseboard_fab2(sch_1):page22_i204@chpset_lib.skx_ext_b(chips)!SKX_EXT_B_BGA1-IC,TBD!!!F100!RSVD(196)!!!!
S!PVCCMCP_CPU0!U5D1!AP23!@baseboard_fab2_lib.baseboard_fab2(sch_1):page22_i204@chpset_lib.skx_ext_b(chips)!SKX_EXT_B_BGA1-IC,TBD!!!F100!RSVD(197)!!!!
S!PVCCMCP_CPU0!U5D1!AN26!@baseboard_fab2_lib.baseboard_fab2(sch_1):page22_i204@chpset_lib.skx_ext_b(chips)!SKX_EXT_B_BGA1-IC,TBD!!!F100!RSVD(200)!!!!
S!PVCCMCP_CPU0!U5D1!AN24!@baseboard_fab2_lib.baseboard_fab2(sch_1):page22_i204@chpset_lib.skx_ext_b(chips)!SKX_EXT_B_BGA1-IC,TBD!!!F100!RSVD(201)!!!!
S!PVCCMCP_CPU0!U5D1!AN22!@baseboard_fab2_lib.baseboard_fab2(sch_1):page22_i204@chpset_lib.skx_ext_b(chips)!SKX_EXT_B_BGA1-IC,TBD!!!F100!RSVD(202)!!!!
S!PVCCIO_CPU0!U5D1!AE36!@baseboard_fab2_lib.baseboard_fab2(sch_1):page38_i34@chpset_lib.skx_ext_b(chips)!SKX_EXT_B_BGA1-IC,TBD!!!F81!VCCIO(95)!!!!
S!PVCCIO_CPU0!U5D1!AD37!@baseboard_fab2_lib.baseboard_fab2(sch_1):page38_i34@chpset_lib.skx_ext_b(chips)!SKX_EXT_B_BGA1-IC,TBD!!!F81!VCCIO(96)!!!!
S!PVCCIO_CPU0!U5D1!AC36!@baseboard_fab2_lib.baseboard_fab2(sch_1):page38_i34@chpset_lib.skx_ext_b(chips)!SKX_EXT_B_BGA1-IC,TBD!!!F81!VCCIO(97)!!!!
S!PVCCIO_CPU0!U5D1!AF35!@baseboard_fab2_lib.baseboard_fab2(sch_1):page38_i34@chpset_lib.skx_ext_b(chips)!SKX_EXT_B_BGA1-IC,TBD!!!F81!VCCIO(98)!!!!
S!PVCCIO_CPU0!U5D1!AD35!@baseboard_fab2_lib.baseboard_fab2(sch_1):page38_i34@chpset_lib.skx_ext_b(chips)!SKX_EXT_B_BGA1-IC,TBD!!!F81!VCCIO(99)!!!!
S!PVCCIO_CPU0!U5D1!AE34!@baseboard_fab2_lib.baseboard_fab2(sch_1):page38_i34@chpset_lib.skx_ext_b(chips)!SKX_EXT_B_BGA1-IC,TBD!!!F81!VCCIO(100)!!!!
S!PVCCIO_CPU0!U5D1!AG34!@baseboard_fab2_lib.baseboard_fab2(sch_1):page38_i34@chpset_lib.skx_ext_b(chips)!SKX_EXT_B_BGA1-IC,TBD!!!F81!VCCIO(101)!!!!
S!PVCCIO_CPU0!U5D1!AM29!@baseboard_fab2_lib.baseboard_fab2(sch_1):page38_i34@chpset_lib.skx_ext_b(chips)!SKX_EXT_B_BGA1-IC,TBD!!!F81!VCCIO(102)!!!!
S!PVCCIO_CPU0!U5D1!AL28!@baseboard_fab2_lib.baseboard_fab2(sch_1):page38_i34@chpset_lib.skx_ext_b(chips)!SKX_EXT_B_BGA1-IC,TBD!!!F81!VCCIO(103)!!!!
S!CLK_100M_CPU0_RC_REFCLK0_DP!U5D1!AM27!@baseboard_fab2_lib.baseboard_fab2(sch_1):page22_i204@chpset_lib.skx_ext_b(chips)!SKX_EXT_B_BGA1-IC,TBD!!!F100!RSVD(206)!!!!
S!VSENSE_PVCCIO_CPU0_SKT_VSEN!U5D1!BH5!@baseboard_fab2_lib.baseboard_fab2(sch_1):page39_i127@chpset_lib.skx_ext_b(chips)!SKX_EXT_B_BGA1-IC,TBD!!!F80!VCCIO_SENSE!!!!
S!VSENSE_PVSA_CPU0_SKT_VSEN!U5D1!CE76!@baseboard_fab2_lib.baseboard_fab2(sch_1):page39_i127@chpset_lib.skx_ext_b(chips)!SKX_EXT_B_BGA1-IC,TBD!!!F80!VCCSA_SENSE!!!!
S!VSENSE_PVCCIO_CPU0_SKT_VRTN!U5D1!BF5!@baseboard_fab2_lib.baseboard_fab2(sch_1):page39_i127@chpset_lib.skx_ext_b(chips)!SKX_EXT_B_BGA1-IC,TBD!!!F80!VSS_VCCIO_SENSE!!!!
S!VSENSE_PVSA_CPU0_SKT_VRTN!U5D1!CG76!@baseboard_fab2_lib.baseboard_fab2(sch_1):page39_i127@chpset_lib.skx_ext_b(chips)!SKX_EXT_B_BGA1-IC,TBD!!!F80!VSS_VCCSA_SENSE!!!!
S!GND!U5D1!L72!@baseboard_fab2_lib.baseboard_fab2(sch_1):page40_i21@chpset_lib.skx_ext_b(chips)!SKX_EXT_B_BGA1-IC,TBD!!!F78!VSS(1068)!!!!
S!GND!U5D1!L22!@baseboard_fab2_lib.baseboard_fab2(sch_1):page40_i21@chpset_lib.skx_ext_b(chips)!SKX_EXT_B_BGA1-IC,TBD!!!F78!VSS(1069)!!!!
S!GND!U5D1!L20!@baseboard_fab2_lib.baseboard_fab2(sch_1):page40_i21@chpset_lib.skx_ext_b(chips)!SKX_EXT_B_BGA1-IC,TBD!!!F78!VSS(1070)!!!!
S!GND!U5D1!L6!@baseboard_fab2_lib.baseboard_fab2(sch_1):page40_i21@chpset_lib.skx_ext_b(chips)!SKX_EXT_B_BGA1-IC,TBD!!!F78!VSS(1071)!!!!
S!GND!U5D1!L2!@baseboard_fab2_lib.baseboard_fab2(sch_1):page40_i21@chpset_lib.skx_ext_b(chips)!SKX_EXT_B_BGA1-IC,TBD!!!F78!VSS(1072)!!!!
S!GND!U5D1!L10!@baseboard_fab2_lib.baseboard_fab2(sch_1):page40_i21@chpset_lib.skx_ext_b(chips)!SKX_EXT_B_BGA1-IC,TBD!!!F78!VSS(1073)!!!!
S!GND!U5D1!K85!@baseboard_fab2_lib.baseboard_fab2(sch_1):page40_i21@chpset_lib.skx_ext_b(chips)!SKX_EXT_B_BGA1-IC,TBD!!!F78!VSS(1074)!!!!
S!GND!U5D1!K83!@baseboard_fab2_lib.baseboard_fab2(sch_1):page40_i21@chpset_lib.skx_ext_b(chips)!SKX_EXT_B_BGA1-IC,TBD!!!F78!VSS(1075)!!!!
S!GND!U5D1!K81!@baseboard_fab2_lib.baseboard_fab2(sch_1):page40_i21@chpset_lib.skx_ext_b(chips)!SKX_EXT_B_BGA1-IC,TBD!!!F78!VSS(1076)!!!!
S!GND!U5D1!K77!@baseboard_fab2_lib.baseboard_fab2(sch_1):page40_i21@chpset_lib.skx_ext_b(chips)!SKX_EXT_B_BGA1-IC,TBD!!!F78!VSS(1077)!!!!
S!GND!U5D1!K73!@baseboard_fab2_lib.baseboard_fab2(sch_1):page40_i21@chpset_lib.skx_ext_b(chips)!SKX_EXT_B_BGA1-IC,TBD!!!F78!VSS(1078)!!!!
S!GND!U5D1!K71!@baseboard_fab2_lib.baseboard_fab2(sch_1):page40_i21@chpset_lib.skx_ext_b(chips)!SKX_EXT_B_BGA1-IC,TBD!!!F78!VSS(1079)!!!!
S!GND!U5D1!K69!@baseboard_fab2_lib.baseboard_fab2(sch_1):page40_i21@chpset_lib.skx_ext_b(chips)!SKX_EXT_B_BGA1-IC,TBD!!!F78!VSS(1080)!!!!
S!GND!U5D1!K67!@baseboard_fab2_lib.baseboard_fab2(sch_1):page40_i21@chpset_lib.skx_ext_b(chips)!SKX_EXT_B_BGA1-IC,TBD!!!F78!VSS(1081)!!!!
S!GND!U5D1!K65!@baseboard_fab2_lib.baseboard_fab2(sch_1):page40_i21@chpset_lib.skx_ext_b(chips)!SKX_EXT_B_BGA1-IC,TBD!!!F78!VSS(1082)!!!!
S!GND!U5D1!K39!@baseboard_fab2_lib.baseboard_fab2(sch_1):page40_i21@chpset_lib.skx_ext_b(chips)!SKX_EXT_B_BGA1-IC,TBD!!!F78!VSS(1083)!!!!
S!GND!U5D1!K33!@baseboard_fab2_lib.baseboard_fab2(sch_1):page40_i21@chpset_lib.skx_ext_b(chips)!SKX_EXT_B_BGA1-IC,TBD!!!F78!VSS(1084)!!!!
S!GND!U5D1!K27!@baseboard_fab2_lib.baseboard_fab2(sch_1):page40_i21@chpset_lib.skx_ext_b(chips)!SKX_EXT_B_BGA1-IC,TBD!!!F78!VSS(1085)!!!!
S!GND!U5D1!DB7!@baseboard_fab2_lib.baseboard_fab2(sch_1):page40_i21@chpset_lib.skx_ext_b(chips)!SKX_EXT_B_BGA1-IC,TBD!!!F78!VSS(1086)!!!!
S!GND!U5D1!K17!@baseboard_fab2_lib.baseboard_fab2(sch_1):page40_i21@chpset_lib.skx_ext_b(chips)!SKX_EXT_B_BGA1-IC,TBD!!!F78!VSS(1087)!!!!
S!GND!U5D1!K13!@baseboard_fab2_lib.baseboard_fab2(sch_1):page40_i21@chpset_lib.skx_ext_b(chips)!SKX_EXT_B_BGA1-IC,TBD!!!F78!VSS(1088)!!!!
S!GND!U5D1!K11!@baseboard_fab2_lib.baseboard_fab2(sch_1):page40_i21@chpset_lib.skx_ext_b(chips)!SKX_EXT_B_BGA1-IC,TBD!!!F78!VSS(1089)!!!!
S!GND!U5D1!K1!@baseboard_fab2_lib.baseboard_fab2(sch_1):page40_i21@chpset_lib.skx_ext_b(chips)!SKX_EXT_B_BGA1-IC,TBD!!!F78!VSS(1090)!!!!
S!GND!U5D1!J84!@baseboard_fab2_lib.baseboard_fab2(sch_1):page40_i21@chpset_lib.skx_ext_b(chips)!SKX_EXT_B_BGA1-IC,TBD!!!F78!VSS(1091)!!!!
S!GND!U5D1!J82!@baseboard_fab2_lib.baseboard_fab2(sch_1):page40_i21@chpset_lib.skx_ext_b(chips)!SKX_EXT_B_BGA1-IC,TBD!!!F78!VSS(1092)!!!!
S!GND!U5D1!J76!@baseboard_fab2_lib.baseboard_fab2(sch_1):page40_i21@chpset_lib.skx_ext_b(chips)!SKX_EXT_B_BGA1-IC,TBD!!!F78!VSS(1093)!!!!
S!GND!U5D1!J74!@baseboard_fab2_lib.baseboard_fab2(sch_1):page40_i20@chpset_lib.skx_ext_b(chips)!SKX_EXT_B_BGA1-IC,TBD!!!F79!VSS(1094)!!!!
S!GND!U5D1!J72!@baseboard_fab2_lib.baseboard_fab2(sch_1):page40_i20@chpset_lib.skx_ext_b(chips)!SKX_EXT_B_BGA1-IC,TBD!!!F79!VSS(1095)!!!!
S!GND!U5D1!J40!@baseboard_fab2_lib.baseboard_fab2(sch_1):page40_i20@chpset_lib.skx_ext_b(chips)!SKX_EXT_B_BGA1-IC,TBD!!!F79!VSS(1096)!!!!
S!GND!U5D1!J38!@baseboard_fab2_lib.baseboard_fab2(sch_1):page40_i20@chpset_lib.skx_ext_b(chips)!SKX_EXT_B_BGA1-IC,TBD!!!F79!VSS(1097)!!!!
S!GND!U5D1!J34!@baseboard_fab2_lib.baseboard_fab2(sch_1):page40_i20@chpset_lib.skx_ext_b(chips)!SKX_EXT_B_BGA1-IC,TBD!!!F79!VSS(1098)!!!!
S!GND!U5D1!J32!@baseboard_fab2_lib.baseboard_fab2(sch_1):page40_i20@chpset_lib.skx_ext_b(chips)!SKX_EXT_B_BGA1-IC,TBD!!!F79!VSS(1099)!!!!
S!GND!U5D1!J28!@baseboard_fab2_lib.baseboard_fab2(sch_1):page40_i20@chpset_lib.skx_ext_b(chips)!SKX_EXT_B_BGA1-IC,TBD!!!F79!VSS(1100)!!!!
S!GND!U5D1!J26!@baseboard_fab2_lib.baseboard_fab2(sch_1):page40_i20@chpset_lib.skx_ext_b(chips)!SKX_EXT_B_BGA1-IC,TBD!!!F79!VSS(1101)!!!!
S!GND!U5D1!J22!@baseboard_fab2_lib.baseboard_fab2(sch_1):page40_i20@chpset_lib.skx_ext_b(chips)!SKX_EXT_B_BGA1-IC,TBD!!!F79!VSS(1102)!!!!
S!GND!U5D1!J14!@baseboard_fab2_lib.baseboard_fab2(sch_1):page40_i20@chpset_lib.skx_ext_b(chips)!SKX_EXT_B_BGA1-IC,TBD!!!F79!VSS(1103)!!!!
S!GND!U5D1!J12!@baseboard_fab2_lib.baseboard_fab2(sch_1):page40_i20@chpset_lib.skx_ext_b(chips)!SKX_EXT_B_BGA1-IC,TBD!!!F79!VSS(1104)!!!!
S!GND!U5D1!J4!@baseboard_fab2_lib.baseboard_fab2(sch_1):page40_i20@chpset_lib.skx_ext_b(chips)!SKX_EXT_B_BGA1-IC,TBD!!!F79!VSS(1105)!!!!
S!GND!U5D1!DN44!@baseboard_fab2_lib.baseboard_fab2(sch_1):page40_i20@chpset_lib.skx_ext_b(chips)!SKX_EXT_B_BGA1-IC,TBD!!!F79!VSS(1106)!!!!
S!GND!U5D1!H75!@baseboard_fab2_lib.baseboard_fab2(sch_1):page40_i20@chpset_lib.skx_ext_b(chips)!SKX_EXT_B_BGA1-IC,TBD!!!F79!VSS(1107)!!!!
S!GND!U5D1!H71!@baseboard_fab2_lib.baseboard_fab2(sch_1):page40_i20@chpset_lib.skx_ext_b(chips)!SKX_EXT_B_BGA1-IC,TBD!!!F79!VSS(1108)!!!!
S!GND!U5D1!H65!@baseboard_fab2_lib.baseboard_fab2(sch_1):page40_i20@chpset_lib.skx_ext_b(chips)!SKX_EXT_B_BGA1-IC,TBD!!!F79!VSS(1109)!!!!
S!GND!U5D1!H41!@baseboard_fab2_lib.baseboard_fab2(sch_1):page40_i20@chpset_lib.skx_ext_b(chips)!SKX_EXT_B_BGA1-IC,TBD!!!F79!VSS(1110)!!!!
S!GND!U5D1!H39!@baseboard_fab2_lib.baseboard_fab2(sch_1):page40_i20@chpset_lib.skx_ext_b(chips)!SKX_EXT_B_BGA1-IC,TBD!!!F79!VSS(1111)!!!!
S!GND!U5D1!H37!@baseboard_fab2_lib.baseboard_fab2(sch_1):page40_i20@chpset_lib.skx_ext_b(chips)!SKX_EXT_B_BGA1-IC,TBD!!!F79!VSS(1112)!!!!
S!GND!U5D1!H35!@baseboard_fab2_lib.baseboard_fab2(sch_1):page40_i20@chpset_lib.skx_ext_b(chips)!SKX_EXT_B_BGA1-IC,TBD!!!F79!VSS(1113)!!!!
S!GND!U5D1!H33!@baseboard_fab2_lib.baseboard_fab2(sch_1):page40_i20@chpset_lib.skx_ext_b(chips)!SKX_EXT_B_BGA1-IC,TBD!!!F79!VSS(1114)!!!!
S!GND!U5D1!H31!@baseboard_fab2_lib.baseboard_fab2(sch_1):page40_i20@chpset_lib.skx_ext_b(chips)!SKX_EXT_B_BGA1-IC,TBD!!!F79!VSS(1115)!!!!
S!GND!U5D1!H29!@baseboard_fab2_lib.baseboard_fab2(sch_1):page40_i20@chpset_lib.skx_ext_b(chips)!SKX_EXT_B_BGA1-IC,TBD!!!F79!VSS(1116)!!!!
S!GND!U5D1!H27!@baseboard_fab2_lib.baseboard_fab2(sch_1):page40_i20@chpset_lib.skx_ext_b(chips)!SKX_EXT_B_BGA1-IC,TBD!!!F79!VSS(1117)!!!!
S!GND!U5D1!H25!@baseboard_fab2_lib.baseboard_fab2(sch_1):page40_i20@chpset_lib.skx_ext_b(chips)!SKX_EXT_B_BGA1-IC,TBD!!!F79!VSS(1118)!!!!
S!GND!U5D1!H11!@baseboard_fab2_lib.baseboard_fab2(sch_1):page40_i20@chpset_lib.skx_ext_b(chips)!SKX_EXT_B_BGA1-IC,TBD!!!F79!VSS(1119)!!!!
S!GND!U5D1!H3!@baseboard_fab2_lib.baseboard_fab2(sch_1):page40_i20@chpset_lib.skx_ext_b(chips)!SKX_EXT_B_BGA1-IC,TBD!!!F79!VSS(1120)!!!!
S!GND!U5D1!G82!@baseboard_fab2_lib.baseboard_fab2(sch_1):page40_i20@chpset_lib.skx_ext_b(chips)!SKX_EXT_B_BGA1-IC,TBD!!!F79!VSS(1121)!!!!
S!GND!U5D1!G80!@baseboard_fab2_lib.baseboard_fab2(sch_1):page40_i20@chpset_lib.skx_ext_b(chips)!SKX_EXT_B_BGA1-IC,TBD!!!F79!VSS(1122)!!!!
S!GND!U5D1!G78!@baseboard_fab2_lib.baseboard_fab2(sch_1):page40_i20@chpset_lib.skx_ext_b(chips)!SKX_EXT_B_BGA1-IC,TBD!!!F79!VSS(1123)!!!!
S!GND!U5D1!G76!@baseboard_fab2_lib.baseboard_fab2(sch_1):page40_i20@chpset_lib.skx_ext_b(chips)!SKX_EXT_B_BGA1-IC,TBD!!!F79!VSS(1124)!!!!
S!GND!U5D1!G70!@baseboard_fab2_lib.baseboard_fab2(sch_1):page40_i20@chpset_lib.skx_ext_b(chips)!SKX_EXT_B_BGA1-IC,TBD!!!F79!VSS(1125)!!!!
S!GND!U5D1!G66!@baseboard_fab2_lib.baseboard_fab2(sch_1):page40_i20@chpset_lib.skx_ext_b(chips)!SKX_EXT_B_BGA1-IC,TBD!!!F79!VSS(1126)!!!!
S!GND!U5D1!G42!@baseboard_fab2_lib.baseboard_fab2(sch_1):page40_i20@chpset_lib.skx_ext_b(chips)!SKX_EXT_B_BGA1-IC,TBD!!!F79!VSS(1127)!!!!
S!GND!U5D1!G38!@baseboard_fab2_lib.baseboard_fab2(sch_1):page40_i20@chpset_lib.skx_ext_b(chips)!SKX_EXT_B_BGA1-IC,TBD!!!F79!VSS(1128)!!!!
S!GND!U5D1!G36!@baseboard_fab2_lib.baseboard_fab2(sch_1):page40_i20@chpset_lib.skx_ext_b(chips)!SKX_EXT_B_BGA1-IC,TBD!!!F79!VSS(1129)!!!!
S!GND!U5D1!G32!@baseboard_fab2_lib.baseboard_fab2(sch_1):page40_i20@chpset_lib.skx_ext_b(chips)!SKX_EXT_B_BGA1-IC,TBD!!!F79!VSS(1130)!!!!
S!GND!U5D1!G30!@baseboard_fab2_lib.baseboard_fab2(sch_1):page40_i20@chpset_lib.skx_ext_b(chips)!SKX_EXT_B_BGA1-IC,TBD!!!F79!VSS(1131)!!!!
S!GND!U5D1!G26!@baseboard_fab2_lib.baseboard_fab2(sch_1):page40_i20@chpset_lib.skx_ext_b(chips)!SKX_EXT_B_BGA1-IC,TBD!!!F79!VSS(1132)!!!!
S!GND!U5D1!G24!@baseboard_fab2_lib.baseboard_fab2(sch_1):page40_i20@chpset_lib.skx_ext_b(chips)!SKX_EXT_B_BGA1-IC,TBD!!!F79!VSS(1133)!!!!
S!GND!U5D1!G22!@baseboard_fab2_lib.baseboard_fab2(sch_1):page40_i20@chpset_lib.skx_ext_b(chips)!SKX_EXT_B_BGA1-IC,TBD!!!F79!VSS(1134)!!!!
S!GND!U5D1!G8!@baseboard_fab2_lib.baseboard_fab2(sch_1):page40_i20@chpset_lib.skx_ext_b(chips)!SKX_EXT_B_BGA1-IC,TBD!!!F79!VSS(1135)!!!!
S!GND!U5D1!G4!@baseboard_fab2_lib.baseboard_fab2(sch_1):page40_i20@chpset_lib.skx_ext_b(chips)!SKX_EXT_B_BGA1-IC,TBD!!!F79!VSS(1136)!!!!
S!GND!U5D1!F69!@baseboard_fab2_lib.baseboard_fab2(sch_1):page40_i20@chpset_lib.skx_ext_b(chips)!SKX_EXT_B_BGA1-IC,TBD!!!F79!VSS(1137)!!!!
S!GND!U5D1!F67!@baseboard_fab2_lib.baseboard_fab2(sch_1):page40_i20@chpset_lib.skx_ext_b(chips)!SKX_EXT_B_BGA1-IC,TBD!!!F79!VSS(1138)!!!!
S!GND!U5D1!F43!@baseboard_fab2_lib.baseboard_fab2(sch_1):page40_i20@chpset_lib.skx_ext_b(chips)!SKX_EXT_B_BGA1-IC,TBD!!!F79!VSS(1139)!!!!
S!GND!U5D1!F37!@baseboard_fab2_lib.baseboard_fab2(sch_1):page40_i20@chpset_lib.skx_ext_b(chips)!SKX_EXT_B_BGA1-IC,TBD!!!F79!VSS(1140)!!!!
S!GND!U5D1!F31!@baseboard_fab2_lib.baseboard_fab2(sch_1):page40_i20@chpset_lib.skx_ext_b(chips)!SKX_EXT_B_BGA1-IC,TBD!!!F79!VSS(1141)!!!!
S!GND!U5D1!F25!@baseboard_fab2_lib.baseboard_fab2(sch_1):page40_i20@chpset_lib.skx_ext_b(chips)!SKX_EXT_B_BGA1-IC,TBD!!!F79!VSS(1142)!!!!
S!GND!U5D1!F19!@baseboard_fab2_lib.baseboard_fab2(sch_1):page40_i20@chpset_lib.skx_ext_b(chips)!SKX_EXT_B_BGA1-IC,TBD!!!F79!VSS(1143)!!!!
S!GND!U5D1!F17!@baseboard_fab2_lib.baseboard_fab2(sch_1):page40_i20@chpset_lib.skx_ext_b(chips)!SKX_EXT_B_BGA1-IC,TBD!!!F79!VSS(1144)!!!!
S!GND!U5D1!F5!@baseboard_fab2_lib.baseboard_fab2(sch_1):page40_i20@chpset_lib.skx_ext_b(chips)!SKX_EXT_B_BGA1-IC,TBD!!!F79!VSS(1145)!!!!
S!GND!U5D1!E76!@baseboard_fab2_lib.baseboard_fab2(sch_1):page40_i20@chpset_lib.skx_ext_b(chips)!SKX_EXT_B_BGA1-IC,TBD!!!F79!VSS(1146)!!!!
S!GND!U5D1!E74!@baseboard_fab2_lib.baseboard_fab2(sch_1):page40_i20@chpset_lib.skx_ext_b(chips)!SKX_EXT_B_BGA1-IC,TBD!!!F79!VSS(1147)!!!!
S!GND!U5D1!E72!@baseboard_fab2_lib.baseboard_fab2(sch_1):page40_i20@chpset_lib.skx_ext_b(chips)!SKX_EXT_B_BGA1-IC,TBD!!!F79!VSS(1148)!!!!
S!GND!U5D1!E22!@baseboard_fab2_lib.baseboard_fab2(sch_1):page40_i20@chpset_lib.skx_ext_b(chips)!SKX_EXT_B_BGA1-IC,TBD!!!F79!VSS(1149)!!!!
S!GND!U5D1!E20!@baseboard_fab2_lib.baseboard_fab2(sch_1):page40_i20@chpset_lib.skx_ext_b(chips)!SKX_EXT_B_BGA1-IC,TBD!!!F79!VSS(1150)!!!!
S!GND!U5D1!E18!@baseboard_fab2_lib.baseboard_fab2(sch_1):page40_i20@chpset_lib.skx_ext_b(chips)!SKX_EXT_B_BGA1-IC,TBD!!!F79!VSS(1151)!!!!
S!GND!U5D1!E16!@baseboard_fab2_lib.baseboard_fab2(sch_1):page40_i20@chpset_lib.skx_ext_b(chips)!SKX_EXT_B_BGA1-IC,TBD!!!F79!VSS(1152)!!!!
S!GND!U5D1!E8!@baseboard_fab2_lib.baseboard_fab2(sch_1):page40_i20@chpset_lib.skx_ext_b(chips)!SKX_EXT_B_BGA1-IC,TBD!!!F79!VSS(1153)!!!!
S!GND!U5D1!E6!@baseboard_fab2_lib.baseboard_fab2(sch_1):page40_i20@chpset_lib.skx_ext_b(chips)!SKX_EXT_B_BGA1-IC,TBD!!!F79!VSS(1154)!!!!
S!GND!U5D1!D77!@baseboard_fab2_lib.baseboard_fab2(sch_1):page40_i20@chpset_lib.skx_ext_b(chips)!SKX_EXT_B_BGA1-IC,TBD!!!F79!VSS(1155)!!!!
S!GND!U5D1!D43!@baseboard_fab2_lib.baseboard_fab2(sch_1):page40_i20@chpset_lib.skx_ext_b(chips)!SKX_EXT_B_BGA1-IC,TBD!!!F79!VSS(1156)!!!!
S!GND!U5D1!D41!@baseboard_fab2_lib.baseboard_fab2(sch_1):page40_i20@chpset_lib.skx_ext_b(chips)!SKX_EXT_B_BGA1-IC,TBD!!!F79!VSS(1157)!!!!
S!GND!U5D1!D39!@baseboard_fab2_lib.baseboard_fab2(sch_1):page40_i20@chpset_lib.skx_ext_b(chips)!SKX_EXT_B_BGA1-IC,TBD!!!F79!VSS(1158)!!!!
S!GND!U5D1!D37!@baseboard_fab2_lib.baseboard_fab2(sch_1):page40_i20@chpset_lib.skx_ext_b(chips)!SKX_EXT_B_BGA1-IC,TBD!!!F79!VSS(1159)!!!!
S!GND!U5D1!D35!@baseboard_fab2_lib.baseboard_fab2(sch_1):page40_i20@chpset_lib.skx_ext_b(chips)!SKX_EXT_B_BGA1-IC,TBD!!!F79!VSS(1160)!!!!
S!GND!U5D1!D33!@baseboard_fab2_lib.baseboard_fab2(sch_1):page40_i20@chpset_lib.skx_ext_b(chips)!SKX_EXT_B_BGA1-IC,TBD!!!F79!VSS(1161)!!!!
S!GND!U5D1!D31!@baseboard_fab2_lib.baseboard_fab2(sch_1):page40_i20@chpset_lib.skx_ext_b(chips)!SKX_EXT_B_BGA1-IC,TBD!!!F79!VSS(1162)!!!!
S!GND!U5D1!D29!@baseboard_fab2_lib.baseboard_fab2(sch_1):page40_i20@chpset_lib.skx_ext_b(chips)!SKX_EXT_B_BGA1-IC,TBD!!!F79!VSS(1163)!!!!
S!GND!U5D1!D27!@baseboard_fab2_lib.baseboard_fab2(sch_1):page40_i20@chpset_lib.skx_ext_b(chips)!SKX_EXT_B_BGA1-IC,TBD!!!F79!VSS(1164)!!!!
S!GND!U5D1!D25!@baseboard_fab2_lib.baseboard_fab2(sch_1):page40_i20@chpset_lib.skx_ext_b(chips)!SKX_EXT_B_BGA1-IC,TBD!!!F79!VSS(1165)!!!!
S!GND!U5D1!D13!@baseboard_fab2_lib.baseboard_fab2(sch_1):page40_i20@chpset_lib.skx_ext_b(chips)!SKX_EXT_B_BGA1-IC,TBD!!!F79!VSS(1166)!!!!
S!GND!U5D1!D11!@baseboard_fab2_lib.baseboard_fab2(sch_1):page40_i20@chpset_lib.skx_ext_b(chips)!SKX_EXT_B_BGA1-IC,TBD!!!F79!VSS(1167)!!!!
S!GND!U5D1!CM27!@baseboard_fab2_lib.baseboard_fab2(sch_1):page40_i20@chpset_lib.skx_ext_b(chips)!SKX_EXT_B_BGA1-IC,TBD!!!F79!VSS(1168)!!!!
S!GND!U5D1!C78!@baseboard_fab2_lib.baseboard_fab2(sch_1):page40_i20@chpset_lib.skx_ext_b(chips)!SKX_EXT_B_BGA1-IC,TBD!!!F79!VSS(1169)!!!!
S!GND!U5D1!C76!@baseboard_fab2_lib.baseboard_fab2(sch_1):page40_i20@chpset_lib.skx_ext_b(chips)!SKX_EXT_B_BGA1-IC,TBD!!!F79!VSS(1170)!!!!
S!GND!U5D1!C16!@baseboard_fab2_lib.baseboard_fab2(sch_1):page40_i20@chpset_lib.skx_ext_b(chips)!SKX_EXT_B_BGA1-IC,TBD!!!F79!VSS(1171)!!!!
S!GND!U5D1!C14!@baseboard_fab2_lib.baseboard_fab2(sch_1):page40_i20@chpset_lib.skx_ext_b(chips)!SKX_EXT_B_BGA1-IC,TBD!!!F79!VSS(1172)!!!!
S!GND!U5D1!C12!@baseboard_fab2_lib.baseboard_fab2(sch_1):page40_i20@chpset_lib.skx_ext_b(chips)!SKX_EXT_B_BGA1-IC,TBD!!!F79!VSS(1173)!!!!
S!GND!U5D1!C10!@baseboard_fab2_lib.baseboard_fab2(sch_1):page40_i20@chpset_lib.skx_ext_b(chips)!SKX_EXT_B_BGA1-IC,TBD!!!F79!VSS(1174)!!!!
S!GND!U5D1!C8!@baseboard_fab2_lib.baseboard_fab2(sch_1):page40_i20@chpset_lib.skx_ext_b(chips)!SKX_EXT_B_BGA1-IC,TBD!!!F79!VSS(1175)!!!!
S!GND!U5D1!B75!@baseboard_fab2_lib.baseboard_fab2(sch_1):page40_i20@chpset_lib.skx_ext_b(chips)!SKX_EXT_B_BGA1-IC,TBD!!!F79!VSS(1176)!!!!
S!GND!U5D1!B71!@baseboard_fab2_lib.baseboard_fab2(sch_1):page40_i20@chpset_lib.skx_ext_b(chips)!SKX_EXT_B_BGA1-IC,TBD!!!F79!VSS(1177)!!!!
S!GND!U5D1!B37!@baseboard_fab2_lib.baseboard_fab2(sch_1):page40_i20@chpset_lib.skx_ext_b(chips)!SKX_EXT_B_BGA1-IC,TBD!!!F79!VSS(1178)!!!!
S!GND!U5D1!B31!@baseboard_fab2_lib.baseboard_fab2(sch_1):page40_i20@chpset_lib.skx_ext_b(chips)!SKX_EXT_B_BGA1-IC,TBD!!!F79!VSS(1179)!!!!
S!GND!U5D1!B25!@baseboard_fab2_lib.baseboard_fab2(sch_1):page40_i20@chpset_lib.skx_ext_b(chips)!SKX_EXT_B_BGA1-IC,TBD!!!F79!VSS(1180)!!!!
S!GND!U5D1!A38!@baseboard_fab2_lib.baseboard_fab2(sch_1):page40_i20@chpset_lib.skx_ext_b(chips)!SKX_EXT_B_BGA1-IC,TBD!!!F79!VSS(1181)!!!!
S!GND!U5D1!A36!@baseboard_fab2_lib.baseboard_fab2(sch_1):page40_i20@chpset_lib.skx_ext_b(chips)!SKX_EXT_B_BGA1-IC,TBD!!!F79!VSS(1182)!!!!
S!GND!U5D1!A32!@baseboard_fab2_lib.baseboard_fab2(sch_1):page40_i20@chpset_lib.skx_ext_b(chips)!SKX_EXT_B_BGA1-IC,TBD!!!F79!VSS(1183)!!!!
S!GND!U5D1!A30!@baseboard_fab2_lib.baseboard_fab2(sch_1):page40_i20@chpset_lib.skx_ext_b(chips)!SKX_EXT_B_BGA1-IC,TBD!!!F79!VSS(1184)!!!!
S!GND!U5D1!A26!@baseboard_fab2_lib.baseboard_fab2(sch_1):page40_i20@chpset_lib.skx_ext_b(chips)!SKX_EXT_B_BGA1-IC,TBD!!!F79!VSS(1185)!!!!
S!GND!U5D1!AC58!@baseboard_fab2_lib.baseboard_fab2(sch_1):page40_i20@chpset_lib.skx_ext_b(chips)!SKX_EXT_B_BGA1-IC,TBD!!!F79!VSS(1186)!!!!
S!GND!U5D1!AC60!@baseboard_fab2_lib.baseboard_fab2(sch_1):page40_i20@chpset_lib.skx_ext_b(chips)!SKX_EXT_B_BGA1-IC,TBD!!!F79!VSS(1187)!!!!
S!GND!U5D1!AC62!@baseboard_fab2_lib.baseboard_fab2(sch_1):page40_i20@chpset_lib.skx_ext_b(chips)!SKX_EXT_B_BGA1-IC,TBD!!!F79!VSS(1188)!!!!
S!GND!U5D1!AJ4!@baseboard_fab2_lib.baseboard_fab2(sch_1):page40_i20@chpset_lib.skx_ext_b(chips)!SKX_EXT_B_BGA1-IC,TBD!!!F79!VSS(1189)!!!!
S!GND!U5D1!AR6!@baseboard_fab2_lib.baseboard_fab2(sch_1):page40_i20@chpset_lib.skx_ext_b(chips)!SKX_EXT_B_BGA1-IC,TBD!!!F79!VSS(1190)!!!!
S!GND!U5D1!CG6!@baseboard_fab2_lib.baseboard_fab2(sch_1):page40_i20@chpset_lib.skx_ext_b(chips)!SKX_EXT_B_BGA1-IC,TBD!!!F79!VSS(1191)!!!!
S!GND!U5D1!CW6!@baseboard_fab2_lib.baseboard_fab2(sch_1):page40_i20@chpset_lib.skx_ext_b(chips)!SKX_EXT_B_BGA1-IC,TBD!!!F79!VSS(1192)!!!!
S!GND!U5D1!DE48!@baseboard_fab2_lib.baseboard_fab2(sch_1):page40_i20@chpset_lib.skx_ext_b(chips)!SKX_EXT_B_BGA1-IC,TBD!!!F79!VSS(1193)!!!!
S!GND!U5D1!DE50!@baseboard_fab2_lib.baseboard_fab2(sch_1):page40_i20@chpset_lib.skx_ext_b(chips)!SKX_EXT_B_BGA1-IC,TBD!!!F79!VSS(1194)!!!!
S!GND!U5D1!DE52!@baseboard_fab2_lib.baseboard_fab2(sch_1):page40_i20@chpset_lib.skx_ext_b(chips)!SKX_EXT_B_BGA1-IC,TBD!!!F79!VSS(1195)!!!!
S!GND!U5D1!DE54!@baseboard_fab2_lib.baseboard_fab2(sch_1):page40_i20@chpset_lib.skx_ext_b(chips)!SKX_EXT_B_BGA1-IC,TBD!!!F79!VSS(1196)!!!!
S!GND!U5D1!DE56!@baseboard_fab2_lib.baseboard_fab2(sch_1):page40_i20@chpset_lib.skx_ext_b(chips)!SKX_EXT_B_BGA1-IC,TBD!!!F79!VSS(1197)!!!!
S!GND!U5D1!DE58!@baseboard_fab2_lib.baseboard_fab2(sch_1):page40_i20@chpset_lib.skx_ext_b(chips)!SKX_EXT_B_BGA1-IC,TBD!!!F79!VSS(1198)!!!!
S!GND!U5D1!DE60!@baseboard_fab2_lib.baseboard_fab2(sch_1):page40_i20@chpset_lib.skx_ext_b(chips)!SKX_EXT_B_BGA1-IC,TBD!!!F79!VSS(1199)!!!!
S!GND!U5D1!DE62!@baseboard_fab2_lib.baseboard_fab2(sch_1):page40_i20@chpset_lib.skx_ext_b(chips)!SKX_EXT_B_BGA1-IC,TBD!!!F79!VSS(1200)!!!!
S!GND!U5D1!DL8!@baseboard_fab2_lib.baseboard_fab2(sch_1):page40_i20@chpset_lib.skx_ext_b(chips)!SKX_EXT_B_BGA1-IC,TBD!!!F79!VSS(1201)!!!!
S!GND!U5D1!DN18!@baseboard_fab2_lib.baseboard_fab2(sch_1):page40_i20@chpset_lib.skx_ext_b(chips)!SKX_EXT_B_BGA1-IC,TBD!!!F79!VSS(1202)!!!!
S!GND!U5D1!DP45!@baseboard_fab2_lib.baseboard_fab2(sch_1):page40_i20@chpset_lib.skx_ext_b(chips)!SKX_EXT_B_BGA1-IC,TBD!!!F79!VSS(1203)!!!!
S!GND!U5D1!DP47!@baseboard_fab2_lib.baseboard_fab2(sch_1):page40_i20@chpset_lib.skx_ext_b(chips)!SKX_EXT_B_BGA1-IC,TBD!!!F79!VSS(1204)!!!!
S!GND!U5D1!DP49!@baseboard_fab2_lib.baseboard_fab2(sch_1):page40_i20@chpset_lib.skx_ext_b(chips)!SKX_EXT_B_BGA1-IC,TBD!!!F79!VSS(1205)!!!!
S!GND!U5D1!DP51!@baseboard_fab2_lib.baseboard_fab2(sch_1):page40_i20@chpset_lib.skx_ext_b(chips)!SKX_EXT_B_BGA1-IC,TBD!!!F79!VSS(1206)!!!!
S!GND!U5D1!DP53!@baseboard_fab2_lib.baseboard_fab2(sch_1):page40_i20@chpset_lib.skx_ext_b(chips)!SKX_EXT_B_BGA1-IC,TBD!!!F79!VSS(1207)!!!!
S!GND!U5D1!DP55!@baseboard_fab2_lib.baseboard_fab2(sch_1):page40_i20@chpset_lib.skx_ext_b(chips)!SKX_EXT_B_BGA1-IC,TBD!!!F79!VSS(1208)!!!!
S!GND!U5D1!DP57!@baseboard_fab2_lib.baseboard_fab2(sch_1):page40_i20@chpset_lib.skx_ext_b(chips)!SKX_EXT_B_BGA1-IC,TBD!!!F79!VSS(1209)!!!!
S!GND!U5D1!DP59!@baseboard_fab2_lib.baseboard_fab2(sch_1):page40_i20@chpset_lib.skx_ext_b(chips)!SKX_EXT_B_BGA1-IC,TBD!!!F79!VSS(1210)!!!!
S!GND!U5D1!DP61!@baseboard_fab2_lib.baseboard_fab2(sch_1):page40_i20@chpset_lib.skx_ext_b(chips)!SKX_EXT_B_BGA1-IC,TBD!!!F79!VSS(1211)!!!!
S!GND!U5D1!DP63!@baseboard_fab2_lib.baseboard_fab2(sch_1):page40_i20@chpset_lib.skx_ext_b(chips)!SKX_EXT_B_BGA1-IC,TBD!!!F79!VSS(1212)!!!!
S!GND!U5D1!DP9!@baseboard_fab2_lib.baseboard_fab2(sch_1):page40_i20@chpset_lib.skx_ext_b(chips)!SKX_EXT_B_BGA1-IC,TBD!!!F79!VSS(1213)!!!!
S!GND!U5D1!DV19!@baseboard_fab2_lib.baseboard_fab2(sch_1):page40_i20@chpset_lib.skx_ext_b(chips)!SKX_EXT_B_BGA1-IC,TBD!!!F79!VSS(1214)!!!!
S!GND!U5D1!DY45!@baseboard_fab2_lib.baseboard_fab2(sch_1):page40_i20@chpset_lib.skx_ext_b(chips)!SKX_EXT_B_BGA1-IC,TBD!!!F79!VSS(1215)!!!!
S!GND!U5D1!DY47!@baseboard_fab2_lib.baseboard_fab2(sch_1):page40_i20@chpset_lib.skx_ext_b(chips)!SKX_EXT_B_BGA1-IC,TBD!!!F79!VSS(1216)!!!!
S!GND!U5D1!DY49!@baseboard_fab2_lib.baseboard_fab2(sch_1):page40_i20@chpset_lib.skx_ext_b(chips)!SKX_EXT_B_BGA1-IC,TBD!!!F79!VSS(1217)!!!!
S!GND!U5D1!DY51!@baseboard_fab2_lib.baseboard_fab2(sch_1):page40_i20@chpset_lib.skx_ext_b(chips)!SKX_EXT_B_BGA1-IC,TBD!!!F79!VSS(1218)!!!!
S!GND!U5D1!DY53!@baseboard_fab2_lib.baseboard_fab2(sch_1):page40_i20@chpset_lib.skx_ext_b(chips)!SKX_EXT_B_BGA1-IC,TBD!!!F79!VSS(1219)!!!!
S!GND!U5D1!DY55!@baseboard_fab2_lib.baseboard_fab2(sch_1):page40_i20@chpset_lib.skx_ext_b(chips)!SKX_EXT_B_BGA1-IC,TBD!!!F79!VSS(1220)!!!!
S!GND!U5D1!DY57!@baseboard_fab2_lib.baseboard_fab2(sch_1):page40_i20@chpset_lib.skx_ext_b(chips)!SKX_EXT_B_BGA1-IC,TBD!!!F79!VSS(1221)!!!!
S!GND!U5D1!DY59!@baseboard_fab2_lib.baseboard_fab2(sch_1):page40_i20@chpset_lib.skx_ext_b(chips)!SKX_EXT_B_BGA1-IC,TBD!!!F79!VSS(1222)!!!!
S!GND!U5D1!DY61!@baseboard_fab2_lib.baseboard_fab2(sch_1):page40_i20@chpset_lib.skx_ext_b(chips)!SKX_EXT_B_BGA1-IC,TBD!!!F79!VSS(1223)!!!!
S!GND!U5D1!DY63!@baseboard_fab2_lib.baseboard_fab2(sch_1):page40_i20@chpset_lib.skx_ext_b(chips)!SKX_EXT_B_BGA1-IC,TBD!!!F79!VSS(1224)!!!!
S!GND!U5D1!EA14!@baseboard_fab2_lib.baseboard_fab2(sch_1):page40_i20@chpset_lib.skx_ext_b(chips)!SKX_EXT_B_BGA1-IC,TBD!!!F79!VSS(1225)!!!!
S!GND!U5D1!L8!@baseboard_fab2_lib.baseboard_fab2(sch_1):page40_i20@chpset_lib.skx_ext_b(chips)!SKX_EXT_B_BGA1-IC,TBD!!!F79!VSS(1226)!!!!
S!GND!U5D1!V11!@baseboard_fab2_lib.baseboard_fab2(sch_1):page40_i20@chpset_lib.skx_ext_b(chips)!SKX_EXT_B_BGA1-IC,TBD!!!F79!VSS(1227)!!!!
S!GND!U5D1!T37!@baseboard_fab2_lib.baseboard_fab2(sch_1):page40_i21@chpset_lib.skx_ext_b(chips)!SKX_EXT_B_BGA1-IC,TBD!!!F78!VSS(1000)!!!!
S!GND!U5D1!T35!@baseboard_fab2_lib.baseboard_fab2(sch_1):page40_i21@chpset_lib.skx_ext_b(chips)!SKX_EXT_B_BGA1-IC,TBD!!!F78!VSS(1001)!!!!
S!GND!U5D1!T31!@baseboard_fab2_lib.baseboard_fab2(sch_1):page40_i21@chpset_lib.skx_ext_b(chips)!SKX_EXT_B_BGA1-IC,TBD!!!F78!VSS(1002)!!!!
S!GND!U5D1!T29!@baseboard_fab2_lib.baseboard_fab2(sch_1):page40_i21@chpset_lib.skx_ext_b(chips)!SKX_EXT_B_BGA1-IC,TBD!!!F78!VSS(1003)!!!!
S!GND!U5D1!T25!@baseboard_fab2_lib.baseboard_fab2(sch_1):page40_i21@chpset_lib.skx_ext_b(chips)!SKX_EXT_B_BGA1-IC,TBD!!!F78!VSS(1004)!!!!
S!GND!U5D1!T17!@baseboard_fab2_lib.baseboard_fab2(sch_1):page40_i21@chpset_lib.skx_ext_b(chips)!SKX_EXT_B_BGA1-IC,TBD!!!F78!VSS(1005)!!!!
S!GND!U5D1!T13!@baseboard_fab2_lib.baseboard_fab2(sch_1):page40_i21@chpset_lib.skx_ext_b(chips)!SKX_EXT_B_BGA1-IC,TBD!!!F78!VSS(1006)!!!!
S!GND!U5D1!R86!@baseboard_fab2_lib.baseboard_fab2(sch_1):page40_i21@chpset_lib.skx_ext_b(chips)!SKX_EXT_B_BGA1-IC,TBD!!!F78!VSS(1007)!!!!
S!GND!U5D1!R78!@baseboard_fab2_lib.baseboard_fab2(sch_1):page40_i21@chpset_lib.skx_ext_b(chips)!SKX_EXT_B_BGA1-IC,TBD!!!F78!VSS(1008)!!!!
S!GND!U5D1!R72!@baseboard_fab2_lib.baseboard_fab2(sch_1):page40_i21@chpset_lib.skx_ext_b(chips)!SKX_EXT_B_BGA1-IC,TBD!!!F78!VSS(1009)!!!!
S!GND!U5D1!R68!@baseboard_fab2_lib.baseboard_fab2(sch_1):page40_i21@chpset_lib.skx_ext_b(chips)!SKX_EXT_B_BGA1-IC,TBD!!!F78!VSS(1010)!!!!
S!GND!U5D1!R40!@baseboard_fab2_lib.baseboard_fab2(sch_1):page40_i21@chpset_lib.skx_ext_b(chips)!SKX_EXT_B_BGA1-IC,TBD!!!F78!VSS(1011)!!!!
S!GND!U5D1!R38!@baseboard_fab2_lib.baseboard_fab2(sch_1):page40_i21@chpset_lib.skx_ext_b(chips)!SKX_EXT_B_BGA1-IC,TBD!!!F78!VSS(1012)!!!!
S!GND!U5D1!R34!@baseboard_fab2_lib.baseboard_fab2(sch_1):page40_i21@chpset_lib.skx_ext_b(chips)!SKX_EXT_B_BGA1-IC,TBD!!!F78!VSS(1013)!!!!
S!GND!U5D1!R32!@baseboard_fab2_lib.baseboard_fab2(sch_1):page40_i21@chpset_lib.skx_ext_b(chips)!SKX_EXT_B_BGA1-IC,TBD!!!F78!VSS(1014)!!!!
S!GND!U5D1!R28!@baseboard_fab2_lib.baseboard_fab2(sch_1):page40_i21@chpset_lib.skx_ext_b(chips)!SKX_EXT_B_BGA1-IC,TBD!!!F78!VSS(1015)!!!!
S!GND!U5D1!R26!@baseboard_fab2_lib.baseboard_fab2(sch_1):page40_i21@chpset_lib.skx_ext_b(chips)!SKX_EXT_B_BGA1-IC,TBD!!!F78!VSS(1016)!!!!
S!GND!U5D1!R22!@baseboard_fab2_lib.baseboard_fab2(sch_1):page40_i21@chpset_lib.skx_ext_b(chips)!SKX_EXT_B_BGA1-IC,TBD!!!F78!VSS(1017)!!!!
S!GND!U5D1!R4!@baseboard_fab2_lib.baseboard_fab2(sch_1):page40_i21@chpset_lib.skx_ext_b(chips)!SKX_EXT_B_BGA1-IC,TBD!!!F78!VSS(1018)!!!!
S!GND!U5D1!R2!@baseboard_fab2_lib.baseboard_fab2(sch_1):page40_i21@chpset_lib.skx_ext_b(chips)!SKX_EXT_B_BGA1-IC,TBD!!!F78!VSS(1019)!!!!
S!GND!U5D1!R18!@baseboard_fab2_lib.baseboard_fab2(sch_1):page40_i21@chpset_lib.skx_ext_b(chips)!SKX_EXT_B_BGA1-IC,TBD!!!F78!VSS(1020)!!!!
S!GND!U5D1!R14!@baseboard_fab2_lib.baseboard_fab2(sch_1):page40_i21@chpset_lib.skx_ext_b(chips)!SKX_EXT_B_BGA1-IC,TBD!!!F78!VSS(1021)!!!!
S!GND!U5D1!P83!@baseboard_fab2_lib.baseboard_fab2(sch_1):page40_i21@chpset_lib.skx_ext_b(chips)!SKX_EXT_B_BGA1-IC,TBD!!!F78!VSS(1022)!!!!
S!GND!U5D1!P81!@baseboard_fab2_lib.baseboard_fab2(sch_1):page40_i21@chpset_lib.skx_ext_b(chips)!SKX_EXT_B_BGA1-IC,TBD!!!F78!VSS(1023)!!!!
S!GND!U5D1!P71!@baseboard_fab2_lib.baseboard_fab2(sch_1):page40_i21@chpset_lib.skx_ext_b(chips)!SKX_EXT_B_BGA1-IC,TBD!!!F78!VSS(1024)!!!!
S!GND!U5D1!P69!@baseboard_fab2_lib.baseboard_fab2(sch_1):page40_i21@chpset_lib.skx_ext_b(chips)!SKX_EXT_B_BGA1-IC,TBD!!!F78!VSS(1025)!!!!
S!GND!U5D1!P67!@baseboard_fab2_lib.baseboard_fab2(sch_1):page40_i21@chpset_lib.skx_ext_b(chips)!SKX_EXT_B_BGA1-IC,TBD!!!F78!VSS(1026)!!!!
S!GND!U5D1!P39!@baseboard_fab2_lib.baseboard_fab2(sch_1):page40_i21@chpset_lib.skx_ext_b(chips)!SKX_EXT_B_BGA1-IC,TBD!!!F78!VSS(1027)!!!!
S!GND!U5D1!P33!@baseboard_fab2_lib.baseboard_fab2(sch_1):page40_i21@chpset_lib.skx_ext_b(chips)!SKX_EXT_B_BGA1-IC,TBD!!!F78!VSS(1028)!!!!
S!GND!U5D1!P27!@baseboard_fab2_lib.baseboard_fab2(sch_1):page40_i21@chpset_lib.skx_ext_b(chips)!SKX_EXT_B_BGA1-IC,TBD!!!F78!VSS(1029)!!!!
S!GND!U5D1!P15!@baseboard_fab2_lib.baseboard_fab2(sch_1):page40_i21@chpset_lib.skx_ext_b(chips)!SKX_EXT_B_BGA1-IC,TBD!!!F78!VSS(1030)!!!!
S!GND!U5D1!P11!@baseboard_fab2_lib.baseboard_fab2(sch_1):page40_i21@chpset_lib.skx_ext_b(chips)!SKX_EXT_B_BGA1-IC,TBD!!!F78!VSS(1031)!!!!
S!GND!U5D1!N8!@baseboard_fab2_lib.baseboard_fab2(sch_1):page40_i21@chpset_lib.skx_ext_b(chips)!SKX_EXT_B_BGA1-IC,TBD!!!F78!VSS(1032)!!!!
S!GND!U5D1!N4!@baseboard_fab2_lib.baseboard_fab2(sch_1):page40_i21@chpset_lib.skx_ext_b(chips)!SKX_EXT_B_BGA1-IC,TBD!!!F78!VSS(1033)!!!!
S!GND!U5D1!N78!@baseboard_fab2_lib.baseboard_fab2(sch_1):page40_i21@chpset_lib.skx_ext_b(chips)!SKX_EXT_B_BGA1-IC,TBD!!!F78!VSS(1034)!!!!
S!GND!U5D1!N76!@baseboard_fab2_lib.baseboard_fab2(sch_1):page40_i21@chpset_lib.skx_ext_b(chips)!SKX_EXT_B_BGA1-IC,TBD!!!F78!VSS(1035)!!!!
S!GND!U5D1!N74!@baseboard_fab2_lib.baseboard_fab2(sch_1):page40_i21@chpset_lib.skx_ext_b(chips)!SKX_EXT_B_BGA1-IC,TBD!!!F78!VSS(1036)!!!!
S!GND!U5D1!N72!@baseboard_fab2_lib.baseboard_fab2(sch_1):page40_i21@chpset_lib.skx_ext_b(chips)!SKX_EXT_B_BGA1-IC,TBD!!!F78!VSS(1037)!!!!
S!GND!U5D1!N70!@baseboard_fab2_lib.baseboard_fab2(sch_1):page40_i21@chpset_lib.skx_ext_b(chips)!SKX_EXT_B_BGA1-IC,TBD!!!F78!VSS(1038)!!!!
S!GND!U5D1!N66!@baseboard_fab2_lib.baseboard_fab2(sch_1):page40_i21@chpset_lib.skx_ext_b(chips)!SKX_EXT_B_BGA1-IC,TBD!!!F78!VSS(1039)!!!!
S!GND!U5D1!N6!@baseboard_fab2_lib.baseboard_fab2(sch_1):page40_i21@chpset_lib.skx_ext_b(chips)!SKX_EXT_B_BGA1-IC,TBD!!!F78!VSS(1040)!!!!
S!GND!U5D1!N22!@baseboard_fab2_lib.baseboard_fab2(sch_1):page40_i21@chpset_lib.skx_ext_b(chips)!SKX_EXT_B_BGA1-IC,TBD!!!F78!VSS(1041)!!!!
S!GND!U5D1!N20!@baseboard_fab2_lib.baseboard_fab2(sch_1):page40_i21@chpset_lib.skx_ext_b(chips)!SKX_EXT_B_BGA1-IC,TBD!!!F78!VSS(1042)!!!!
S!GND!U5D1!DM19!@baseboard_fab2_lib.baseboard_fab2(sch_1):page40_i21@chpset_lib.skx_ext_b(chips)!SKX_EXT_B_BGA1-IC,TBD!!!F78!VSS(1043)!!!!
S!GND!U5D1!M85!@baseboard_fab2_lib.baseboard_fab2(sch_1):page40_i21@chpset_lib.skx_ext_b(chips)!SKX_EXT_B_BGA1-IC,TBD!!!F78!VSS(1044)!!!!
S!GND!U5D1!M83!@baseboard_fab2_lib.baseboard_fab2(sch_1):page40_i21@chpset_lib.skx_ext_b(chips)!SKX_EXT_B_BGA1-IC,TBD!!!F78!VSS(1045)!!!!
S!GND!U5D1!M79!@baseboard_fab2_lib.baseboard_fab2(sch_1):page40_i21@chpset_lib.skx_ext_b(chips)!SKX_EXT_B_BGA1-IC,TBD!!!F78!VSS(1046)!!!!
S!GND!U5D1!M71!@baseboard_fab2_lib.baseboard_fab2(sch_1):page40_i21@chpset_lib.skx_ext_b(chips)!SKX_EXT_B_BGA1-IC,TBD!!!F78!VSS(1047)!!!!
S!GND!U5D1!M65!@baseboard_fab2_lib.baseboard_fab2(sch_1):page40_i21@chpset_lib.skx_ext_b(chips)!SKX_EXT_B_BGA1-IC,TBD!!!F78!VSS(1048)!!!!
S!GND!U5D1!M43!@baseboard_fab2_lib.baseboard_fab2(sch_1):page40_i21@chpset_lib.skx_ext_b(chips)!SKX_EXT_B_BGA1-IC,TBD!!!F78!VSS(1049)!!!!
S!GND!U5D1!M41!@baseboard_fab2_lib.baseboard_fab2(sch_1):page40_i21@chpset_lib.skx_ext_b(chips)!SKX_EXT_B_BGA1-IC,TBD!!!F78!VSS(1050)!!!!
S!GND!U5D1!M39!@baseboard_fab2_lib.baseboard_fab2(sch_1):page40_i21@chpset_lib.skx_ext_b(chips)!SKX_EXT_B_BGA1-IC,TBD!!!F78!VSS(1051)!!!!
S!GND!U5D1!M37!@baseboard_fab2_lib.baseboard_fab2(sch_1):page40_i21@chpset_lib.skx_ext_b(chips)!SKX_EXT_B_BGA1-IC,TBD!!!F78!VSS(1052)!!!!
S!GND!U5D1!M35!@baseboard_fab2_lib.baseboard_fab2(sch_1):page40_i21@chpset_lib.skx_ext_b(chips)!SKX_EXT_B_BGA1-IC,TBD!!!F78!VSS(1053)!!!!
S!GND!U5D1!M33!@baseboard_fab2_lib.baseboard_fab2(sch_1):page40_i21@chpset_lib.skx_ext_b(chips)!SKX_EXT_B_BGA1-IC,TBD!!!F78!VSS(1054)!!!!
S!GND!U5D1!M31!@baseboard_fab2_lib.baseboard_fab2(sch_1):page40_i21@chpset_lib.skx_ext_b(chips)!SKX_EXT_B_BGA1-IC,TBD!!!F78!VSS(1055)!!!!
S!GND!U5D1!M29!@baseboard_fab2_lib.baseboard_fab2(sch_1):page40_i21@chpset_lib.skx_ext_b(chips)!SKX_EXT_B_BGA1-IC,TBD!!!F78!VSS(1056)!!!!
S!GND!U5D1!M27!@baseboard_fab2_lib.baseboard_fab2(sch_1):page40_i21@chpset_lib.skx_ext_b(chips)!SKX_EXT_B_BGA1-IC,TBD!!!F78!VSS(1057)!!!!
S!GND!U5D1!M25!@baseboard_fab2_lib.baseboard_fab2(sch_1):page40_i21@chpset_lib.skx_ext_b(chips)!SKX_EXT_B_BGA1-IC,TBD!!!F78!VSS(1058)!!!!
S!GND!U5D1!M23!@baseboard_fab2_lib.baseboard_fab2(sch_1):page40_i21@chpset_lib.skx_ext_b(chips)!SKX_EXT_B_BGA1-IC,TBD!!!F78!VSS(1059)!!!!
S!GND!U5D1!M19!@baseboard_fab2_lib.baseboard_fab2(sch_1):page40_i21@chpset_lib.skx_ext_b(chips)!SKX_EXT_B_BGA1-IC,TBD!!!F78!VSS(1060)!!!!
S!GND!U5D1!M17!@baseboard_fab2_lib.baseboard_fab2(sch_1):page40_i21@chpset_lib.skx_ext_b(chips)!SKX_EXT_B_BGA1-IC,TBD!!!F78!VSS(1061)!!!!
S!GND!U5D1!M15!@baseboard_fab2_lib.baseboard_fab2(sch_1):page40_i21@chpset_lib.skx_ext_b(chips)!SKX_EXT_B_BGA1-IC,TBD!!!F78!VSS(1062)!!!!
S!GND!U5D1!CT7!@baseboard_fab2_lib.baseboard_fab2(sch_1):page40_i21@chpset_lib.skx_ext_b(chips)!SKX_EXT_B_BGA1-IC,TBD!!!F78!VSS(1063)!!!!
S!GND!U5D1!BT9!@baseboard_fab2_lib.baseboard_fab2(sch_1):page40_i21@chpset_lib.skx_ext_b(chips)!SKX_EXT_B_BGA1-IC,TBD!!!F78!VSS(1064)!!!!
S!GND!U5D1!L82!@baseboard_fab2_lib.baseboard_fab2(sch_1):page40_i21@chpset_lib.skx_ext_b(chips)!SKX_EXT_B_BGA1-IC,TBD!!!F78!VSS(1065)!!!!
S!GND!U5D1!L80!@baseboard_fab2_lib.baseboard_fab2(sch_1):page40_i21@chpset_lib.skx_ext_b(chips)!SKX_EXT_B_BGA1-IC,TBD!!!F78!VSS(1066)!!!!
S!GND!U5D1!L78!@baseboard_fab2_lib.baseboard_fab2(sch_1):page40_i21@chpset_lib.skx_ext_b(chips)!SKX_EXT_B_BGA1-IC,TBD!!!F78!VSS(1067)!!!!
S!GND!U5D1!AB69!@baseboard_fab2_lib.baseboard_fab2(sch_1):page40_i22@chpset_lib.skx_ext_b(chips)!SKX_EXT_B_BGA1-IC,TBD!!!F77!VSS(908)!!!!
S!GND!U5D1!AB65!@baseboard_fab2_lib.baseboard_fab2(sch_1):page40_i22@chpset_lib.skx_ext_b(chips)!SKX_EXT_B_BGA1-IC,TBD!!!F77!VSS(909)!!!!
S!GND!U5D1!AB41!@baseboard_fab2_lib.baseboard_fab2(sch_1):page40_i22@chpset_lib.skx_ext_b(chips)!SKX_EXT_B_BGA1-IC,TBD!!!F77!VSS(910)!!!!
S!GND!U5D1!AB37!@baseboard_fab2_lib.baseboard_fab2(sch_1):page40_i22@chpset_lib.skx_ext_b(chips)!SKX_EXT_B_BGA1-IC,TBD!!!F77!VSS(911)!!!!
S!GND!U5D1!AB35!@baseboard_fab2_lib.baseboard_fab2(sch_1):page40_i22@chpset_lib.skx_ext_b(chips)!SKX_EXT_B_BGA1-IC,TBD!!!F77!VSS(912)!!!!
S!GND!U5D1!AB31!@baseboard_fab2_lib.baseboard_fab2(sch_1):page40_i22@chpset_lib.skx_ext_b(chips)!SKX_EXT_B_BGA1-IC,TBD!!!F77!VSS(913)!!!!
S!GND!U5D1!AB29!@baseboard_fab2_lib.baseboard_fab2(sch_1):page40_i22@chpset_lib.skx_ext_b(chips)!SKX_EXT_B_BGA1-IC,TBD!!!F77!VSS(914)!!!!
S!GND!U5D1!AB25!@baseboard_fab2_lib.baseboard_fab2(sch_1):page40_i22@chpset_lib.skx_ext_b(chips)!SKX_EXT_B_BGA1-IC,TBD!!!F77!VSS(915)!!!!
S!GND!U5D1!AB23!@baseboard_fab2_lib.baseboard_fab2(sch_1):page40_i22@chpset_lib.skx_ext_b(chips)!SKX_EXT_B_BGA1-IC,TBD!!!F77!VSS(916)!!!!
S!GND!U5D1!AB21!@baseboard_fab2_lib.baseboard_fab2(sch_1):page40_i22@chpset_lib.skx_ext_b(chips)!SKX_EXT_B_BGA1-IC,TBD!!!F77!VSS(917)!!!!
S!GND!U5D1!AB11!@baseboard_fab2_lib.baseboard_fab2(sch_1):page40_i22@chpset_lib.skx_ext_b(chips)!SKX_EXT_B_BGA1-IC,TBD!!!F77!VSS(918)!!!!
S!GND!U5D1!AB5!@baseboard_fab2_lib.baseboard_fab2(sch_1):page40_i22@chpset_lib.skx_ext_b(chips)!SKX_EXT_B_BGA1-IC,TBD!!!F77!VSS(919)!!!!
S!GND!U5D1!AB1!@baseboard_fab2_lib.baseboard_fab2(sch_1):page40_i22@chpset_lib.skx_ext_b(chips)!SKX_EXT_B_BGA1-IC,TBD!!!F77!VSS(920)!!!!
S!GND!U5D1!AA82!@baseboard_fab2_lib.baseboard_fab2(sch_1):page40_i22@chpset_lib.skx_ext_b(chips)!SKX_EXT_B_BGA1-IC,TBD!!!F77!VSS(921)!!!!
S!GND!U5D1!AA80!@baseboard_fab2_lib.baseboard_fab2(sch_1):page40_i22@chpset_lib.skx_ext_b(chips)!SKX_EXT_B_BGA1-IC,TBD!!!F77!VSS(922)!!!!
S!GND!U5D1!AA78!@baseboard_fab2_lib.baseboard_fab2(sch_1):page40_i22@chpset_lib.skx_ext_b(chips)!SKX_EXT_B_BGA1-IC,TBD!!!F77!VSS(923)!!!!
S!GND!U5D1!AA76!@baseboard_fab2_lib.baseboard_fab2(sch_1):page40_i22@chpset_lib.skx_ext_b(chips)!SKX_EXT_B_BGA1-IC,TBD!!!F77!VSS(924)!!!!
S!GND!U5D1!AA68!@baseboard_fab2_lib.baseboard_fab2(sch_1):page40_i22@chpset_lib.skx_ext_b(chips)!SKX_EXT_B_BGA1-IC,TBD!!!F77!VSS(925)!!!!
S!GND!U5D1!AA66!@baseboard_fab2_lib.baseboard_fab2(sch_1):page40_i22@chpset_lib.skx_ext_b(chips)!SKX_EXT_B_BGA1-IC,TBD!!!F77!VSS(926)!!!!
S!GND!U5D1!AA64!@baseboard_fab2_lib.baseboard_fab2(sch_1):page40_i22@chpset_lib.skx_ext_b(chips)!SKX_EXT_B_BGA1-IC,TBD!!!F77!VSS(927)!!!!
S!GND!U5D1!AA42!@baseboard_fab2_lib.baseboard_fab2(sch_1):page40_i22@chpset_lib.skx_ext_b(chips)!SKX_EXT_B_BGA1-IC,TBD!!!F77!VSS(928)!!!!
S!GND!U5D1!AA36!@baseboard_fab2_lib.baseboard_fab2(sch_1):page40_i22@chpset_lib.skx_ext_b(chips)!SKX_EXT_B_BGA1-IC,TBD!!!F77!VSS(929)!!!!
S!GND!U5D1!AA30!@baseboard_fab2_lib.baseboard_fab2(sch_1):page40_i22@chpset_lib.skx_ext_b(chips)!SKX_EXT_B_BGA1-IC,TBD!!!F77!VSS(930)!!!!
S!GND!U5D1!AA24!@baseboard_fab2_lib.baseboard_fab2(sch_1):page40_i22@chpset_lib.skx_ext_b(chips)!SKX_EXT_B_BGA1-IC,TBD!!!F77!VSS(931)!!!!
S!GND!U5D1!AA22!@baseboard_fab2_lib.baseboard_fab2(sch_1):page40_i22@chpset_lib.skx_ext_b(chips)!SKX_EXT_B_BGA1-IC,TBD!!!F77!VSS(932)!!!!
S!GND!U5D1!AA18!@baseboard_fab2_lib.baseboard_fab2(sch_1):page40_i22@chpset_lib.skx_ext_b(chips)!SKX_EXT_B_BGA1-IC,TBD!!!F77!VSS(933)!!!!
S!GND!U5D1!AA16!@baseboard_fab2_lib.baseboard_fab2(sch_1):page40_i21@chpset_lib.skx_ext_b(chips)!SKX_EXT_B_BGA1-IC,TBD!!!F78!VSS(934)!!!!
S!GND!U5D1!AA4!@baseboard_fab2_lib.baseboard_fab2(sch_1):page40_i21@chpset_lib.skx_ext_b(chips)!SKX_EXT_B_BGA1-IC,TBD!!!F78!VSS(935)!!!!
S!GND!U5D1!Y85!@baseboard_fab2_lib.baseboard_fab2(sch_1):page40_i21@chpset_lib.skx_ext_b(chips)!SKX_EXT_B_BGA1-IC,TBD!!!F78!VSS(936)!!!!
S!GND!U5D1!Y83!@baseboard_fab2_lib.baseboard_fab2(sch_1):page40_i21@chpset_lib.skx_ext_b(chips)!SKX_EXT_B_BGA1-IC,TBD!!!F78!VSS(937)!!!!
S!GND!U5D1!Y81!@baseboard_fab2_lib.baseboard_fab2(sch_1):page40_i21@chpset_lib.skx_ext_b(chips)!SKX_EXT_B_BGA1-IC,TBD!!!F78!VSS(938)!!!!
S!GND!U5D1!Y79!@baseboard_fab2_lib.baseboard_fab2(sch_1):page40_i21@chpset_lib.skx_ext_b(chips)!SKX_EXT_B_BGA1-IC,TBD!!!F78!VSS(939)!!!!
S!GND!U5D1!Y73!@baseboard_fab2_lib.baseboard_fab2(sch_1):page40_i21@chpset_lib.skx_ext_b(chips)!SKX_EXT_B_BGA1-IC,TBD!!!F78!VSS(940)!!!!
S!GND!U5D1!Y71!@baseboard_fab2_lib.baseboard_fab2(sch_1):page40_i21@chpset_lib.skx_ext_b(chips)!SKX_EXT_B_BGA1-IC,TBD!!!F78!VSS(941)!!!!
S!GND!U5D1!Y9!@baseboard_fab2_lib.baseboard_fab2(sch_1):page40_i21@chpset_lib.skx_ext_b(chips)!SKX_EXT_B_BGA1-IC,TBD!!!F78!VSS(942)!!!!
S!GND!U5D1!Y7!@baseboard_fab2_lib.baseboard_fab2(sch_1):page40_i21@chpset_lib.skx_ext_b(chips)!SKX_EXT_B_BGA1-IC,TBD!!!F78!VSS(943)!!!!
S!GND!U5D1!Y67!@baseboard_fab2_lib.baseboard_fab2(sch_1):page40_i21@chpset_lib.skx_ext_b(chips)!SKX_EXT_B_BGA1-IC,TBD!!!F78!VSS(944)!!!!
S!GND!U5D1!Y5!@baseboard_fab2_lib.baseboard_fab2(sch_1):page40_i21@chpset_lib.skx_ext_b(chips)!SKX_EXT_B_BGA1-IC,TBD!!!F78!VSS(945)!!!!
S!GND!U5D1!Y17!@baseboard_fab2_lib.baseboard_fab2(sch_1):page40_i21@chpset_lib.skx_ext_b(chips)!SKX_EXT_B_BGA1-IC,TBD!!!F78!VSS(946)!!!!
S!GND!U5D1!Y15!@baseboard_fab2_lib.baseboard_fab2(sch_1):page40_i21@chpset_lib.skx_ext_b(chips)!SKX_EXT_B_BGA1-IC,TBD!!!F78!VSS(947)!!!!
S!GND!U5D1!W82!@baseboard_fab2_lib.baseboard_fab2(sch_1):page40_i21@chpset_lib.skx_ext_b(chips)!SKX_EXT_B_BGA1-IC,TBD!!!F78!VSS(948)!!!!
S!GND!U5D1!W78!@baseboard_fab2_lib.baseboard_fab2(sch_1):page40_i21@chpset_lib.skx_ext_b(chips)!SKX_EXT_B_BGA1-IC,TBD!!!F78!VSS(949)!!!!
S!GND!U5D1!W74!@baseboard_fab2_lib.baseboard_fab2(sch_1):page40_i21@chpset_lib.skx_ext_b(chips)!SKX_EXT_B_BGA1-IC,TBD!!!F78!VSS(950)!!!!
S!GND!U5D1!W68!@baseboard_fab2_lib.baseboard_fab2(sch_1):page40_i21@chpset_lib.skx_ext_b(chips)!SKX_EXT_B_BGA1-IC,TBD!!!F78!VSS(951)!!!!
S!GND!U5D1!W42!@baseboard_fab2_lib.baseboard_fab2(sch_1):page40_i21@chpset_lib.skx_ext_b(chips)!SKX_EXT_B_BGA1-IC,TBD!!!F78!VSS(952)!!!!
S!GND!U5D1!W40!@baseboard_fab2_lib.baseboard_fab2(sch_1):page40_i21@chpset_lib.skx_ext_b(chips)!SKX_EXT_B_BGA1-IC,TBD!!!F78!VSS(953)!!!!
S!GND!U5D1!W38!@baseboard_fab2_lib.baseboard_fab2(sch_1):page40_i21@chpset_lib.skx_ext_b(chips)!SKX_EXT_B_BGA1-IC,TBD!!!F78!VSS(954)!!!!
S!GND!U5D1!W36!@baseboard_fab2_lib.baseboard_fab2(sch_1):page40_i21@chpset_lib.skx_ext_b(chips)!SKX_EXT_B_BGA1-IC,TBD!!!F78!VSS(955)!!!!
S!GND!U5D1!W34!@baseboard_fab2_lib.baseboard_fab2(sch_1):page40_i21@chpset_lib.skx_ext_b(chips)!SKX_EXT_B_BGA1-IC,TBD!!!F78!VSS(956)!!!!
S!GND!U5D1!W32!@baseboard_fab2_lib.baseboard_fab2(sch_1):page40_i21@chpset_lib.skx_ext_b(chips)!SKX_EXT_B_BGA1-IC,TBD!!!F78!VSS(957)!!!!
S!GND!U5D1!W30!@baseboard_fab2_lib.baseboard_fab2(sch_1):page40_i21@chpset_lib.skx_ext_b(chips)!SKX_EXT_B_BGA1-IC,TBD!!!F78!VSS(958)!!!!
S!GND!U5D1!W28!@baseboard_fab2_lib.baseboard_fab2(sch_1):page40_i21@chpset_lib.skx_ext_b(chips)!SKX_EXT_B_BGA1-IC,TBD!!!F78!VSS(959)!!!!
S!GND!U5D1!W26!@baseboard_fab2_lib.baseboard_fab2(sch_1):page40_i21@chpset_lib.skx_ext_b(chips)!SKX_EXT_B_BGA1-IC,TBD!!!F78!VSS(960)!!!!
S!GND!U5D1!W24!@baseboard_fab2_lib.baseboard_fab2(sch_1):page40_i21@chpset_lib.skx_ext_b(chips)!SKX_EXT_B_BGA1-IC,TBD!!!F78!VSS(961)!!!!
S!GND!U5D1!W22!@baseboard_fab2_lib.baseboard_fab2(sch_1):page40_i21@chpset_lib.skx_ext_b(chips)!SKX_EXT_B_BGA1-IC,TBD!!!F78!VSS(962)!!!!
S!GND!U5D1!W12!@baseboard_fab2_lib.baseboard_fab2(sch_1):page40_i21@chpset_lib.skx_ext_b(chips)!SKX_EXT_B_BGA1-IC,TBD!!!F78!VSS(963)!!!!
S!GND!U5D1!AC56!@baseboard_fab2_lib.baseboard_fab2(sch_1):page40_i21@chpset_lib.skx_ext_b(chips)!SKX_EXT_B_BGA1-IC,TBD!!!F78!VSS(964)!!!!
S!GND!U5D1!W8!@baseboard_fab2_lib.baseboard_fab2(sch_1):page40_i21@chpset_lib.skx_ext_b(chips)!SKX_EXT_B_BGA1-IC,TBD!!!F78!VSS(965)!!!!
S!GND!U5D1!V83!@baseboard_fab2_lib.baseboard_fab2(sch_1):page40_i21@chpset_lib.skx_ext_b(chips)!SKX_EXT_B_BGA1-IC,TBD!!!F78!VSS(966)!!!!
S!GND!U5D1!V77!@baseboard_fab2_lib.baseboard_fab2(sch_1):page40_i21@chpset_lib.skx_ext_b(chips)!SKX_EXT_B_BGA1-IC,TBD!!!F78!VSS(967)!!!!
S!GND!U5D1!V75!@baseboard_fab2_lib.baseboard_fab2(sch_1):page40_i21@chpset_lib.skx_ext_b(chips)!SKX_EXT_B_BGA1-IC,TBD!!!F78!VSS(968)!!!!
S!GND!U5D1!V73!@baseboard_fab2_lib.baseboard_fab2(sch_1):page40_i21@chpset_lib.skx_ext_b(chips)!SKX_EXT_B_BGA1-IC,TBD!!!F78!VSS(969)!!!!
S!GND!U5D1!V43!@baseboard_fab2_lib.baseboard_fab2(sch_1):page40_i21@chpset_lib.skx_ext_b(chips)!SKX_EXT_B_BGA1-IC,TBD!!!F78!VSS(970)!!!!
S!GND!U5D1!V23!@baseboard_fab2_lib.baseboard_fab2(sch_1):page40_i21@chpset_lib.skx_ext_b(chips)!SKX_EXT_B_BGA1-IC,TBD!!!F78!VSS(971)!!!!
S!GND!U5D1!V21!@baseboard_fab2_lib.baseboard_fab2(sch_1):page40_i21@chpset_lib.skx_ext_b(chips)!SKX_EXT_B_BGA1-IC,TBD!!!F78!VSS(972)!!!!
S!GND!U5D1!V15!@baseboard_fab2_lib.baseboard_fab2(sch_1):page40_i21@chpset_lib.skx_ext_b(chips)!SKX_EXT_B_BGA1-IC,TBD!!!F78!VSS(973)!!!!
S!GND!U5D1!V13!@baseboard_fab2_lib.baseboard_fab2(sch_1):page40_i21@chpset_lib.skx_ext_b(chips)!SKX_EXT_B_BGA1-IC,TBD!!!F78!VSS(974)!!!!
S!GND!U5D1!V9!@baseboard_fab2_lib.baseboard_fab2(sch_1):page40_i21@chpset_lib.skx_ext_b(chips)!SKX_EXT_B_BGA1-IC,TBD!!!F78!VSS(975)!!!!
S!GND!U5D1!V5!@baseboard_fab2_lib.baseboard_fab2(sch_1):page40_i21@chpset_lib.skx_ext_b(chips)!SKX_EXT_B_BGA1-IC,TBD!!!F78!VSS(976)!!!!
S!GND!U5D1!V1!@baseboard_fab2_lib.baseboard_fab2(sch_1):page40_i21@chpset_lib.skx_ext_b(chips)!SKX_EXT_B_BGA1-IC,TBD!!!F78!VSS(977)!!!!
S!GND!U5D1!U86!@baseboard_fab2_lib.baseboard_fab2(sch_1):page40_i21@chpset_lib.skx_ext_b(chips)!SKX_EXT_B_BGA1-IC,TBD!!!F78!VSS(978)!!!!
S!GND!U5D1!U80!@baseboard_fab2_lib.baseboard_fab2(sch_1):page40_i21@chpset_lib.skx_ext_b(chips)!SKX_EXT_B_BGA1-IC,TBD!!!F78!VSS(979)!!!!
S!GND!U5D1!U78!@baseboard_fab2_lib.baseboard_fab2(sch_1):page40_i21@chpset_lib.skx_ext_b(chips)!SKX_EXT_B_BGA1-IC,TBD!!!F78!VSS(980)!!!!
S!GND!U5D1!U76!@baseboard_fab2_lib.baseboard_fab2(sch_1):page40_i21@chpset_lib.skx_ext_b(chips)!SKX_EXT_B_BGA1-IC,TBD!!!F78!VSS(981)!!!!
S!GND!U5D1!U74!@baseboard_fab2_lib.baseboard_fab2(sch_1):page40_i21@chpset_lib.skx_ext_b(chips)!SKX_EXT_B_BGA1-IC,TBD!!!F78!VSS(982)!!!!
S!GND!U5D1!U70!@baseboard_fab2_lib.baseboard_fab2(sch_1):page40_i21@chpset_lib.skx_ext_b(chips)!SKX_EXT_B_BGA1-IC,TBD!!!F78!VSS(983)!!!!
S!GND!U5D1!U68!@baseboard_fab2_lib.baseboard_fab2(sch_1):page40_i21@chpset_lib.skx_ext_b(chips)!SKX_EXT_B_BGA1-IC,TBD!!!F78!VSS(984)!!!!
S!GND!U5D1!U42!@baseboard_fab2_lib.baseboard_fab2(sch_1):page40_i21@chpset_lib.skx_ext_b(chips)!SKX_EXT_B_BGA1-IC,TBD!!!F78!VSS(985)!!!!
S!GND!U5D1!U36!@baseboard_fab2_lib.baseboard_fab2(sch_1):page40_i21@chpset_lib.skx_ext_b(chips)!SKX_EXT_B_BGA1-IC,TBD!!!F78!VSS(986)!!!!
S!GND!U5D1!U30!@baseboard_fab2_lib.baseboard_fab2(sch_1):page40_i21@chpset_lib.skx_ext_b(chips)!SKX_EXT_B_BGA1-IC,TBD!!!F78!VSS(987)!!!!
S!GND!U5D1!U24!@baseboard_fab2_lib.baseboard_fab2(sch_1):page40_i21@chpset_lib.skx_ext_b(chips)!SKX_EXT_B_BGA1-IC,TBD!!!F78!VSS(988)!!!!
S!GND!U5D1!U22!@baseboard_fab2_lib.baseboard_fab2(sch_1):page40_i21@chpset_lib.skx_ext_b(chips)!SKX_EXT_B_BGA1-IC,TBD!!!F78!VSS(989)!!!!
S!GND!U5D1!U20!@baseboard_fab2_lib.baseboard_fab2(sch_1):page40_i21@chpset_lib.skx_ext_b(chips)!SKX_EXT_B_BGA1-IC,TBD!!!F78!VSS(990)!!!!
S!GND!U5D1!U6!@baseboard_fab2_lib.baseboard_fab2(sch_1):page40_i21@chpset_lib.skx_ext_b(chips)!SKX_EXT_B_BGA1-IC,TBD!!!F78!VSS(991)!!!!
S!GND!U5D1!U4!@baseboard_fab2_lib.baseboard_fab2(sch_1):page40_i21@chpset_lib.skx_ext_b(chips)!SKX_EXT_B_BGA1-IC,TBD!!!F78!VSS(992)!!!!
S!GND!U5D1!U2!@baseboard_fab2_lib.baseboard_fab2(sch_1):page40_i21@chpset_lib.skx_ext_b(chips)!SKX_EXT_B_BGA1-IC,TBD!!!F78!VSS(993)!!!!
S!GND!U5D1!T85!@baseboard_fab2_lib.baseboard_fab2(sch_1):page40_i21@chpset_lib.skx_ext_b(chips)!SKX_EXT_B_BGA1-IC,TBD!!!F78!VSS(994)!!!!
S!GND!U5D1!T83!@baseboard_fab2_lib.baseboard_fab2(sch_1):page40_i21@chpset_lib.skx_ext_b(chips)!SKX_EXT_B_BGA1-IC,TBD!!!F78!VSS(995)!!!!
S!GND!U5D1!T77!@baseboard_fab2_lib.baseboard_fab2(sch_1):page40_i21@chpset_lib.skx_ext_b(chips)!SKX_EXT_B_BGA1-IC,TBD!!!F78!VSS(996)!!!!
S!GND!U5D1!T73!@baseboard_fab2_lib.baseboard_fab2(sch_1):page40_i21@chpset_lib.skx_ext_b(chips)!SKX_EXT_B_BGA1-IC,TBD!!!F78!VSS(997)!!!!
S!GND!U5D1!T65!@baseboard_fab2_lib.baseboard_fab2(sch_1):page40_i21@chpset_lib.skx_ext_b(chips)!SKX_EXT_B_BGA1-IC,TBD!!!F78!VSS(998)!!!!
S!GND!U5D1!T41!@baseboard_fab2_lib.baseboard_fab2(sch_1):page40_i21@chpset_lib.skx_ext_b(chips)!SKX_EXT_B_BGA1-IC,TBD!!!F78!VSS(999)!!!!
S!GND!U5D1!AP63!@baseboard_fab2_lib.baseboard_fab2(sch_1):page40_i23@chpset_lib.skx_ext_b(chips)!SKX_EXT_B_BGA1-IC,TBD!!!F76!VSS(748)!!!!
S!GND!U5D1!AP59!@baseboard_fab2_lib.baseboard_fab2(sch_1):page40_i23@chpset_lib.skx_ext_b(chips)!SKX_EXT_B_BGA1-IC,TBD!!!F76!VSS(749)!!!!
S!GND!U5D1!AP31!@baseboard_fab2_lib.baseboard_fab2(sch_1):page40_i23@chpset_lib.skx_ext_b(chips)!SKX_EXT_B_BGA1-IC,TBD!!!F76!VSS(750)!!!!
S!GND!U5D1!AP19!@baseboard_fab2_lib.baseboard_fab2(sch_1):page40_i23@chpset_lib.skx_ext_b(chips)!SKX_EXT_B_BGA1-IC,TBD!!!F76!VSS(751)!!!!
S!GND!U5D1!AP13!@baseboard_fab2_lib.baseboard_fab2(sch_1):page40_i23@chpset_lib.skx_ext_b(chips)!SKX_EXT_B_BGA1-IC,TBD!!!F76!VSS(752)!!!!
S!GND!U5D1!AP9!@baseboard_fab2_lib.baseboard_fab2(sch_1):page40_i23@chpset_lib.skx_ext_b(chips)!SKX_EXT_B_BGA1-IC,TBD!!!F76!VSS(753)!!!!
S!GND!U5D1!AP5!@baseboard_fab2_lib.baseboard_fab2(sch_1):page40_i23@chpset_lib.skx_ext_b(chips)!SKX_EXT_B_BGA1-IC,TBD!!!F76!VSS(754)!!!!
S!GND!U5D1!AN78!@baseboard_fab2_lib.baseboard_fab2(sch_1):page40_i23@chpset_lib.skx_ext_b(chips)!SKX_EXT_B_BGA1-IC,TBD!!!F76!VSS(755)!!!!
S!GND!U5D1!AN58!@baseboard_fab2_lib.baseboard_fab2(sch_1):page40_i23@chpset_lib.skx_ext_b(chips)!SKX_EXT_B_BGA1-IC,TBD!!!F76!VSS(756)!!!!
S!GND!U5D1!AN28!@baseboard_fab2_lib.baseboard_fab2(sch_1):page40_i23@chpset_lib.skx_ext_b(chips)!SKX_EXT_B_BGA1-IC,TBD!!!F76!VSS(757)!!!!
S!GND!U5D1!AN6!@baseboard_fab2_lib.baseboard_fab2(sch_1):page40_i23@chpset_lib.skx_ext_b(chips)!SKX_EXT_B_BGA1-IC,TBD!!!F76!VSS(758)!!!!
S!GND!U5D1!AN2!@baseboard_fab2_lib.baseboard_fab2(sch_1):page40_i23@chpset_lib.skx_ext_b(chips)!SKX_EXT_B_BGA1-IC,TBD!!!F76!VSS(759)!!!!
S!GND!U5D1!AM83!@baseboard_fab2_lib.baseboard_fab2(sch_1):page40_i23@chpset_lib.skx_ext_b(chips)!SKX_EXT_B_BGA1-IC,TBD!!!F76!VSS(760)!!!!
S!GND!U5D1!AM79!@baseboard_fab2_lib.baseboard_fab2(sch_1):page40_i23@chpset_lib.skx_ext_b(chips)!SKX_EXT_B_BGA1-IC,TBD!!!F76!VSS(761)!!!!
S!GND!U5D1!AM73!@baseboard_fab2_lib.baseboard_fab2(sch_1):page40_i23@chpset_lib.skx_ext_b(chips)!SKX_EXT_B_BGA1-IC,TBD!!!F76!VSS(762)!!!!
S!GND!U5D1!AM69!@baseboard_fab2_lib.baseboard_fab2(sch_1):page40_i23@chpset_lib.skx_ext_b(chips)!SKX_EXT_B_BGA1-IC,TBD!!!F76!VSS(763)!!!!
S!GND!U5D1!AM63!@baseboard_fab2_lib.baseboard_fab2(sch_1):page40_i23@chpset_lib.skx_ext_b(chips)!SKX_EXT_B_BGA1-IC,TBD!!!F76!VSS(764)!!!!
S!GND!U5D1!AM57!@baseboard_fab2_lib.baseboard_fab2(sch_1):page40_i23@chpset_lib.skx_ext_b(chips)!SKX_EXT_B_BGA1-IC,TBD!!!F76!VSS(765)!!!!
S!GND!U5D1!AM31!@baseboard_fab2_lib.baseboard_fab2(sch_1):page40_i23@chpset_lib.skx_ext_b(chips)!SKX_EXT_B_BGA1-IC,TBD!!!F76!VSS(766)!!!!
S!GND!U5D1!AC50!@baseboard_fab2_lib.baseboard_fab2(sch_1):page40_i23@chpset_lib.skx_ext_b(chips)!SKX_EXT_B_BGA1-IC,TBD!!!F76!VSS(767)!!!!
S!GND!U5D1!AM1!@baseboard_fab2_lib.baseboard_fab2(sch_1):page40_i23@chpset_lib.skx_ext_b(chips)!SKX_EXT_B_BGA1-IC,TBD!!!F76!VSS(768)!!!!
S!GND!U5D1!AL86!@baseboard_fab2_lib.baseboard_fab2(sch_1):page40_i23@chpset_lib.skx_ext_b(chips)!SKX_EXT_B_BGA1-IC,TBD!!!F76!VSS(769)!!!!
S!GND!U5D1!AL82!@baseboard_fab2_lib.baseboard_fab2(sch_1):page40_i23@chpset_lib.skx_ext_b(chips)!SKX_EXT_B_BGA1-IC,TBD!!!F76!VSS(770)!!!!
S!GND!U5D1!AL80!@baseboard_fab2_lib.baseboard_fab2(sch_1):page40_i23@chpset_lib.skx_ext_b(chips)!SKX_EXT_B_BGA1-IC,TBD!!!F76!VSS(771)!!!!
S!GND!U5D1!AL78!@baseboard_fab2_lib.baseboard_fab2(sch_1):page40_i23@chpset_lib.skx_ext_b(chips)!SKX_EXT_B_BGA1-IC,TBD!!!F76!VSS(772)!!!!
S!GND!U5D1!AL76!@baseboard_fab2_lib.baseboard_fab2(sch_1):page40_i23@chpset_lib.skx_ext_b(chips)!SKX_EXT_B_BGA1-IC,TBD!!!F76!VSS(773)!!!!
S!GND!U5D1!AL68!@baseboard_fab2_lib.baseboard_fab2(sch_1):page40_i22@chpset_lib.skx_ext_b(chips)!SKX_EXT_B_BGA1-IC,TBD!!!F77!VSS(774)!!!!
S!GND!U5D1!AL64!@baseboard_fab2_lib.baseboard_fab2(sch_1):page40_i22@chpset_lib.skx_ext_b(chips)!SKX_EXT_B_BGA1-IC,TBD!!!F77!VSS(775)!!!!
S!GND!U5D1!AL56!@baseboard_fab2_lib.baseboard_fab2(sch_1):page40_i22@chpset_lib.skx_ext_b(chips)!SKX_EXT_B_BGA1-IC,TBD!!!F77!VSS(776)!!!!
S!GND!U5D1!AL32!@baseboard_fab2_lib.baseboard_fab2(sch_1):page40_i22@chpset_lib.skx_ext_b(chips)!SKX_EXT_B_BGA1-IC,TBD!!!F77!VSS(777)!!!!
S!GND!U5D1!AL30!@baseboard_fab2_lib.baseboard_fab2(sch_1):page40_i22@chpset_lib.skx_ext_b(chips)!SKX_EXT_B_BGA1-IC,TBD!!!F77!VSS(778)!!!!
S!GND!U5D1!AL24!@baseboard_fab2_lib.baseboard_fab2(sch_1):page40_i22@chpset_lib.skx_ext_b(chips)!SKX_EXT_B_BGA1-IC,TBD!!!F77!VSS(779)!!!!
S!GND!U5D1!AL10!@baseboard_fab2_lib.baseboard_fab2(sch_1):page40_i22@chpset_lib.skx_ext_b(chips)!SKX_EXT_B_BGA1-IC,TBD!!!F77!VSS(780)!!!!
S!GND!U5D1!AL4!@baseboard_fab2_lib.baseboard_fab2(sch_1):page40_i22@chpset_lib.skx_ext_b(chips)!SKX_EXT_B_BGA1-IC,TBD!!!F77!VSS(781)!!!!
S!GND!U5D1!AK85!@baseboard_fab2_lib.baseboard_fab2(sch_1):page40_i22@chpset_lib.skx_ext_b(chips)!SKX_EXT_B_BGA1-IC,TBD!!!F77!VSS(782)!!!!
S!GND!U5D1!AK83!@baseboard_fab2_lib.baseboard_fab2(sch_1):page40_i22@chpset_lib.skx_ext_b(chips)!SKX_EXT_B_BGA1-IC,TBD!!!F77!VSS(783)!!!!
S!GND!U5D1!AK81!@baseboard_fab2_lib.baseboard_fab2(sch_1):page40_i22@chpset_lib.skx_ext_b(chips)!SKX_EXT_B_BGA1-IC,TBD!!!F77!VSS(784)!!!!
S!GND!U5D1!AK79!@baseboard_fab2_lib.baseboard_fab2(sch_1):page40_i22@chpset_lib.skx_ext_b(chips)!SKX_EXT_B_BGA1-IC,TBD!!!F77!VSS(785)!!!!
S!GND!U5D1!AK73!@baseboard_fab2_lib.baseboard_fab2(sch_1):page40_i22@chpset_lib.skx_ext_b(chips)!SKX_EXT_B_BGA1-IC,TBD!!!F77!VSS(786)!!!!
S!GND!U5D1!AK67!@baseboard_fab2_lib.baseboard_fab2(sch_1):page40_i22@chpset_lib.skx_ext_b(chips)!SKX_EXT_B_BGA1-IC,TBD!!!F77!VSS(787)!!!!
S!GND!U5D1!AK65!@baseboard_fab2_lib.baseboard_fab2(sch_1):page40_i22@chpset_lib.skx_ext_b(chips)!SKX_EXT_B_BGA1-IC,TBD!!!F77!VSS(788)!!!!
S!GND!U5D1!AK55!@baseboard_fab2_lib.baseboard_fab2(sch_1):page40_i22@chpset_lib.skx_ext_b(chips)!SKX_EXT_B_BGA1-IC,TBD!!!F77!VSS(789)!!!!
S!GND!U5D1!AK33!@baseboard_fab2_lib.baseboard_fab2(sch_1):page40_i22@chpset_lib.skx_ext_b(chips)!SKX_EXT_B_BGA1-IC,TBD!!!F77!VSS(790)!!!!
S!GND!U5D1!AK31!@baseboard_fab2_lib.baseboard_fab2(sch_1):page40_i22@chpset_lib.skx_ext_b(chips)!SKX_EXT_B_BGA1-IC,TBD!!!F77!VSS(791)!!!!
S!GND!U5D1!AK29!@baseboard_fab2_lib.baseboard_fab2(sch_1):page40_i22@chpset_lib.skx_ext_b(chips)!SKX_EXT_B_BGA1-IC,TBD!!!F77!VSS(792)!!!!
S!GND!U5D1!AK25!@baseboard_fab2_lib.baseboard_fab2(sch_1):page40_i22@chpset_lib.skx_ext_b(chips)!SKX_EXT_B_BGA1-IC,TBD!!!F77!VSS(793)!!!!
S!GND!U5D1!AK23!@baseboard_fab2_lib.baseboard_fab2(sch_1):page40_i22@chpset_lib.skx_ext_b(chips)!SKX_EXT_B_BGA1-IC,TBD!!!F77!VSS(794)!!!!
S!GND!U5D1!AK19!@baseboard_fab2_lib.baseboard_fab2(sch_1):page40_i22@chpset_lib.skx_ext_b(chips)!SKX_EXT_B_BGA1-IC,TBD!!!F77!VSS(795)!!!!
S!GND!U5D1!AK13!@baseboard_fab2_lib.baseboard_fab2(sch_1):page40_i22@chpset_lib.skx_ext_b(chips)!SKX_EXT_B_BGA1-IC,TBD!!!F77!VSS(796)!!!!
S!GND!U5D1!AK9!@baseboard_fab2_lib.baseboard_fab2(sch_1):page40_i22@chpset_lib.skx_ext_b(chips)!SKX_EXT_B_BGA1-IC,TBD!!!F77!VSS(797)!!!!
S!GND!U5D1!AJ86!@baseboard_fab2_lib.baseboard_fab2(sch_1):page40_i22@chpset_lib.skx_ext_b(chips)!SKX_EXT_B_BGA1-IC,TBD!!!F77!VSS(798)!!!!
S!GND!U5D1!AJ82!@baseboard_fab2_lib.baseboard_fab2(sch_1):page40_i22@chpset_lib.skx_ext_b(chips)!SKX_EXT_B_BGA1-IC,TBD!!!F77!VSS(799)!!!!
S!GND!U5D1!AJ78!@baseboard_fab2_lib.baseboard_fab2(sch_1):page40_i22@chpset_lib.skx_ext_b(chips)!SKX_EXT_B_BGA1-IC,TBD!!!F77!VSS(800)!!!!
S!GND!U5D1!AJ74!@baseboard_fab2_lib.baseboard_fab2(sch_1):page40_i22@chpset_lib.skx_ext_b(chips)!SKX_EXT_B_BGA1-IC,TBD!!!F77!VSS(801)!!!!
S!GND!U5D1!AJ68!@baseboard_fab2_lib.baseboard_fab2(sch_1):page40_i22@chpset_lib.skx_ext_b(chips)!SKX_EXT_B_BGA1-IC,TBD!!!F77!VSS(802)!!!!
S!GND!U5D1!AJ66!@baseboard_fab2_lib.baseboard_fab2(sch_1):page40_i22@chpset_lib.skx_ext_b(chips)!SKX_EXT_B_BGA1-IC,TBD!!!F77!VSS(803)!!!!
S!GND!U5D1!AJ54!@baseboard_fab2_lib.baseboard_fab2(sch_1):page40_i22@chpset_lib.skx_ext_b(chips)!SKX_EXT_B_BGA1-IC,TBD!!!F77!VSS(804)!!!!
S!GND!U5D1!AJ52!@baseboard_fab2_lib.baseboard_fab2(sch_1):page40_i22@chpset_lib.skx_ext_b(chips)!SKX_EXT_B_BGA1-IC,TBD!!!F77!VSS(805)!!!!
S!GND!U5D1!AJ50!@baseboard_fab2_lib.baseboard_fab2(sch_1):page40_i22@chpset_lib.skx_ext_b(chips)!SKX_EXT_B_BGA1-IC,TBD!!!F77!VSS(806)!!!!
S!GND!U5D1!AJ48!@baseboard_fab2_lib.baseboard_fab2(sch_1):page40_i22@chpset_lib.skx_ext_b(chips)!SKX_EXT_B_BGA1-IC,TBD!!!F77!VSS(807)!!!!
S!GND!U5D1!AJ46!@baseboard_fab2_lib.baseboard_fab2(sch_1):page40_i22@chpset_lib.skx_ext_b(chips)!SKX_EXT_B_BGA1-IC,TBD!!!F77!VSS(808)!!!!
S!GND!U5D1!AJ34!@baseboard_fab2_lib.baseboard_fab2(sch_1):page40_i22@chpset_lib.skx_ext_b(chips)!SKX_EXT_B_BGA1-IC,TBD!!!F77!VSS(809)!!!!
S!GND!U5D1!AJ32!@baseboard_fab2_lib.baseboard_fab2(sch_1):page40_i22@chpset_lib.skx_ext_b(chips)!SKX_EXT_B_BGA1-IC,TBD!!!F77!VSS(810)!!!!
S!GND!U5D1!AJ28!@baseboard_fab2_lib.baseboard_fab2(sch_1):page40_i22@chpset_lib.skx_ext_b(chips)!SKX_EXT_B_BGA1-IC,TBD!!!F77!VSS(811)!!!!
S!GND!U5D1!AJ26!@baseboard_fab2_lib.baseboard_fab2(sch_1):page40_i22@chpset_lib.skx_ext_b(chips)!SKX_EXT_B_BGA1-IC,TBD!!!F77!VSS(812)!!!!
S!GND!U5D1!AJ22!@baseboard_fab2_lib.baseboard_fab2(sch_1):page40_i22@chpset_lib.skx_ext_b(chips)!SKX_EXT_B_BGA1-IC,TBD!!!F77!VSS(813)!!!!
S!GND!U5D1!AJ8!@baseboard_fab2_lib.baseboard_fab2(sch_1):page40_i22@chpset_lib.skx_ext_b(chips)!SKX_EXT_B_BGA1-IC,TBD!!!F77!VSS(814)!!!!
S!GND!U5D1!AH83!@baseboard_fab2_lib.baseboard_fab2(sch_1):page40_i22@chpset_lib.skx_ext_b(chips)!SKX_EXT_B_BGA1-IC,TBD!!!F77!VSS(815)!!!!
S!GND!U5D1!AH77!@baseboard_fab2_lib.baseboard_fab2(sch_1):page40_i22@chpset_lib.skx_ext_b(chips)!SKX_EXT_B_BGA1-IC,TBD!!!F77!VSS(816)!!!!
S!GND!U5D1!AH75!@baseboard_fab2_lib.baseboard_fab2(sch_1):page40_i22@chpset_lib.skx_ext_b(chips)!SKX_EXT_B_BGA1-IC,TBD!!!F77!VSS(817)!!!!
S!GND!U5D1!AH69!@baseboard_fab2_lib.baseboard_fab2(sch_1):page40_i22@chpset_lib.skx_ext_b(chips)!SKX_EXT_B_BGA1-IC,TBD!!!F77!VSS(818)!!!!
S!GND!U5D1!AH65!@baseboard_fab2_lib.baseboard_fab2(sch_1):page40_i22@chpset_lib.skx_ext_b(chips)!SKX_EXT_B_BGA1-IC,TBD!!!F77!VSS(819)!!!!
S!GND!U5D1!AH61!@baseboard_fab2_lib.baseboard_fab2(sch_1):page40_i22@chpset_lib.skx_ext_b(chips)!SKX_EXT_B_BGA1-IC,TBD!!!F77!VSS(820)!!!!
S!GND!U5D1!AH59!@baseboard_fab2_lib.baseboard_fab2(sch_1):page40_i22@chpset_lib.skx_ext_b(chips)!SKX_EXT_B_BGA1-IC,TBD!!!F77!VSS(821)!!!!
S!GND!U5D1!AH53!@baseboard_fab2_lib.baseboard_fab2(sch_1):page40_i22@chpset_lib.skx_ext_b(chips)!SKX_EXT_B_BGA1-IC,TBD!!!F77!VSS(822)!!!!
S!GND!U5D1!AH51!@baseboard_fab2_lib.baseboard_fab2(sch_1):page40_i22@chpset_lib.skx_ext_b(chips)!SKX_EXT_B_BGA1-IC,TBD!!!F77!VSS(823)!!!!
S!GND!U5D1!AH49!@baseboard_fab2_lib.baseboard_fab2(sch_1):page40_i22@chpset_lib.skx_ext_b(chips)!SKX_EXT_B_BGA1-IC,TBD!!!F77!VSS(824)!!!!
S!GND!U5D1!AH47!@baseboard_fab2_lib.baseboard_fab2(sch_1):page40_i22@chpset_lib.skx_ext_b(chips)!SKX_EXT_B_BGA1-IC,TBD!!!F77!VSS(825)!!!!
S!GND!U5D1!AH45!@baseboard_fab2_lib.baseboard_fab2(sch_1):page40_i22@chpset_lib.skx_ext_b(chips)!SKX_EXT_B_BGA1-IC,TBD!!!F77!VSS(826)!!!!
S!GND!U5D1!AH35!@baseboard_fab2_lib.baseboard_fab2(sch_1):page40_i22@chpset_lib.skx_ext_b(chips)!SKX_EXT_B_BGA1-IC,TBD!!!F77!VSS(827)!!!!
S!GND!U5D1!AH33!@baseboard_fab2_lib.baseboard_fab2(sch_1):page40_i22@chpset_lib.skx_ext_b(chips)!SKX_EXT_B_BGA1-IC,TBD!!!F77!VSS(828)!!!!
S!GND!U5D1!AH27!@baseboard_fab2_lib.baseboard_fab2(sch_1):page40_i22@chpset_lib.skx_ext_b(chips)!SKX_EXT_B_BGA1-IC,TBD!!!F77!VSS(829)!!!!
S!GND!U5D1!AH21!@baseboard_fab2_lib.baseboard_fab2(sch_1):page40_i22@chpset_lib.skx_ext_b(chips)!SKX_EXT_B_BGA1-IC,TBD!!!F77!VSS(830)!!!!
S!GND!U5D1!AH5!@baseboard_fab2_lib.baseboard_fab2(sch_1):page40_i22@chpset_lib.skx_ext_b(chips)!SKX_EXT_B_BGA1-IC,TBD!!!F77!VSS(831)!!!!
S!GND!U5D1!AH1!@baseboard_fab2_lib.baseboard_fab2(sch_1):page40_i22@chpset_lib.skx_ext_b(chips)!SKX_EXT_B_BGA1-IC,TBD!!!F77!VSS(832)!!!!
S!GND!U5D1!AG80!@baseboard_fab2_lib.baseboard_fab2(sch_1):page40_i22@chpset_lib.skx_ext_b(chips)!SKX_EXT_B_BGA1-IC,TBD!!!F77!VSS(833)!!!!
S!GND!U5D1!AG78!@baseboard_fab2_lib.baseboard_fab2(sch_1):page40_i22@chpset_lib.skx_ext_b(chips)!SKX_EXT_B_BGA1-IC,TBD!!!F77!VSS(834)!!!!
S!GND!U5D1!AG76!@baseboard_fab2_lib.baseboard_fab2(sch_1):page40_i22@chpset_lib.skx_ext_b(chips)!SKX_EXT_B_BGA1-IC,TBD!!!F77!VSS(835)!!!!
S!GND!U5D1!AG74!@baseboard_fab2_lib.baseboard_fab2(sch_1):page40_i22@chpset_lib.skx_ext_b(chips)!SKX_EXT_B_BGA1-IC,TBD!!!F77!VSS(836)!!!!
S!GND!U5D1!AG70!@baseboard_fab2_lib.baseboard_fab2(sch_1):page40_i22@chpset_lib.skx_ext_b(chips)!SKX_EXT_B_BGA1-IC,TBD!!!F77!VSS(837)!!!!
S!GND!U5D1!AG64!@baseboard_fab2_lib.baseboard_fab2(sch_1):page40_i22@chpset_lib.skx_ext_b(chips)!SKX_EXT_B_BGA1-IC,TBD!!!F77!VSS(838)!!!!
S!GND!U5D1!AG36!@baseboard_fab2_lib.baseboard_fab2(sch_1):page40_i22@chpset_lib.skx_ext_b(chips)!SKX_EXT_B_BGA1-IC,TBD!!!F77!VSS(839)!!!!
S!GND!U5D1!AG18!@baseboard_fab2_lib.baseboard_fab2(sch_1):page40_i22@chpset_lib.skx_ext_b(chips)!SKX_EXT_B_BGA1-IC,TBD!!!F77!VSS(840)!!!!
S!GND!U5D1!AG14!@baseboard_fab2_lib.baseboard_fab2(sch_1):page40_i22@chpset_lib.skx_ext_b(chips)!SKX_EXT_B_BGA1-IC,TBD!!!F77!VSS(841)!!!!
S!GND!U5D1!AG12!@baseboard_fab2_lib.baseboard_fab2(sch_1):page40_i22@chpset_lib.skx_ext_b(chips)!SKX_EXT_B_BGA1-IC,TBD!!!F77!VSS(842)!!!!
S!GND!U5D1!AF85!@baseboard_fab2_lib.baseboard_fab2(sch_1):page40_i22@chpset_lib.skx_ext_b(chips)!SKX_EXT_B_BGA1-IC,TBD!!!F77!VSS(843)!!!!
S!GND!U5D1!AF83!@baseboard_fab2_lib.baseboard_fab2(sch_1):page40_i22@chpset_lib.skx_ext_b(chips)!SKX_EXT_B_BGA1-IC,TBD!!!F77!VSS(844)!!!!
S!GND!U5D1!AF77!@baseboard_fab2_lib.baseboard_fab2(sch_1):page40_i22@chpset_lib.skx_ext_b(chips)!SKX_EXT_B_BGA1-IC,TBD!!!F77!VSS(845)!!!!
S!GND!U5D1!AF73!@baseboard_fab2_lib.baseboard_fab2(sch_1):page40_i22@chpset_lib.skx_ext_b(chips)!SKX_EXT_B_BGA1-IC,TBD!!!F77!VSS(846)!!!!
S!GND!U5D1!AF41!@baseboard_fab2_lib.baseboard_fab2(sch_1):page40_i22@chpset_lib.skx_ext_b(chips)!SKX_EXT_B_BGA1-IC,TBD!!!F77!VSS(847)!!!!
S!GND!U5D1!AF39!@baseboard_fab2_lib.baseboard_fab2(sch_1):page40_i22@chpset_lib.skx_ext_b(chips)!SKX_EXT_B_BGA1-IC,TBD!!!F77!VSS(848)!!!!
S!GND!U5D1!AF37!@baseboard_fab2_lib.baseboard_fab2(sch_1):page40_i22@chpset_lib.skx_ext_b(chips)!SKX_EXT_B_BGA1-IC,TBD!!!F77!VSS(849)!!!!
S!GND!U5D1!AF33!@baseboard_fab2_lib.baseboard_fab2(sch_1):page40_i22@chpset_lib.skx_ext_b(chips)!SKX_EXT_B_BGA1-IC,TBD!!!F77!VSS(850)!!!!
S!GND!U5D1!AF31!@baseboard_fab2_lib.baseboard_fab2(sch_1):page40_i22@chpset_lib.skx_ext_b(chips)!SKX_EXT_B_BGA1-IC,TBD!!!F77!VSS(851)!!!!
S!GND!U5D1!AF29!@baseboard_fab2_lib.baseboard_fab2(sch_1):page40_i22@chpset_lib.skx_ext_b(chips)!SKX_EXT_B_BGA1-IC,TBD!!!F77!VSS(852)!!!!
S!GND!U5D1!AF27!@baseboard_fab2_lib.baseboard_fab2(sch_1):page40_i22@chpset_lib.skx_ext_b(chips)!SKX_EXT_B_BGA1-IC,TBD!!!F77!VSS(853)!!!!
S!GND!U5D1!AF25!@baseboard_fab2_lib.baseboard_fab2(sch_1):page40_i22@chpset_lib.skx_ext_b(chips)!SKX_EXT_B_BGA1-IC,TBD!!!F77!VSS(854)!!!!
S!GND!U5D1!AF23!@baseboard_fab2_lib.baseboard_fab2(sch_1):page40_i22@chpset_lib.skx_ext_b(chips)!SKX_EXT_B_BGA1-IC,TBD!!!F77!VSS(855)!!!!
S!GND!U5D1!AF21!@baseboard_fab2_lib.baseboard_fab2(sch_1):page40_i22@chpset_lib.skx_ext_b(chips)!SKX_EXT_B_BGA1-IC,TBD!!!F77!VSS(856)!!!!
S!GND!U5D1!AF9!@baseboard_fab2_lib.baseboard_fab2(sch_1):page40_i22@chpset_lib.skx_ext_b(chips)!SKX_EXT_B_BGA1-IC,TBD!!!F77!VSS(857)!!!!
S!GND!U5D1!AC52!@baseboard_fab2_lib.baseboard_fab2(sch_1):page40_i22@chpset_lib.skx_ext_b(chips)!SKX_EXT_B_BGA1-IC,TBD!!!F77!VSS(858)!!!!
S!GND!U5D1!AF1!@baseboard_fab2_lib.baseboard_fab2(sch_1):page40_i22@chpset_lib.skx_ext_b(chips)!SKX_EXT_B_BGA1-IC,TBD!!!F77!VSS(859)!!!!
S!GND!U5D1!AE78!@baseboard_fab2_lib.baseboard_fab2(sch_1):page40_i22@chpset_lib.skx_ext_b(chips)!SKX_EXT_B_BGA1-IC,TBD!!!F77!VSS(860)!!!!
S!GND!U5D1!AE70!@baseboard_fab2_lib.baseboard_fab2(sch_1):page40_i22@chpset_lib.skx_ext_b(chips)!SKX_EXT_B_BGA1-IC,TBD!!!F77!VSS(861)!!!!
S!GND!U5D1!AE68!@baseboard_fab2_lib.baseboard_fab2(sch_1):page40_i22@chpset_lib.skx_ext_b(chips)!SKX_EXT_B_BGA1-IC,TBD!!!F77!VSS(862)!!!!
S!GND!U5D1!AE66!@baseboard_fab2_lib.baseboard_fab2(sch_1):page40_i22@chpset_lib.skx_ext_b(chips)!SKX_EXT_B_BGA1-IC,TBD!!!F77!VSS(863)!!!!
S!GND!U5D1!AE64!@baseboard_fab2_lib.baseboard_fab2(sch_1):page40_i22@chpset_lib.skx_ext_b(chips)!SKX_EXT_B_BGA1-IC,TBD!!!F77!VSS(864)!!!!
S!GND!U5D1!AE42!@baseboard_fab2_lib.baseboard_fab2(sch_1):page40_i22@chpset_lib.skx_ext_b(chips)!SKX_EXT_B_BGA1-IC,TBD!!!F77!VSS(865)!!!!
S!GND!U5D1!AE40!@baseboard_fab2_lib.baseboard_fab2(sch_1):page40_i22@chpset_lib.skx_ext_b(chips)!SKX_EXT_B_BGA1-IC,TBD!!!F77!VSS(866)!!!!
S!GND!U5D1!AE38!@baseboard_fab2_lib.baseboard_fab2(sch_1):page40_i22@chpset_lib.skx_ext_b(chips)!SKX_EXT_B_BGA1-IC,TBD!!!F77!VSS(867)!!!!
S!GND!U5D1!AE16!@baseboard_fab2_lib.baseboard_fab2(sch_1):page40_i22@chpset_lib.skx_ext_b(chips)!SKX_EXT_B_BGA1-IC,TBD!!!F77!VSS(868)!!!!
S!GND!U5D1!AC54!@baseboard_fab2_lib.baseboard_fab2(sch_1):page40_i22@chpset_lib.skx_ext_b(chips)!SKX_EXT_B_BGA1-IC,TBD!!!F77!VSS(869)!!!!
S!GND!U5D1!AE8!@baseboard_fab2_lib.baseboard_fab2(sch_1):page40_i22@chpset_lib.skx_ext_b(chips)!SKX_EXT_B_BGA1-IC,TBD!!!F77!VSS(870)!!!!
S!GND!U5D1!AE4!@baseboard_fab2_lib.baseboard_fab2(sch_1):page40_i22@chpset_lib.skx_ext_b(chips)!SKX_EXT_B_BGA1-IC,TBD!!!F77!VSS(871)!!!!
S!GND!U5D1!AD85!@baseboard_fab2_lib.baseboard_fab2(sch_1):page40_i22@chpset_lib.skx_ext_b(chips)!SKX_EXT_B_BGA1-IC,TBD!!!F77!VSS(872)!!!!
S!GND!U5D1!AD83!@baseboard_fab2_lib.baseboard_fab2(sch_1):page40_i22@chpset_lib.skx_ext_b(chips)!SKX_EXT_B_BGA1-IC,TBD!!!F77!VSS(873)!!!!
S!GND!U5D1!AD81!@baseboard_fab2_lib.baseboard_fab2(sch_1):page40_i22@chpset_lib.skx_ext_b(chips)!SKX_EXT_B_BGA1-IC,TBD!!!F77!VSS(874)!!!!
S!GND!U5D1!AD75!@baseboard_fab2_lib.baseboard_fab2(sch_1):page40_i22@chpset_lib.skx_ext_b(chips)!SKX_EXT_B_BGA1-IC,TBD!!!F77!VSS(875)!!!!
S!GND!U5D1!AD73!@baseboard_fab2_lib.baseboard_fab2(sch_1):page40_i22@chpset_lib.skx_ext_b(chips)!SKX_EXT_B_BGA1-IC,TBD!!!F77!VSS(876)!!!!
S!GND!U5D1!AD71!@baseboard_fab2_lib.baseboard_fab2(sch_1):page40_i22@chpset_lib.skx_ext_b(chips)!SKX_EXT_B_BGA1-IC,TBD!!!F77!VSS(877)!!!!
S!GND!U5D1!AD43!@baseboard_fab2_lib.baseboard_fab2(sch_1):page40_i22@chpset_lib.skx_ext_b(chips)!SKX_EXT_B_BGA1-IC,TBD!!!F77!VSS(878)!!!!
S!GND!U5D1!AD39!@baseboard_fab2_lib.baseboard_fab2(sch_1):page40_i22@chpset_lib.skx_ext_b(chips)!SKX_EXT_B_BGA1-IC,TBD!!!F77!VSS(879)!!!!
S!GND!U5D1!AD33!@baseboard_fab2_lib.baseboard_fab2(sch_1):page40_i22@chpset_lib.skx_ext_b(chips)!SKX_EXT_B_BGA1-IC,TBD!!!F77!VSS(880)!!!!
S!GND!U5D1!AD27!@baseboard_fab2_lib.baseboard_fab2(sch_1):page40_i22@chpset_lib.skx_ext_b(chips)!SKX_EXT_B_BGA1-IC,TBD!!!F77!VSS(881)!!!!
S!GND!U5D1!AD21!@baseboard_fab2_lib.baseboard_fab2(sch_1):page40_i22@chpset_lib.skx_ext_b(chips)!SKX_EXT_B_BGA1-IC,TBD!!!F77!VSS(882)!!!!
S!GND!U5D1!AD19!@baseboard_fab2_lib.baseboard_fab2(sch_1):page40_i22@chpset_lib.skx_ext_b(chips)!SKX_EXT_B_BGA1-IC,TBD!!!F77!VSS(883)!!!!
S!GND!U5D1!AD15!@baseboard_fab2_lib.baseboard_fab2(sch_1):page40_i22@chpset_lib.skx_ext_b(chips)!SKX_EXT_B_BGA1-IC,TBD!!!F77!VSS(884)!!!!
S!GND!U5D1!AD13!@baseboard_fab2_lib.baseboard_fab2(sch_1):page40_i22@chpset_lib.skx_ext_b(chips)!SKX_EXT_B_BGA1-IC,TBD!!!F77!VSS(885)!!!!
S!GND!U5D1!AD11!@baseboard_fab2_lib.baseboard_fab2(sch_1):page40_i22@chpset_lib.skx_ext_b(chips)!SKX_EXT_B_BGA1-IC,TBD!!!F77!VSS(886)!!!!
S!GND!U5D1!AD9!@baseboard_fab2_lib.baseboard_fab2(sch_1):page40_i22@chpset_lib.skx_ext_b(chips)!SKX_EXT_B_BGA1-IC,TBD!!!F77!VSS(887)!!!!
S!GND!U5D1!AD7!@baseboard_fab2_lib.baseboard_fab2(sch_1):page40_i22@chpset_lib.skx_ext_b(chips)!SKX_EXT_B_BGA1-IC,TBD!!!F77!VSS(888)!!!!
S!GND!U5D1!AD3!@baseboard_fab2_lib.baseboard_fab2(sch_1):page40_i22@chpset_lib.skx_ext_b(chips)!SKX_EXT_B_BGA1-IC,TBD!!!F77!VSS(889)!!!!
S!GND!U5D1!AC86!@baseboard_fab2_lib.baseboard_fab2(sch_1):page40_i22@chpset_lib.skx_ext_b(chips)!SKX_EXT_B_BGA1-IC,TBD!!!F77!VSS(890)!!!!
S!GND!U5D1!AC84!@baseboard_fab2_lib.baseboard_fab2(sch_1):page40_i22@chpset_lib.skx_ext_b(chips)!SKX_EXT_B_BGA1-IC,TBD!!!F77!VSS(891)!!!!
S!GND!U5D1!AC78!@baseboard_fab2_lib.baseboard_fab2(sch_1):page40_i22@chpset_lib.skx_ext_b(chips)!SKX_EXT_B_BGA1-IC,TBD!!!F77!VSS(892)!!!!
S!GND!U5D1!AC72!@baseboard_fab2_lib.baseboard_fab2(sch_1):page40_i22@chpset_lib.skx_ext_b(chips)!SKX_EXT_B_BGA1-IC,TBD!!!F77!VSS(893)!!!!
S!GND!U5D1!AC70!@baseboard_fab2_lib.baseboard_fab2(sch_1):page40_i22@chpset_lib.skx_ext_b(chips)!SKX_EXT_B_BGA1-IC,TBD!!!F77!VSS(894)!!!!
S!GND!U5D1!AC64!@baseboard_fab2_lib.baseboard_fab2(sch_1):page40_i22@chpset_lib.skx_ext_b(chips)!SKX_EXT_B_BGA1-IC,TBD!!!F77!VSS(895)!!!!
S!GND!U5D1!AC40!@baseboard_fab2_lib.baseboard_fab2(sch_1):page40_i22@chpset_lib.skx_ext_b(chips)!SKX_EXT_B_BGA1-IC,TBD!!!F77!VSS(896)!!!!
S!GND!U5D1!AC38!@baseboard_fab2_lib.baseboard_fab2(sch_1):page40_i22@chpset_lib.skx_ext_b(chips)!SKX_EXT_B_BGA1-IC,TBD!!!F77!VSS(897)!!!!
S!GND!U5D1!AC34!@baseboard_fab2_lib.baseboard_fab2(sch_1):page40_i22@chpset_lib.skx_ext_b(chips)!SKX_EXT_B_BGA1-IC,TBD!!!F77!VSS(898)!!!!
S!GND!U5D1!AC32!@baseboard_fab2_lib.baseboard_fab2(sch_1):page40_i22@chpset_lib.skx_ext_b(chips)!SKX_EXT_B_BGA1-IC,TBD!!!F77!VSS(899)!!!!
S!GND!U5D1!AC28!@baseboard_fab2_lib.baseboard_fab2(sch_1):page40_i22@chpset_lib.skx_ext_b(chips)!SKX_EXT_B_BGA1-IC,TBD!!!F77!VSS(900)!!!!
S!GND!U5D1!AC26!@baseboard_fab2_lib.baseboard_fab2(sch_1):page40_i22@chpset_lib.skx_ext_b(chips)!SKX_EXT_B_BGA1-IC,TBD!!!F77!VSS(901)!!!!
S!GND!U5D1!AC22!@baseboard_fab2_lib.baseboard_fab2(sch_1):page40_i22@chpset_lib.skx_ext_b(chips)!SKX_EXT_B_BGA1-IC,TBD!!!F77!VSS(902)!!!!
S!GND!U5D1!AC18!@baseboard_fab2_lib.baseboard_fab2(sch_1):page40_i22@chpset_lib.skx_ext_b(chips)!SKX_EXT_B_BGA1-IC,TBD!!!F77!VSS(903)!!!!
S!GND!U5D1!AB85!@baseboard_fab2_lib.baseboard_fab2(sch_1):page40_i22@chpset_lib.skx_ext_b(chips)!SKX_EXT_B_BGA1-IC,TBD!!!F77!VSS(904)!!!!
S!GND!U5D1!AB83!@baseboard_fab2_lib.baseboard_fab2(sch_1):page40_i22@chpset_lib.skx_ext_b(chips)!SKX_EXT_B_BGA1-IC,TBD!!!F77!VSS(905)!!!!
S!GND!U5D1!AB79!@baseboard_fab2_lib.baseboard_fab2(sch_1):page40_i22@chpset_lib.skx_ext_b(chips)!SKX_EXT_B_BGA1-IC,TBD!!!F77!VSS(906)!!!!
S!GND!U5D1!AB73!@baseboard_fab2_lib.baseboard_fab2(sch_1):page40_i22@chpset_lib.skx_ext_b(chips)!SKX_EXT_B_BGA1-IC,TBD!!!F77!VSS(907)!!!!
S!GND!U5D1!BL70!@baseboard_fab2_lib.baseboard_fab2(sch_1):page41_i283@chpset_lib.skx_ext_b(chips)!SKX_EXT_B_BGA1-IC,TBD!!!F75!VSS(588)!!!!
S!GND!U5D1!BL68!@baseboard_fab2_lib.baseboard_fab2(sch_1):page41_i283@chpset_lib.skx_ext_b(chips)!SKX_EXT_B_BGA1-IC,TBD!!!F75!VSS(589)!!!!
S!GND!U5D1!BL66!@baseboard_fab2_lib.baseboard_fab2(sch_1):page41_i283@chpset_lib.skx_ext_b(chips)!SKX_EXT_B_BGA1-IC,TBD!!!F75!VSS(590)!!!!
S!GND!U5D1!BL64!@baseboard_fab2_lib.baseboard_fab2(sch_1):page41_i283@chpset_lib.skx_ext_b(chips)!SKX_EXT_B_BGA1-IC,TBD!!!F75!VSS(591)!!!!
S!GND!U5D1!BL24!@baseboard_fab2_lib.baseboard_fab2(sch_1):page41_i283@chpset_lib.skx_ext_b(chips)!SKX_EXT_B_BGA1-IC,TBD!!!F75!VSS(592)!!!!
S!GND!U5D1!BL22!@baseboard_fab2_lib.baseboard_fab2(sch_1):page41_i283@chpset_lib.skx_ext_b(chips)!SKX_EXT_B_BGA1-IC,TBD!!!F75!VSS(593)!!!!
S!GND!U5D1!P61!@baseboard_fab2_lib.baseboard_fab2(sch_1):page41_i283@chpset_lib.skx_ext_b(chips)!SKX_EXT_B_BGA1-IC,TBD!!!F75!VSS(594)!!!!
S!GND!U5D1!BL12!@baseboard_fab2_lib.baseboard_fab2(sch_1):page41_i283@chpset_lib.skx_ext_b(chips)!SKX_EXT_B_BGA1-IC,TBD!!!F75!VSS(595)!!!!
S!GND!U5D1!BL10!@baseboard_fab2_lib.baseboard_fab2(sch_1):page41_i283@chpset_lib.skx_ext_b(chips)!SKX_EXT_B_BGA1-IC,TBD!!!F75!VSS(596)!!!!
S!GND!U5D1!BL6!@baseboard_fab2_lib.baseboard_fab2(sch_1):page41_i283@chpset_lib.skx_ext_b(chips)!SKX_EXT_B_BGA1-IC,TBD!!!F75!VSS(597)!!!!
S!GND!U5D1!BK19!@baseboard_fab2_lib.baseboard_fab2(sch_1):page41_i283@chpset_lib.skx_ext_b(chips)!SKX_EXT_B_BGA1-IC,TBD!!!F75!VSS(598)!!!!
S!GND!U5D1!BK11!@baseboard_fab2_lib.baseboard_fab2(sch_1):page41_i283@chpset_lib.skx_ext_b(chips)!SKX_EXT_B_BGA1-IC,TBD!!!F75!VSS(599)!!!!
S!GND!U5D1!BK7!@baseboard_fab2_lib.baseboard_fab2(sch_1):page41_i283@chpset_lib.skx_ext_b(chips)!SKX_EXT_B_BGA1-IC,TBD!!!F75!VSS(600)!!!!
S!GND!U5D1!BK3!@baseboard_fab2_lib.baseboard_fab2(sch_1):page41_i283@chpset_lib.skx_ext_b(chips)!SKX_EXT_B_BGA1-IC,TBD!!!F75!VSS(601)!!!!
S!GND!U5D1!BJ6!@baseboard_fab2_lib.baseboard_fab2(sch_1):page41_i283@chpset_lib.skx_ext_b(chips)!SKX_EXT_B_BGA1-IC,TBD!!!F75!VSS(602)!!!!
S!GND!U5D1!BJ4!@baseboard_fab2_lib.baseboard_fab2(sch_1):page41_i283@chpset_lib.skx_ext_b(chips)!SKX_EXT_B_BGA1-IC,TBD!!!F75!VSS(603)!!!!
S!GND!U5D1!BH21!@baseboard_fab2_lib.baseboard_fab2(sch_1):page41_i283@chpset_lib.skx_ext_b(chips)!SKX_EXT_B_BGA1-IC,TBD!!!F75!VSS(604)!!!!
S!GND!U5D1!BH15!@baseboard_fab2_lib.baseboard_fab2(sch_1):page41_i283@chpset_lib.skx_ext_b(chips)!SKX_EXT_B_BGA1-IC,TBD!!!F75!VSS(605)!!!!
S!GND!U5D1!BH11!@baseboard_fab2_lib.baseboard_fab2(sch_1):page41_i283@chpset_lib.skx_ext_b(chips)!SKX_EXT_B_BGA1-IC,TBD!!!F75!VSS(606)!!!!
S!GND!U5D1!BH9!@baseboard_fab2_lib.baseboard_fab2(sch_1):page41_i283@chpset_lib.skx_ext_b(chips)!SKX_EXT_B_BGA1-IC,TBD!!!F75!VSS(607)!!!!
S!GND!U5D1!BH7!@baseboard_fab2_lib.baseboard_fab2(sch_1):page41_i283@chpset_lib.skx_ext_b(chips)!SKX_EXT_B_BGA1-IC,TBD!!!F75!VSS(608)!!!!
S!GND!U5D1!BG82!@baseboard_fab2_lib.baseboard_fab2(sch_1):page41_i283@chpset_lib.skx_ext_b(chips)!SKX_EXT_B_BGA1-IC,TBD!!!F75!VSS(609)!!!!
S!GND!U5D1!BG80!@baseboard_fab2_lib.baseboard_fab2(sch_1):page41_i283@chpset_lib.skx_ext_b(chips)!SKX_EXT_B_BGA1-IC,TBD!!!F75!VSS(610)!!!!
S!GND!U5D1!BG78!@baseboard_fab2_lib.baseboard_fab2(sch_1):page41_i283@chpset_lib.skx_ext_b(chips)!SKX_EXT_B_BGA1-IC,TBD!!!F75!VSS(611)!!!!
S!GND!U5D1!BG76!@baseboard_fab2_lib.baseboard_fab2(sch_1):page41_i283@chpset_lib.skx_ext_b(chips)!SKX_EXT_B_BGA1-IC,TBD!!!F75!VSS(612)!!!!
S!GND!U5D1!BG74!@baseboard_fab2_lib.baseboard_fab2(sch_1):page41_i283@chpset_lib.skx_ext_b(chips)!SKX_EXT_B_BGA1-IC,TBD!!!F75!VSS(613)!!!!
S!GND!U5D1!BG72!@baseboard_fab2_lib.baseboard_fab2(sch_1):page40_i23@chpset_lib.skx_ext_b(chips)!SKX_EXT_B_BGA1-IC,TBD!!!F76!VSS(614)!!!!
S!GND!U5D1!BG24!@baseboard_fab2_lib.baseboard_fab2(sch_1):page40_i23@chpset_lib.skx_ext_b(chips)!SKX_EXT_B_BGA1-IC,TBD!!!F76!VSS(615)!!!!
S!GND!U5D1!BG22!@baseboard_fab2_lib.baseboard_fab2(sch_1):page40_i23@chpset_lib.skx_ext_b(chips)!SKX_EXT_B_BGA1-IC,TBD!!!F76!VSS(616)!!!!
S!GND!U5D1!BG10!@baseboard_fab2_lib.baseboard_fab2(sch_1):page40_i23@chpset_lib.skx_ext_b(chips)!SKX_EXT_B_BGA1-IC,TBD!!!F76!VSS(617)!!!!
S!GND!U5D1!BG8!@baseboard_fab2_lib.baseboard_fab2(sch_1):page40_i23@chpset_lib.skx_ext_b(chips)!SKX_EXT_B_BGA1-IC,TBD!!!F76!VSS(618)!!!!
S!GND!U5D1!BG6!@baseboard_fab2_lib.baseboard_fab2(sch_1):page40_i23@chpset_lib.skx_ext_b(chips)!SKX_EXT_B_BGA1-IC,TBD!!!F76!VSS(619)!!!!
S!GND!U5D1!BF71!@baseboard_fab2_lib.baseboard_fab2(sch_1):page40_i23@chpset_lib.skx_ext_b(chips)!SKX_EXT_B_BGA1-IC,TBD!!!F76!VSS(620)!!!!
S!GND!U5D1!BF69!@baseboard_fab2_lib.baseboard_fab2(sch_1):page40_i23@chpset_lib.skx_ext_b(chips)!SKX_EXT_B_BGA1-IC,TBD!!!F76!VSS(621)!!!!
S!GND!U5D1!BF67!@baseboard_fab2_lib.baseboard_fab2(sch_1):page40_i23@chpset_lib.skx_ext_b(chips)!SKX_EXT_B_BGA1-IC,TBD!!!F76!VSS(622)!!!!
S!GND!U5D1!BF65!@baseboard_fab2_lib.baseboard_fab2(sch_1):page40_i23@chpset_lib.skx_ext_b(chips)!SKX_EXT_B_BGA1-IC,TBD!!!F76!VSS(623)!!!!
S!GND!U5D1!BF63!@baseboard_fab2_lib.baseboard_fab2(sch_1):page40_i23@chpset_lib.skx_ext_b(chips)!SKX_EXT_B_BGA1-IC,TBD!!!F76!VSS(624)!!!!
S!GND!U5D1!BF25!@baseboard_fab2_lib.baseboard_fab2(sch_1):page40_i23@chpset_lib.skx_ext_b(chips)!SKX_EXT_B_BGA1-IC,TBD!!!F76!VSS(625)!!!!
S!GND!U5D1!BF19!@baseboard_fab2_lib.baseboard_fab2(sch_1):page40_i23@chpset_lib.skx_ext_b(chips)!SKX_EXT_B_BGA1-IC,TBD!!!F76!VSS(626)!!!!
S!GND!U5D1!BF17!@baseboard_fab2_lib.baseboard_fab2(sch_1):page40_i23@chpset_lib.skx_ext_b(chips)!SKX_EXT_B_BGA1-IC,TBD!!!F76!VSS(627)!!!!
S!GND!U5D1!BF15!@baseboard_fab2_lib.baseboard_fab2(sch_1):page40_i23@chpset_lib.skx_ext_b(chips)!SKX_EXT_B_BGA1-IC,TBD!!!F76!VSS(628)!!!!
S!GND!U5D1!BF9!@baseboard_fab2_lib.baseboard_fab2(sch_1):page40_i23@chpset_lib.skx_ext_b(chips)!SKX_EXT_B_BGA1-IC,TBD!!!F76!VSS(629)!!!!
S!GND!U5D1!BE70!@baseboard_fab2_lib.baseboard_fab2(sch_1):page40_i23@chpset_lib.skx_ext_b(chips)!SKX_EXT_B_BGA1-IC,TBD!!!F76!VSS(630)!!!!
S!GND!U5D1!BE68!@baseboard_fab2_lib.baseboard_fab2(sch_1):page40_i23@chpset_lib.skx_ext_b(chips)!SKX_EXT_B_BGA1-IC,TBD!!!F76!VSS(631)!!!!
S!GND!U5D1!BE66!@baseboard_fab2_lib.baseboard_fab2(sch_1):page40_i23@chpset_lib.skx_ext_b(chips)!SKX_EXT_B_BGA1-IC,TBD!!!F76!VSS(632)!!!!
S!GND!U5D1!BE64!@baseboard_fab2_lib.baseboard_fab2(sch_1):page40_i23@chpset_lib.skx_ext_b(chips)!SKX_EXT_B_BGA1-IC,TBD!!!F76!VSS(633)!!!!
S!GND!U5D1!BE26!@baseboard_fab2_lib.baseboard_fab2(sch_1):page40_i23@chpset_lib.skx_ext_b(chips)!SKX_EXT_B_BGA1-IC,TBD!!!F76!VSS(634)!!!!
S!GND!U5D1!BE10!@baseboard_fab2_lib.baseboard_fab2(sch_1):page40_i23@chpset_lib.skx_ext_b(chips)!SKX_EXT_B_BGA1-IC,TBD!!!F76!VSS(635)!!!!
S!GND!U5D1!BE8!@baseboard_fab2_lib.baseboard_fab2(sch_1):page40_i23@chpset_lib.skx_ext_b(chips)!SKX_EXT_B_BGA1-IC,TBD!!!F76!VSS(636)!!!!
S!GND!U5D1!BE6!@baseboard_fab2_lib.baseboard_fab2(sch_1):page40_i23@chpset_lib.skx_ext_b(chips)!SKX_EXT_B_BGA1-IC,TBD!!!F76!VSS(637)!!!!
S!GND!U5D1!BE4!@baseboard_fab2_lib.baseboard_fab2(sch_1):page40_i23@chpset_lib.skx_ext_b(chips)!SKX_EXT_B_BGA1-IC,TBD!!!F76!VSS(638)!!!!
S!GND!U5D1!BD71!@baseboard_fab2_lib.baseboard_fab2(sch_1):page40_i23@chpset_lib.skx_ext_b(chips)!SKX_EXT_B_BGA1-IC,TBD!!!F76!VSS(639)!!!!
S!GND!U5D1!BD63!@baseboard_fab2_lib.baseboard_fab2(sch_1):page40_i23@chpset_lib.skx_ext_b(chips)!SKX_EXT_B_BGA1-IC,TBD!!!F76!VSS(640)!!!!
S!GND!U5D1!BD27!@baseboard_fab2_lib.baseboard_fab2(sch_1):page40_i23@chpset_lib.skx_ext_b(chips)!SKX_EXT_B_BGA1-IC,TBD!!!F76!VSS(641)!!!!
S!GND!U5D1!BD21!@baseboard_fab2_lib.baseboard_fab2(sch_1):page40_i23@chpset_lib.skx_ext_b(chips)!SKX_EXT_B_BGA1-IC,TBD!!!F76!VSS(642)!!!!
S!GND!U5D1!BD15!@baseboard_fab2_lib.baseboard_fab2(sch_1):page40_i23@chpset_lib.skx_ext_b(chips)!SKX_EXT_B_BGA1-IC,TBD!!!F76!VSS(643)!!!!
S!GND!U5D1!BD11!@baseboard_fab2_lib.baseboard_fab2(sch_1):page40_i23@chpset_lib.skx_ext_b(chips)!SKX_EXT_B_BGA1-IC,TBD!!!F76!VSS(644)!!!!
S!GND!U5D1!BD5!@baseboard_fab2_lib.baseboard_fab2(sch_1):page40_i23@chpset_lib.skx_ext_b(chips)!SKX_EXT_B_BGA1-IC,TBD!!!F76!VSS(645)!!!!
S!GND!U5D1!BC82!@baseboard_fab2_lib.baseboard_fab2(sch_1):page40_i23@chpset_lib.skx_ext_b(chips)!SKX_EXT_B_BGA1-IC,TBD!!!F76!VSS(646)!!!!
S!GND!U5D1!BC80!@baseboard_fab2_lib.baseboard_fab2(sch_1):page40_i23@chpset_lib.skx_ext_b(chips)!SKX_EXT_B_BGA1-IC,TBD!!!F76!VSS(647)!!!!
S!GND!U5D1!BC78!@baseboard_fab2_lib.baseboard_fab2(sch_1):page40_i23@chpset_lib.skx_ext_b(chips)!SKX_EXT_B_BGA1-IC,TBD!!!F76!VSS(648)!!!!
S!GND!U5D1!BC76!@baseboard_fab2_lib.baseboard_fab2(sch_1):page40_i23@chpset_lib.skx_ext_b(chips)!SKX_EXT_B_BGA1-IC,TBD!!!F76!VSS(649)!!!!
S!GND!U5D1!BC74!@baseboard_fab2_lib.baseboard_fab2(sch_1):page40_i23@chpset_lib.skx_ext_b(chips)!SKX_EXT_B_BGA1-IC,TBD!!!F76!VSS(650)!!!!
S!GND!U5D1!BC72!@baseboard_fab2_lib.baseboard_fab2(sch_1):page40_i23@chpset_lib.skx_ext_b(chips)!SKX_EXT_B_BGA1-IC,TBD!!!F76!VSS(651)!!!!
S!GND!U5D1!BC70!@baseboard_fab2_lib.baseboard_fab2(sch_1):page40_i23@chpset_lib.skx_ext_b(chips)!SKX_EXT_B_BGA1-IC,TBD!!!F76!VSS(652)!!!!
S!GND!U5D1!BC16!@baseboard_fab2_lib.baseboard_fab2(sch_1):page40_i23@chpset_lib.skx_ext_b(chips)!SKX_EXT_B_BGA1-IC,TBD!!!F76!VSS(653)!!!!
S!GND!U5D1!BC12!@baseboard_fab2_lib.baseboard_fab2(sch_1):page40_i23@chpset_lib.skx_ext_b(chips)!SKX_EXT_B_BGA1-IC,TBD!!!F76!VSS(654)!!!!
S!GND!U5D1!BC8!@baseboard_fab2_lib.baseboard_fab2(sch_1):page40_i23@chpset_lib.skx_ext_b(chips)!SKX_EXT_B_BGA1-IC,TBD!!!F76!VSS(655)!!!!
S!GND!U5D1!BC4!@baseboard_fab2_lib.baseboard_fab2(sch_1):page40_i23@chpset_lib.skx_ext_b(chips)!SKX_EXT_B_BGA1-IC,TBD!!!F76!VSS(656)!!!!
S!GND!U5D1!BB83!@baseboard_fab2_lib.baseboard_fab2(sch_1):page40_i23@chpset_lib.skx_ext_b(chips)!SKX_EXT_B_BGA1-IC,TBD!!!F76!VSS(657)!!!!
S!GND!U5D1!BB81!@baseboard_fab2_lib.baseboard_fab2(sch_1):page40_i23@chpset_lib.skx_ext_b(chips)!SKX_EXT_B_BGA1-IC,TBD!!!F76!VSS(658)!!!!
S!GND!U5D1!BB79!@baseboard_fab2_lib.baseboard_fab2(sch_1):page40_i23@chpset_lib.skx_ext_b(chips)!SKX_EXT_B_BGA1-IC,TBD!!!F76!VSS(659)!!!!
S!GND!U5D1!BB77!@baseboard_fab2_lib.baseboard_fab2(sch_1):page40_i23@chpset_lib.skx_ext_b(chips)!SKX_EXT_B_BGA1-IC,TBD!!!F76!VSS(660)!!!!
S!GND!U5D1!BB75!@baseboard_fab2_lib.baseboard_fab2(sch_1):page40_i23@chpset_lib.skx_ext_b(chips)!SKX_EXT_B_BGA1-IC,TBD!!!F76!VSS(661)!!!!
S!GND!U5D1!BB73!@baseboard_fab2_lib.baseboard_fab2(sch_1):page40_i23@chpset_lib.skx_ext_b(chips)!SKX_EXT_B_BGA1-IC,TBD!!!F76!VSS(662)!!!!
S!GND!U5D1!BB69!@baseboard_fab2_lib.baseboard_fab2(sch_1):page40_i23@chpset_lib.skx_ext_b(chips)!SKX_EXT_B_BGA1-IC,TBD!!!F76!VSS(663)!!!!
S!GND!U5D1!BB63!@baseboard_fab2_lib.baseboard_fab2(sch_1):page40_i23@chpset_lib.skx_ext_b(chips)!SKX_EXT_B_BGA1-IC,TBD!!!F76!VSS(664)!!!!
S!GND!U5D1!BB23!@baseboard_fab2_lib.baseboard_fab2(sch_1):page40_i23@chpset_lib.skx_ext_b(chips)!SKX_EXT_B_BGA1-IC,TBD!!!F76!VSS(665)!!!!
S!GND!U5D1!BB19!@baseboard_fab2_lib.baseboard_fab2(sch_1):page40_i23@chpset_lib.skx_ext_b(chips)!SKX_EXT_B_BGA1-IC,TBD!!!F76!VSS(666)!!!!
S!GND!U5D1!BA84!@baseboard_fab2_lib.baseboard_fab2(sch_1):page40_i23@chpset_lib.skx_ext_b(chips)!SKX_EXT_B_BGA1-IC,TBD!!!F76!VSS(667)!!!!
S!GND!U5D1!BA80!@baseboard_fab2_lib.baseboard_fab2(sch_1):page40_i23@chpset_lib.skx_ext_b(chips)!SKX_EXT_B_BGA1-IC,TBD!!!F76!VSS(668)!!!!
S!GND!U5D1!BA74!@baseboard_fab2_lib.baseboard_fab2(sch_1):page40_i23@chpset_lib.skx_ext_b(chips)!SKX_EXT_B_BGA1-IC,TBD!!!F76!VSS(669)!!!!
S!GND!U5D1!BA68!@baseboard_fab2_lib.baseboard_fab2(sch_1):page40_i23@chpset_lib.skx_ext_b(chips)!SKX_EXT_B_BGA1-IC,TBD!!!F76!VSS(670)!!!!
S!GND!U5D1!BA62!@baseboard_fab2_lib.baseboard_fab2(sch_1):page40_i23@chpset_lib.skx_ext_b(chips)!SKX_EXT_B_BGA1-IC,TBD!!!F76!VSS(671)!!!!
S!GND!U5D1!BA12!@baseboard_fab2_lib.baseboard_fab2(sch_1):page40_i23@chpset_lib.skx_ext_b(chips)!SKX_EXT_B_BGA1-IC,TBD!!!F76!VSS(672)!!!!
S!GND!U5D1!BA6!@baseboard_fab2_lib.baseboard_fab2(sch_1):page40_i23@chpset_lib.skx_ext_b(chips)!SKX_EXT_B_BGA1-IC,TBD!!!F76!VSS(673)!!!!
S!GND!U5D1!BA2!@baseboard_fab2_lib.baseboard_fab2(sch_1):page40_i23@chpset_lib.skx_ext_b(chips)!SKX_EXT_B_BGA1-IC,TBD!!!F76!VSS(674)!!!!
S!GND!U5D1!AY81!@baseboard_fab2_lib.baseboard_fab2(sch_1):page40_i23@chpset_lib.skx_ext_b(chips)!SKX_EXT_B_BGA1-IC,TBD!!!F76!VSS(675)!!!!
S!GND!U5D1!AY79!@baseboard_fab2_lib.baseboard_fab2(sch_1):page40_i23@chpset_lib.skx_ext_b(chips)!SKX_EXT_B_BGA1-IC,TBD!!!F76!VSS(676)!!!!
S!GND!U5D1!AY63!@baseboard_fab2_lib.baseboard_fab2(sch_1):page40_i23@chpset_lib.skx_ext_b(chips)!SKX_EXT_B_BGA1-IC,TBD!!!F76!VSS(677)!!!!
S!GND!U5D1!AY25!@baseboard_fab2_lib.baseboard_fab2(sch_1):page40_i23@chpset_lib.skx_ext_b(chips)!SKX_EXT_B_BGA1-IC,TBD!!!F76!VSS(678)!!!!
S!GND!U5D1!AY23!@baseboard_fab2_lib.baseboard_fab2(sch_1):page40_i23@chpset_lib.skx_ext_b(chips)!SKX_EXT_B_BGA1-IC,TBD!!!F76!VSS(679)!!!!
S!GND!U5D1!AY21!@baseboard_fab2_lib.baseboard_fab2(sch_1):page40_i23@chpset_lib.skx_ext_b(chips)!SKX_EXT_B_BGA1-IC,TBD!!!F76!VSS(680)!!!!
S!GND!U5D1!AY17!@baseboard_fab2_lib.baseboard_fab2(sch_1):page40_i23@chpset_lib.skx_ext_b(chips)!SKX_EXT_B_BGA1-IC,TBD!!!F76!VSS(681)!!!!
S!GND!U5D1!AY15!@baseboard_fab2_lib.baseboard_fab2(sch_1):page40_i23@chpset_lib.skx_ext_b(chips)!SKX_EXT_B_BGA1-IC,TBD!!!F76!VSS(682)!!!!
S!GND!U5D1!AY5!@baseboard_fab2_lib.baseboard_fab2(sch_1):page40_i23@chpset_lib.skx_ext_b(chips)!SKX_EXT_B_BGA1-IC,TBD!!!F76!VSS(683)!!!!
S!GND!U5D1!AW84!@baseboard_fab2_lib.baseboard_fab2(sch_1):page40_i23@chpset_lib.skx_ext_b(chips)!SKX_EXT_B_BGA1-IC,TBD!!!F76!VSS(684)!!!!
S!GND!U5D1!AW82!@baseboard_fab2_lib.baseboard_fab2(sch_1):page40_i23@chpset_lib.skx_ext_b(chips)!SKX_EXT_B_BGA1-IC,TBD!!!F76!VSS(685)!!!!
S!GND!U5D1!AW78!@baseboard_fab2_lib.baseboard_fab2(sch_1):page40_i23@chpset_lib.skx_ext_b(chips)!SKX_EXT_B_BGA1-IC,TBD!!!F76!VSS(686)!!!!
S!GND!U5D1!AW74!@baseboard_fab2_lib.baseboard_fab2(sch_1):page40_i23@chpset_lib.skx_ext_b(chips)!SKX_EXT_B_BGA1-IC,TBD!!!F76!VSS(687)!!!!
S!GND!U5D1!AW72!@baseboard_fab2_lib.baseboard_fab2(sch_1):page40_i23@chpset_lib.skx_ext_b(chips)!SKX_EXT_B_BGA1-IC,TBD!!!F76!VSS(688)!!!!
S!GND!U5D1!AW70!@baseboard_fab2_lib.baseboard_fab2(sch_1):page40_i23@chpset_lib.skx_ext_b(chips)!SKX_EXT_B_BGA1-IC,TBD!!!F76!VSS(689)!!!!
S!GND!U5D1!AW68!@baseboard_fab2_lib.baseboard_fab2(sch_1):page40_i23@chpset_lib.skx_ext_b(chips)!SKX_EXT_B_BGA1-IC,TBD!!!F76!VSS(690)!!!!
S!GND!U5D1!AW66!@baseboard_fab2_lib.baseboard_fab2(sch_1):page40_i23@chpset_lib.skx_ext_b(chips)!SKX_EXT_B_BGA1-IC,TBD!!!F76!VSS(691)!!!!
S!GND!U5D1!AW62!@baseboard_fab2_lib.baseboard_fab2(sch_1):page40_i23@chpset_lib.skx_ext_b(chips)!SKX_EXT_B_BGA1-IC,TBD!!!F76!VSS(692)!!!!
S!GND!U5D1!AW10!@baseboard_fab2_lib.baseboard_fab2(sch_1):page40_i23@chpset_lib.skx_ext_b(chips)!SKX_EXT_B_BGA1-IC,TBD!!!F76!VSS(693)!!!!
S!GND!U5D1!AW2!@baseboard_fab2_lib.baseboard_fab2(sch_1):page40_i23@chpset_lib.skx_ext_b(chips)!SKX_EXT_B_BGA1-IC,TBD!!!F76!VSS(694)!!!!
S!GND!U5D1!AV83!@baseboard_fab2_lib.baseboard_fab2(sch_1):page40_i23@chpset_lib.skx_ext_b(chips)!SKX_EXT_B_BGA1-IC,TBD!!!F76!VSS(695)!!!!
S!GND!U5D1!AV75!@baseboard_fab2_lib.baseboard_fab2(sch_1):page40_i23@chpset_lib.skx_ext_b(chips)!SKX_EXT_B_BGA1-IC,TBD!!!F76!VSS(696)!!!!
S!GND!U5D1!AV67!@baseboard_fab2_lib.baseboard_fab2(sch_1):page40_i23@chpset_lib.skx_ext_b(chips)!SKX_EXT_B_BGA1-IC,TBD!!!F76!VSS(697)!!!!
S!GND!U5D1!AV65!@baseboard_fab2_lib.baseboard_fab2(sch_1):page40_i23@chpset_lib.skx_ext_b(chips)!SKX_EXT_B_BGA1-IC,TBD!!!F76!VSS(698)!!!!
S!GND!U5D1!AV63!@baseboard_fab2_lib.baseboard_fab2(sch_1):page40_i23@chpset_lib.skx_ext_b(chips)!SKX_EXT_B_BGA1-IC,TBD!!!F76!VSS(699)!!!!
S!GND!U5D1!AV25!@baseboard_fab2_lib.baseboard_fab2(sch_1):page40_i23@chpset_lib.skx_ext_b(chips)!SKX_EXT_B_BGA1-IC,TBD!!!F76!VSS(700)!!!!
S!GND!U5D1!AV23!@baseboard_fab2_lib.baseboard_fab2(sch_1):page40_i23@chpset_lib.skx_ext_b(chips)!SKX_EXT_B_BGA1-IC,TBD!!!F76!VSS(701)!!!!
S!GND!U5D1!AV19!@baseboard_fab2_lib.baseboard_fab2(sch_1):page40_i23@chpset_lib.skx_ext_b(chips)!SKX_EXT_B_BGA1-IC,TBD!!!F76!VSS(702)!!!!
S!GND!U5D1!AV13!@baseboard_fab2_lib.baseboard_fab2(sch_1):page40_i23@chpset_lib.skx_ext_b(chips)!SKX_EXT_B_BGA1-IC,TBD!!!F76!VSS(703)!!!!
S!GND!U5D1!AV11!@baseboard_fab2_lib.baseboard_fab2(sch_1):page40_i23@chpset_lib.skx_ext_b(chips)!SKX_EXT_B_BGA1-IC,TBD!!!F76!VSS(704)!!!!
S!GND!U5D1!AV7!@baseboard_fab2_lib.baseboard_fab2(sch_1):page40_i23@chpset_lib.skx_ext_b(chips)!SKX_EXT_B_BGA1-IC,TBD!!!F76!VSS(705)!!!!
S!GND!U5D1!AV3!@baseboard_fab2_lib.baseboard_fab2(sch_1):page40_i23@chpset_lib.skx_ext_b(chips)!SKX_EXT_B_BGA1-IC,TBD!!!F76!VSS(706)!!!!
S!GND!U5D1!AV1!@baseboard_fab2_lib.baseboard_fab2(sch_1):page40_i23@chpset_lib.skx_ext_b(chips)!SKX_EXT_B_BGA1-IC,TBD!!!F76!VSS(707)!!!!
S!GND!U5D1!AU86!@baseboard_fab2_lib.baseboard_fab2(sch_1):page40_i23@chpset_lib.skx_ext_b(chips)!SKX_EXT_B_BGA1-IC,TBD!!!F76!VSS(708)!!!!
S!GND!U5D1!AU84!@baseboard_fab2_lib.baseboard_fab2(sch_1):page40_i23@chpset_lib.skx_ext_b(chips)!SKX_EXT_B_BGA1-IC,TBD!!!F76!VSS(709)!!!!
S!GND!U5D1!AU80!@baseboard_fab2_lib.baseboard_fab2(sch_1):page40_i23@chpset_lib.skx_ext_b(chips)!SKX_EXT_B_BGA1-IC,TBD!!!F76!VSS(710)!!!!
S!GND!U5D1!AU78!@baseboard_fab2_lib.baseboard_fab2(sch_1):page40_i23@chpset_lib.skx_ext_b(chips)!SKX_EXT_B_BGA1-IC,TBD!!!F76!VSS(711)!!!!
S!GND!U5D1!AU76!@baseboard_fab2_lib.baseboard_fab2(sch_1):page40_i23@chpset_lib.skx_ext_b(chips)!SKX_EXT_B_BGA1-IC,TBD!!!F76!VSS(712)!!!!
S!GND!U5D1!AU74!@baseboard_fab2_lib.baseboard_fab2(sch_1):page40_i23@chpset_lib.skx_ext_b(chips)!SKX_EXT_B_BGA1-IC,TBD!!!F76!VSS(713)!!!!
S!GND!U5D1!AU68!@baseboard_fab2_lib.baseboard_fab2(sch_1):page40_i23@chpset_lib.skx_ext_b(chips)!SKX_EXT_B_BGA1-IC,TBD!!!F76!VSS(714)!!!!
S!GND!U5D1!AU64!@baseboard_fab2_lib.baseboard_fab2(sch_1):page40_i23@chpset_lib.skx_ext_b(chips)!SKX_EXT_B_BGA1-IC,TBD!!!F76!VSS(715)!!!!
S!GND!U5D1!AU62!@baseboard_fab2_lib.baseboard_fab2(sch_1):page40_i23@chpset_lib.skx_ext_b(chips)!SKX_EXT_B_BGA1-IC,TBD!!!F76!VSS(716)!!!!
S!GND!U5D1!AU28!@baseboard_fab2_lib.baseboard_fab2(sch_1):page40_i23@chpset_lib.skx_ext_b(chips)!SKX_EXT_B_BGA1-IC,TBD!!!F76!VSS(717)!!!!
S!GND!U5D1!AU26!@baseboard_fab2_lib.baseboard_fab2(sch_1):page40_i23@chpset_lib.skx_ext_b(chips)!SKX_EXT_B_BGA1-IC,TBD!!!F76!VSS(718)!!!!
S!GND!U5D1!AU6!@baseboard_fab2_lib.baseboard_fab2(sch_1):page40_i23@chpset_lib.skx_ext_b(chips)!SKX_EXT_B_BGA1-IC,TBD!!!F76!VSS(719)!!!!
S!GND!U5D1!AU2!@baseboard_fab2_lib.baseboard_fab2(sch_1):page40_i23@chpset_lib.skx_ext_b(chips)!SKX_EXT_B_BGA1-IC,TBD!!!F76!VSS(720)!!!!
S!GND!U5D1!AT85!@baseboard_fab2_lib.baseboard_fab2(sch_1):page40_i23@chpset_lib.skx_ext_b(chips)!SKX_EXT_B_BGA1-IC,TBD!!!F76!VSS(721)!!!!
S!GND!U5D1!AT83!@baseboard_fab2_lib.baseboard_fab2(sch_1):page40_i23@chpset_lib.skx_ext_b(chips)!SKX_EXT_B_BGA1-IC,TBD!!!F76!VSS(722)!!!!
S!GND!U5D1!AT77!@baseboard_fab2_lib.baseboard_fab2(sch_1):page40_i23@chpset_lib.skx_ext_b(chips)!SKX_EXT_B_BGA1-IC,TBD!!!F76!VSS(723)!!!!
S!GND!U5D1!AT73!@baseboard_fab2_lib.baseboard_fab2(sch_1):page40_i23@chpset_lib.skx_ext_b(chips)!SKX_EXT_B_BGA1-IC,TBD!!!F76!VSS(724)!!!!
S!GND!U5D1!AT69!@baseboard_fab2_lib.baseboard_fab2(sch_1):page40_i23@chpset_lib.skx_ext_b(chips)!SKX_EXT_B_BGA1-IC,TBD!!!F76!VSS(725)!!!!
S!GND!U5D1!AT63!@baseboard_fab2_lib.baseboard_fab2(sch_1):page40_i23@chpset_lib.skx_ext_b(chips)!SKX_EXT_B_BGA1-IC,TBD!!!F76!VSS(726)!!!!
S!GND!U5D1!AT61!@baseboard_fab2_lib.baseboard_fab2(sch_1):page40_i23@chpset_lib.skx_ext_b(chips)!SKX_EXT_B_BGA1-IC,TBD!!!F76!VSS(727)!!!!
S!GND!U5D1!AT27!@baseboard_fab2_lib.baseboard_fab2(sch_1):page40_i23@chpset_lib.skx_ext_b(chips)!SKX_EXT_B_BGA1-IC,TBD!!!F76!VSS(728)!!!!
S!GND!U5D1!AT21!@baseboard_fab2_lib.baseboard_fab2(sch_1):page40_i23@chpset_lib.skx_ext_b(chips)!SKX_EXT_B_BGA1-IC,TBD!!!F76!VSS(729)!!!!
S!GND!U5D1!AT17!@baseboard_fab2_lib.baseboard_fab2(sch_1):page40_i23@chpset_lib.skx_ext_b(chips)!SKX_EXT_B_BGA1-IC,TBD!!!F76!VSS(730)!!!!
S!GND!U5D1!AT15!@baseboard_fab2_lib.baseboard_fab2(sch_1):page40_i23@chpset_lib.skx_ext_b(chips)!SKX_EXT_B_BGA1-IC,TBD!!!F76!VSS(731)!!!!
S!GND!U5D1!P63!@baseboard_fab2_lib.baseboard_fab2(sch_1):page40_i23@chpset_lib.skx_ext_b(chips)!SKX_EXT_B_BGA1-IC,TBD!!!F76!VSS(732)!!!!
S!GND!U5D1!AC48!@baseboard_fab2_lib.baseboard_fab2(sch_1):page40_i23@chpset_lib.skx_ext_b(chips)!SKX_EXT_B_BGA1-IC,TBD!!!F76!VSS(733)!!!!
S!GND!U5D1!AR78!@baseboard_fab2_lib.baseboard_fab2(sch_1):page40_i23@chpset_lib.skx_ext_b(chips)!SKX_EXT_B_BGA1-IC,TBD!!!F76!VSS(734)!!!!
S!GND!U5D1!AR72!@baseboard_fab2_lib.baseboard_fab2(sch_1):page40_i23@chpset_lib.skx_ext_b(chips)!SKX_EXT_B_BGA1-IC,TBD!!!F76!VSS(735)!!!!
S!GND!U5D1!AR60!@baseboard_fab2_lib.baseboard_fab2(sch_1):page40_i23@chpset_lib.skx_ext_b(chips)!SKX_EXT_B_BGA1-IC,TBD!!!F76!VSS(736)!!!!
S!GND!U5D1!AR30!@baseboard_fab2_lib.baseboard_fab2(sch_1):page40_i23@chpset_lib.skx_ext_b(chips)!SKX_EXT_B_BGA1-IC,TBD!!!F76!VSS(737)!!!!
S!GND!U5D1!AR24!@baseboard_fab2_lib.baseboard_fab2(sch_1):page40_i23@chpset_lib.skx_ext_b(chips)!SKX_EXT_B_BGA1-IC,TBD!!!F76!VSS(738)!!!!
S!GND!U5D1!AR10!@baseboard_fab2_lib.baseboard_fab2(sch_1):page40_i23@chpset_lib.skx_ext_b(chips)!SKX_EXT_B_BGA1-IC,TBD!!!F76!VSS(739)!!!!
S!GND!U5D1!AP85!@baseboard_fab2_lib.baseboard_fab2(sch_1):page40_i23@chpset_lib.skx_ext_b(chips)!SKX_EXT_B_BGA1-IC,TBD!!!F76!VSS(740)!!!!
S!GND!U5D1!AP83!@baseboard_fab2_lib.baseboard_fab2(sch_1):page40_i23@chpset_lib.skx_ext_b(chips)!SKX_EXT_B_BGA1-IC,TBD!!!F76!VSS(741)!!!!
S!GND!U5D1!AP81!@baseboard_fab2_lib.baseboard_fab2(sch_1):page40_i23@chpset_lib.skx_ext_b(chips)!SKX_EXT_B_BGA1-IC,TBD!!!F76!VSS(742)!!!!
S!GND!U5D1!AP75!@baseboard_fab2_lib.baseboard_fab2(sch_1):page40_i23@chpset_lib.skx_ext_b(chips)!SKX_EXT_B_BGA1-IC,TBD!!!F76!VSS(743)!!!!
S!GND!U5D1!AP73!@baseboard_fab2_lib.baseboard_fab2(sch_1):page40_i23@chpset_lib.skx_ext_b(chips)!SKX_EXT_B_BGA1-IC,TBD!!!F76!VSS(744)!!!!
S!GND!U5D1!AP69!@baseboard_fab2_lib.baseboard_fab2(sch_1):page40_i23@chpset_lib.skx_ext_b(chips)!SKX_EXT_B_BGA1-IC,TBD!!!F76!VSS(745)!!!!
S!GND!U5D1!AP67!@baseboard_fab2_lib.baseboard_fab2(sch_1):page40_i23@chpset_lib.skx_ext_b(chips)!SKX_EXT_B_BGA1-IC,TBD!!!F76!VSS(746)!!!!
S!GND!U5D1!AP65!@baseboard_fab2_lib.baseboard_fab2(sch_1):page40_i23@chpset_lib.skx_ext_b(chips)!SKX_EXT_B_BGA1-IC,TBD!!!F76!VSS(747)!!!!
S!GND!U5D1!H63!@baseboard_fab2_lib.baseboard_fab2(sch_1):page41_i284@chpset_lib.skx_ext_b(chips)!SKX_EXT_B_BGA1-IC,TBD!!!F74!VSS(428)!!!!
S!GND!U5D1!P45!@baseboard_fab2_lib.baseboard_fab2(sch_1):page41_i284@chpset_lib.skx_ext_b(chips)!SKX_EXT_B_BGA1-IC,TBD!!!F74!VSS(429)!!!!
S!GND!U5D1!CL18!@baseboard_fab2_lib.baseboard_fab2(sch_1):page41_i284@chpset_lib.skx_ext_b(chips)!SKX_EXT_B_BGA1-IC,TBD!!!F74!VSS(430)!!!!
S!GND!U5D1!CL14!@baseboard_fab2_lib.baseboard_fab2(sch_1):page41_i284@chpset_lib.skx_ext_b(chips)!SKX_EXT_B_BGA1-IC,TBD!!!F74!VSS(431)!!!!
S!GND!U5D1!CL8!@baseboard_fab2_lib.baseboard_fab2(sch_1):page41_i284@chpset_lib.skx_ext_b(chips)!SKX_EXT_B_BGA1-IC,TBD!!!F74!VSS(432)!!!!
S!GND!U5D1!CK85!@baseboard_fab2_lib.baseboard_fab2(sch_1):page41_i284@chpset_lib.skx_ext_b(chips)!SKX_EXT_B_BGA1-IC,TBD!!!F74!VSS(433)!!!!
S!GND!U5D1!CK83!@baseboard_fab2_lib.baseboard_fab2(sch_1):page41_i284@chpset_lib.skx_ext_b(chips)!SKX_EXT_B_BGA1-IC,TBD!!!F74!VSS(434)!!!!
S!GND!U5D1!CK75!@baseboard_fab2_lib.baseboard_fab2(sch_1):page41_i284@chpset_lib.skx_ext_b(chips)!SKX_EXT_B_BGA1-IC,TBD!!!F74!VSS(435)!!!!
S!GND!U5D1!CK73!@baseboard_fab2_lib.baseboard_fab2(sch_1):page41_i284@chpset_lib.skx_ext_b(chips)!SKX_EXT_B_BGA1-IC,TBD!!!F74!VSS(436)!!!!
S!GND!U5D1!CK71!@baseboard_fab2_lib.baseboard_fab2(sch_1):page41_i284@chpset_lib.skx_ext_b(chips)!SKX_EXT_B_BGA1-IC,TBD!!!F74!VSS(437)!!!!
S!GND!U5D1!CK69!@baseboard_fab2_lib.baseboard_fab2(sch_1):page41_i284@chpset_lib.skx_ext_b(chips)!SKX_EXT_B_BGA1-IC,TBD!!!F74!VSS(438)!!!!
S!GND!U5D1!CK67!@baseboard_fab2_lib.baseboard_fab2(sch_1):page41_i284@chpset_lib.skx_ext_b(chips)!SKX_EXT_B_BGA1-IC,TBD!!!F74!VSS(439)!!!!
S!GND!U5D1!CK65!@baseboard_fab2_lib.baseboard_fab2(sch_1):page41_i284@chpset_lib.skx_ext_b(chips)!SKX_EXT_B_BGA1-IC,TBD!!!F74!VSS(440)!!!!
S!GND!U5D1!CK63!@baseboard_fab2_lib.baseboard_fab2(sch_1):page41_i284@chpset_lib.skx_ext_b(chips)!SKX_EXT_B_BGA1-IC,TBD!!!F74!VSS(441)!!!!
S!GND!U5D1!CK27!@baseboard_fab2_lib.baseboard_fab2(sch_1):page41_i284@chpset_lib.skx_ext_b(chips)!SKX_EXT_B_BGA1-IC,TBD!!!F74!VSS(442)!!!!
S!GND!U5D1!CK21!@baseboard_fab2_lib.baseboard_fab2(sch_1):page41_i284@chpset_lib.skx_ext_b(chips)!SKX_EXT_B_BGA1-IC,TBD!!!F74!VSS(443)!!!!
S!GND!U5D1!CK15!@baseboard_fab2_lib.baseboard_fab2(sch_1):page41_i284@chpset_lib.skx_ext_b(chips)!SKX_EXT_B_BGA1-IC,TBD!!!F74!VSS(444)!!!!
S!GND!U5D1!CK11!@baseboard_fab2_lib.baseboard_fab2(sch_1):page41_i284@chpset_lib.skx_ext_b(chips)!SKX_EXT_B_BGA1-IC,TBD!!!F74!VSS(445)!!!!
S!GND!U5D1!CJ86!@baseboard_fab2_lib.baseboard_fab2(sch_1):page41_i284@chpset_lib.skx_ext_b(chips)!SKX_EXT_B_BGA1-IC,TBD!!!F74!VSS(446)!!!!
S!GND!U5D1!CJ84!@baseboard_fab2_lib.baseboard_fab2(sch_1):page41_i284@chpset_lib.skx_ext_b(chips)!SKX_EXT_B_BGA1-IC,TBD!!!F74!VSS(447)!!!!
S!GND!U5D1!CJ82!@baseboard_fab2_lib.baseboard_fab2(sch_1):page41_i284@chpset_lib.skx_ext_b(chips)!SKX_EXT_B_BGA1-IC,TBD!!!F74!VSS(448)!!!!
S!GND!U5D1!CJ78!@baseboard_fab2_lib.baseboard_fab2(sch_1):page41_i284@chpset_lib.skx_ext_b(chips)!SKX_EXT_B_BGA1-IC,TBD!!!F74!VSS(449)!!!!
S!GND!U5D1!CJ76!@baseboard_fab2_lib.baseboard_fab2(sch_1):page41_i284@chpset_lib.skx_ext_b(chips)!SKX_EXT_B_BGA1-IC,TBD!!!F74!VSS(450)!!!!
S!GND!U5D1!CJ74!@baseboard_fab2_lib.baseboard_fab2(sch_1):page41_i284@chpset_lib.skx_ext_b(chips)!SKX_EXT_B_BGA1-IC,TBD!!!F74!VSS(451)!!!!
S!GND!U5D1!CJ62!@baseboard_fab2_lib.baseboard_fab2(sch_1):page41_i284@chpset_lib.skx_ext_b(chips)!SKX_EXT_B_BGA1-IC,TBD!!!F74!VSS(452)!!!!
S!GND!U5D1!P47!@baseboard_fab2_lib.baseboard_fab2(sch_1):page41_i284@chpset_lib.skx_ext_b(chips)!SKX_EXT_B_BGA1-IC,TBD!!!F74!VSS(453)!!!!
S!GND!U5D1!P49!@baseboard_fab2_lib.baseboard_fab2(sch_1):page41_i283@chpset_lib.skx_ext_b(chips)!SKX_EXT_B_BGA1-IC,TBD!!!F75!VSS(454)!!!!
S!GND!U5D1!CJ12!@baseboard_fab2_lib.baseboard_fab2(sch_1):page41_i283@chpset_lib.skx_ext_b(chips)!SKX_EXT_B_BGA1-IC,TBD!!!F75!VSS(455)!!!!
S!GND!U5D1!CJ10!@baseboard_fab2_lib.baseboard_fab2(sch_1):page41_i283@chpset_lib.skx_ext_b(chips)!SKX_EXT_B_BGA1-IC,TBD!!!F75!VSS(456)!!!!
S!GND!U5D1!CJ8!@baseboard_fab2_lib.baseboard_fab2(sch_1):page41_i283@chpset_lib.skx_ext_b(chips)!SKX_EXT_B_BGA1-IC,TBD!!!F75!VSS(457)!!!!
S!GND!U5D1!CJ6!@baseboard_fab2_lib.baseboard_fab2(sch_1):page41_i283@chpset_lib.skx_ext_b(chips)!SKX_EXT_B_BGA1-IC,TBD!!!F75!VSS(458)!!!!
S!GND!U5D1!CJ2!@baseboard_fab2_lib.baseboard_fab2(sch_1):page41_i283@chpset_lib.skx_ext_b(chips)!SKX_EXT_B_BGA1-IC,TBD!!!F75!VSS(459)!!!!
S!GND!U5D1!CH83!@baseboard_fab2_lib.baseboard_fab2(sch_1):page41_i283@chpset_lib.skx_ext_b(chips)!SKX_EXT_B_BGA1-IC,TBD!!!F75!VSS(460)!!!!
S!GND!U5D1!CH81!@baseboard_fab2_lib.baseboard_fab2(sch_1):page41_i283@chpset_lib.skx_ext_b(chips)!SKX_EXT_B_BGA1-IC,TBD!!!F75!VSS(461)!!!!
S!GND!U5D1!CH79!@baseboard_fab2_lib.baseboard_fab2(sch_1):page41_i283@chpset_lib.skx_ext_b(chips)!SKX_EXT_B_BGA1-IC,TBD!!!F75!VSS(462)!!!!
S!GND!U5D1!CH73!@baseboard_fab2_lib.baseboard_fab2(sch_1):page41_i283@chpset_lib.skx_ext_b(chips)!SKX_EXT_B_BGA1-IC,TBD!!!F75!VSS(463)!!!!
S!GND!U5D1!CH67!@baseboard_fab2_lib.baseboard_fab2(sch_1):page41_i283@chpset_lib.skx_ext_b(chips)!SKX_EXT_B_BGA1-IC,TBD!!!F75!VSS(464)!!!!
S!GND!U5D1!CH63!@baseboard_fab2_lib.baseboard_fab2(sch_1):page41_i283@chpset_lib.skx_ext_b(chips)!SKX_EXT_B_BGA1-IC,TBD!!!F75!VSS(465)!!!!
S!GND!U5D1!CH19!@baseboard_fab2_lib.baseboard_fab2(sch_1):page41_i283@chpset_lib.skx_ext_b(chips)!SKX_EXT_B_BGA1-IC,TBD!!!F75!VSS(466)!!!!
S!GND!U5D1!CH15!@baseboard_fab2_lib.baseboard_fab2(sch_1):page41_i283@chpset_lib.skx_ext_b(chips)!SKX_EXT_B_BGA1-IC,TBD!!!F75!VSS(467)!!!!
S!GND!U5D1!CH3!@baseboard_fab2_lib.baseboard_fab2(sch_1):page41_i283@chpset_lib.skx_ext_b(chips)!SKX_EXT_B_BGA1-IC,TBD!!!F75!VSS(468)!!!!
S!GND!U5D1!CH1!@baseboard_fab2_lib.baseboard_fab2(sch_1):page41_i283@chpset_lib.skx_ext_b(chips)!SKX_EXT_B_BGA1-IC,TBD!!!F75!VSS(469)!!!!
S!GND!U5D1!CG80!@baseboard_fab2_lib.baseboard_fab2(sch_1):page41_i283@chpset_lib.skx_ext_b(chips)!SKX_EXT_B_BGA1-IC,TBD!!!F75!VSS(470)!!!!
S!GND!U5D1!CG72!@baseboard_fab2_lib.baseboard_fab2(sch_1):page41_i283@chpset_lib.skx_ext_b(chips)!SKX_EXT_B_BGA1-IC,TBD!!!F75!VSS(471)!!!!
S!GND!U5D1!CG68!@baseboard_fab2_lib.baseboard_fab2(sch_1):page41_i283@chpset_lib.skx_ext_b(chips)!SKX_EXT_B_BGA1-IC,TBD!!!F75!VSS(472)!!!!
S!GND!U5D1!CG62!@baseboard_fab2_lib.baseboard_fab2(sch_1):page41_i283@chpset_lib.skx_ext_b(chips)!SKX_EXT_B_BGA1-IC,TBD!!!F75!VSS(473)!!!!
S!GND!U5D1!CG22!@baseboard_fab2_lib.baseboard_fab2(sch_1):page41_i283@chpset_lib.skx_ext_b(chips)!SKX_EXT_B_BGA1-IC,TBD!!!F75!VSS(474)!!!!
S!GND!U5D1!CG18!@baseboard_fab2_lib.baseboard_fab2(sch_1):page41_i283@chpset_lib.skx_ext_b(chips)!SKX_EXT_B_BGA1-IC,TBD!!!F75!VSS(475)!!!!
S!GND!U5D1!P51!@baseboard_fab2_lib.baseboard_fab2(sch_1):page41_i283@chpset_lib.skx_ext_b(chips)!SKX_EXT_B_BGA1-IC,TBD!!!F75!VSS(476)!!!!
S!GND!U5D1!CF83!@baseboard_fab2_lib.baseboard_fab2(sch_1):page41_i283@chpset_lib.skx_ext_b(chips)!SKX_EXT_B_BGA1-IC,TBD!!!F75!VSS(477)!!!!
S!GND!U5D1!CF77!@baseboard_fab2_lib.baseboard_fab2(sch_1):page41_i283@chpset_lib.skx_ext_b(chips)!SKX_EXT_B_BGA1-IC,TBD!!!F75!VSS(478)!!!!
S!GND!U5D1!CF71!@baseboard_fab2_lib.baseboard_fab2(sch_1):page41_i283@chpset_lib.skx_ext_b(chips)!SKX_EXT_B_BGA1-IC,TBD!!!F75!VSS(479)!!!!
S!GND!U5D1!CF69!@baseboard_fab2_lib.baseboard_fab2(sch_1):page41_i283@chpset_lib.skx_ext_b(chips)!SKX_EXT_B_BGA1-IC,TBD!!!F75!VSS(480)!!!!
S!GND!U5D1!CF63!@baseboard_fab2_lib.baseboard_fab2(sch_1):page41_i283@chpset_lib.skx_ext_b(chips)!SKX_EXT_B_BGA1-IC,TBD!!!F75!VSS(481)!!!!
S!GND!U5D1!CF9!@baseboard_fab2_lib.baseboard_fab2(sch_1):page41_i283@chpset_lib.skx_ext_b(chips)!SKX_EXT_B_BGA1-IC,TBD!!!F75!VSS(482)!!!!
S!GND!U5D1!P53!@baseboard_fab2_lib.baseboard_fab2(sch_1):page41_i283@chpset_lib.skx_ext_b(chips)!SKX_EXT_B_BGA1-IC,TBD!!!F75!VSS(483)!!!!
S!GND!U5D1!CE82!@baseboard_fab2_lib.baseboard_fab2(sch_1):page41_i283@chpset_lib.skx_ext_b(chips)!SKX_EXT_B_BGA1-IC,TBD!!!F75!VSS(484)!!!!
S!GND!U5D1!CE70!@baseboard_fab2_lib.baseboard_fab2(sch_1):page41_i283@chpset_lib.skx_ext_b(chips)!SKX_EXT_B_BGA1-IC,TBD!!!F75!VSS(485)!!!!
S!GND!U5D1!CE62!@baseboard_fab2_lib.baseboard_fab2(sch_1):page41_i283@chpset_lib.skx_ext_b(chips)!SKX_EXT_B_BGA1-IC,TBD!!!F75!VSS(486)!!!!
S!GND!U5D1!CE26!@baseboard_fab2_lib.baseboard_fab2(sch_1):page41_i283@chpset_lib.skx_ext_b(chips)!SKX_EXT_B_BGA1-IC,TBD!!!F75!VSS(487)!!!!
S!GND!U5D1!CE20!@baseboard_fab2_lib.baseboard_fab2(sch_1):page41_i283@chpset_lib.skx_ext_b(chips)!SKX_EXT_B_BGA1-IC,TBD!!!F75!VSS(488)!!!!
S!GND!U5D1!CE14!@baseboard_fab2_lib.baseboard_fab2(sch_1):page41_i283@chpset_lib.skx_ext_b(chips)!SKX_EXT_B_BGA1-IC,TBD!!!F75!VSS(489)!!!!
S!GND!U5D1!CE10!@baseboard_fab2_lib.baseboard_fab2(sch_1):page41_i283@chpset_lib.skx_ext_b(chips)!SKX_EXT_B_BGA1-IC,TBD!!!F75!VSS(490)!!!!
S!GND!U5D1!CD81!@baseboard_fab2_lib.baseboard_fab2(sch_1):page41_i283@chpset_lib.skx_ext_b(chips)!SKX_EXT_B_BGA1-IC,TBD!!!F75!VSS(491)!!!!
S!GND!U5D1!CD79!@baseboard_fab2_lib.baseboard_fab2(sch_1):page41_i283@chpset_lib.skx_ext_b(chips)!SKX_EXT_B_BGA1-IC,TBD!!!F75!VSS(492)!!!!
S!GND!U5D1!CD77!@baseboard_fab2_lib.baseboard_fab2(sch_1):page41_i283@chpset_lib.skx_ext_b(chips)!SKX_EXT_B_BGA1-IC,TBD!!!F75!VSS(493)!!!!
S!GND!U5D1!CD75!@baseboard_fab2_lib.baseboard_fab2(sch_1):page41_i283@chpset_lib.skx_ext_b(chips)!SKX_EXT_B_BGA1-IC,TBD!!!F75!VSS(494)!!!!
S!GND!U5D1!CD73!@baseboard_fab2_lib.baseboard_fab2(sch_1):page41_i283@chpset_lib.skx_ext_b(chips)!SKX_EXT_B_BGA1-IC,TBD!!!F75!VSS(495)!!!!
S!GND!U5D1!CD63!@baseboard_fab2_lib.baseboard_fab2(sch_1):page41_i283@chpset_lib.skx_ext_b(chips)!SKX_EXT_B_BGA1-IC,TBD!!!F75!VSS(496)!!!!
S!GND!U5D1!CD13!@baseboard_fab2_lib.baseboard_fab2(sch_1):page41_i283@chpset_lib.skx_ext_b(chips)!SKX_EXT_B_BGA1-IC,TBD!!!F75!VSS(497)!!!!
S!GND!U5D1!CD5!@baseboard_fab2_lib.baseboard_fab2(sch_1):page41_i283@chpset_lib.skx_ext_b(chips)!SKX_EXT_B_BGA1-IC,TBD!!!F75!VSS(498)!!!!
S!GND!U5D1!CC82!@baseboard_fab2_lib.baseboard_fab2(sch_1):page41_i283@chpset_lib.skx_ext_b(chips)!SKX_EXT_B_BGA1-IC,TBD!!!F75!VSS(499)!!!!
S!GND!U5D1!CC80!@baseboard_fab2_lib.baseboard_fab2(sch_1):page41_i283@chpset_lib.skx_ext_b(chips)!SKX_EXT_B_BGA1-IC,TBD!!!F75!VSS(500)!!!!
S!GND!U5D1!CC78!@baseboard_fab2_lib.baseboard_fab2(sch_1):page41_i283@chpset_lib.skx_ext_b(chips)!SKX_EXT_B_BGA1-IC,TBD!!!F75!VSS(501)!!!!
S!GND!U5D1!CC76!@baseboard_fab2_lib.baseboard_fab2(sch_1):page41_i283@chpset_lib.skx_ext_b(chips)!SKX_EXT_B_BGA1-IC,TBD!!!F75!VSS(502)!!!!
S!GND!U5D1!CC74!@baseboard_fab2_lib.baseboard_fab2(sch_1):page41_i283@chpset_lib.skx_ext_b(chips)!SKX_EXT_B_BGA1-IC,TBD!!!F75!VSS(503)!!!!
S!GND!U5D1!CC72!@baseboard_fab2_lib.baseboard_fab2(sch_1):page41_i283@chpset_lib.skx_ext_b(chips)!SKX_EXT_B_BGA1-IC,TBD!!!F75!VSS(504)!!!!
S!GND!U5D1!CC64!@baseboard_fab2_lib.baseboard_fab2(sch_1):page41_i283@chpset_lib.skx_ext_b(chips)!SKX_EXT_B_BGA1-IC,TBD!!!F75!VSS(505)!!!!
S!GND!U5D1!CC24!@baseboard_fab2_lib.baseboard_fab2(sch_1):page41_i283@chpset_lib.skx_ext_b(chips)!SKX_EXT_B_BGA1-IC,TBD!!!F75!VSS(506)!!!!
S!GND!U5D1!CC18!@baseboard_fab2_lib.baseboard_fab2(sch_1):page41_i283@chpset_lib.skx_ext_b(chips)!SKX_EXT_B_BGA1-IC,TBD!!!F75!VSS(507)!!!!
S!GND!U5D1!CC16!@baseboard_fab2_lib.baseboard_fab2(sch_1):page41_i283@chpset_lib.skx_ext_b(chips)!SKX_EXT_B_BGA1-IC,TBD!!!F75!VSS(508)!!!!
S!GND!U5D1!CC4!@baseboard_fab2_lib.baseboard_fab2(sch_1):page41_i283@chpset_lib.skx_ext_b(chips)!SKX_EXT_B_BGA1-IC,TBD!!!F75!VSS(509)!!!!
S!GND!U5D1!CB71!@baseboard_fab2_lib.baseboard_fab2(sch_1):page41_i283@chpset_lib.skx_ext_b(chips)!SKX_EXT_B_BGA1-IC,TBD!!!F75!VSS(510)!!!!
S!GND!U5D1!CB63!@baseboard_fab2_lib.baseboard_fab2(sch_1):page41_i283@chpset_lib.skx_ext_b(chips)!SKX_EXT_B_BGA1-IC,TBD!!!F75!VSS(511)!!!!
S!GND!U5D1!CB27!@baseboard_fab2_lib.baseboard_fab2(sch_1):page41_i283@chpset_lib.skx_ext_b(chips)!SKX_EXT_B_BGA1-IC,TBD!!!F75!VSS(512)!!!!
S!GND!U5D1!CB9!@baseboard_fab2_lib.baseboard_fab2(sch_1):page41_i283@chpset_lib.skx_ext_b(chips)!SKX_EXT_B_BGA1-IC,TBD!!!F75!VSS(513)!!!!
S!GND!U5D1!CB7!@baseboard_fab2_lib.baseboard_fab2(sch_1):page41_i283@chpset_lib.skx_ext_b(chips)!SKX_EXT_B_BGA1-IC,TBD!!!F75!VSS(514)!!!!
S!GND!U5D1!CA70!@baseboard_fab2_lib.baseboard_fab2(sch_1):page41_i283@chpset_lib.skx_ext_b(chips)!SKX_EXT_B_BGA1-IC,TBD!!!F75!VSS(515)!!!!
S!GND!U5D1!CA68!@baseboard_fab2_lib.baseboard_fab2(sch_1):page41_i283@chpset_lib.skx_ext_b(chips)!SKX_EXT_B_BGA1-IC,TBD!!!F75!VSS(516)!!!!
S!GND!U5D1!CA66!@baseboard_fab2_lib.baseboard_fab2(sch_1):page41_i283@chpset_lib.skx_ext_b(chips)!SKX_EXT_B_BGA1-IC,TBD!!!F75!VSS(517)!!!!
S!GND!U5D1!CA64!@baseboard_fab2_lib.baseboard_fab2(sch_1):page41_i283@chpset_lib.skx_ext_b(chips)!SKX_EXT_B_BGA1-IC,TBD!!!F75!VSS(518)!!!!
S!GND!U5D1!CA26!@baseboard_fab2_lib.baseboard_fab2(sch_1):page41_i283@chpset_lib.skx_ext_b(chips)!SKX_EXT_B_BGA1-IC,TBD!!!F75!VSS(519)!!!!
S!GND!U5D1!CA18!@baseboard_fab2_lib.baseboard_fab2(sch_1):page41_i283@chpset_lib.skx_ext_b(chips)!SKX_EXT_B_BGA1-IC,TBD!!!F75!VSS(520)!!!!
S!GND!U5D1!CA14!@baseboard_fab2_lib.baseboard_fab2(sch_1):page41_i283@chpset_lib.skx_ext_b(chips)!SKX_EXT_B_BGA1-IC,TBD!!!F75!VSS(521)!!!!
S!GND!U5D1!CA10!@baseboard_fab2_lib.baseboard_fab2(sch_1):page41_i283@chpset_lib.skx_ext_b(chips)!SKX_EXT_B_BGA1-IC,TBD!!!F75!VSS(522)!!!!
S!GND!U5D1!CA8!@baseboard_fab2_lib.baseboard_fab2(sch_1):page41_i283@chpset_lib.skx_ext_b(chips)!SKX_EXT_B_BGA1-IC,TBD!!!F75!VSS(523)!!!!
S!GND!U5D1!CA6!@baseboard_fab2_lib.baseboard_fab2(sch_1):page41_i283@chpset_lib.skx_ext_b(chips)!SKX_EXT_B_BGA1-IC,TBD!!!F75!VSS(524)!!!!
S!GND!U5D1!CA2!@baseboard_fab2_lib.baseboard_fab2(sch_1):page41_i283@chpset_lib.skx_ext_b(chips)!SKX_EXT_B_BGA1-IC,TBD!!!F75!VSS(525)!!!!
S!GND!U5D1!BY71!@baseboard_fab2_lib.baseboard_fab2(sch_1):page41_i283@chpset_lib.skx_ext_b(chips)!SKX_EXT_B_BGA1-IC,TBD!!!F75!VSS(526)!!!!
S!GND!U5D1!BY69!@baseboard_fab2_lib.baseboard_fab2(sch_1):page41_i283@chpset_lib.skx_ext_b(chips)!SKX_EXT_B_BGA1-IC,TBD!!!F75!VSS(527)!!!!
S!GND!U5D1!BY67!@baseboard_fab2_lib.baseboard_fab2(sch_1):page41_i283@chpset_lib.skx_ext_b(chips)!SKX_EXT_B_BGA1-IC,TBD!!!F75!VSS(528)!!!!
S!GND!U5D1!BY65!@baseboard_fab2_lib.baseboard_fab2(sch_1):page41_i283@chpset_lib.skx_ext_b(chips)!SKX_EXT_B_BGA1-IC,TBD!!!F75!VSS(529)!!!!
S!GND!U5D1!BY63!@baseboard_fab2_lib.baseboard_fab2(sch_1):page41_i283@chpset_lib.skx_ext_b(chips)!SKX_EXT_B_BGA1-IC,TBD!!!F75!VSS(530)!!!!
S!GND!U5D1!BY23!@baseboard_fab2_lib.baseboard_fab2(sch_1):page41_i283@chpset_lib.skx_ext_b(chips)!SKX_EXT_B_BGA1-IC,TBD!!!F75!VSS(531)!!!!
S!GND!U5D1!BY13!@baseboard_fab2_lib.baseboard_fab2(sch_1):page41_i283@chpset_lib.skx_ext_b(chips)!SKX_EXT_B_BGA1-IC,TBD!!!F75!VSS(532)!!!!
S!GND!U5D1!BY11!@baseboard_fab2_lib.baseboard_fab2(sch_1):page41_i283@chpset_lib.skx_ext_b(chips)!SKX_EXT_B_BGA1-IC,TBD!!!F75!VSS(533)!!!!
S!GND!U5D1!BW82!@baseboard_fab2_lib.baseboard_fab2(sch_1):page41_i283@chpset_lib.skx_ext_b(chips)!SKX_EXT_B_BGA1-IC,TBD!!!F75!VSS(534)!!!!
S!GND!U5D1!BW80!@baseboard_fab2_lib.baseboard_fab2(sch_1):page41_i283@chpset_lib.skx_ext_b(chips)!SKX_EXT_B_BGA1-IC,TBD!!!F75!VSS(535)!!!!
S!GND!U5D1!BW78!@baseboard_fab2_lib.baseboard_fab2(sch_1):page41_i283@chpset_lib.skx_ext_b(chips)!SKX_EXT_B_BGA1-IC,TBD!!!F75!VSS(536)!!!!
S!GND!U5D1!BW76!@baseboard_fab2_lib.baseboard_fab2(sch_1):page41_i283@chpset_lib.skx_ext_b(chips)!SKX_EXT_B_BGA1-IC,TBD!!!F75!VSS(537)!!!!
S!GND!U5D1!BW74!@baseboard_fab2_lib.baseboard_fab2(sch_1):page41_i283@chpset_lib.skx_ext_b(chips)!SKX_EXT_B_BGA1-IC,TBD!!!F75!VSS(538)!!!!
S!GND!U5D1!BW72!@baseboard_fab2_lib.baseboard_fab2(sch_1):page41_i283@chpset_lib.skx_ext_b(chips)!SKX_EXT_B_BGA1-IC,TBD!!!F75!VSS(539)!!!!
S!GND!U5D1!BW26!@baseboard_fab2_lib.baseboard_fab2(sch_1):page41_i283@chpset_lib.skx_ext_b(chips)!SKX_EXT_B_BGA1-IC,TBD!!!F75!VSS(540)!!!!
S!GND!U5D1!BW18!@baseboard_fab2_lib.baseboard_fab2(sch_1):page41_i283@chpset_lib.skx_ext_b(chips)!SKX_EXT_B_BGA1-IC,TBD!!!F75!VSS(541)!!!!
S!GND!U5D1!BW16!@baseboard_fab2_lib.baseboard_fab2(sch_1):page41_i283@chpset_lib.skx_ext_b(chips)!SKX_EXT_B_BGA1-IC,TBD!!!F75!VSS(542)!!!!
S!GND!U5D1!BW14!@baseboard_fab2_lib.baseboard_fab2(sch_1):page41_i283@chpset_lib.skx_ext_b(chips)!SKX_EXT_B_BGA1-IC,TBD!!!F75!VSS(543)!!!!
S!GND!U5D1!BW12!@baseboard_fab2_lib.baseboard_fab2(sch_1):page41_i283@chpset_lib.skx_ext_b(chips)!SKX_EXT_B_BGA1-IC,TBD!!!F75!VSS(544)!!!!
S!GND!U5D1!P55!@baseboard_fab2_lib.baseboard_fab2(sch_1):page41_i283@chpset_lib.skx_ext_b(chips)!SKX_EXT_B_BGA1-IC,TBD!!!F75!VSS(545)!!!!
S!GND!U5D1!BW6!@baseboard_fab2_lib.baseboard_fab2(sch_1):page41_i283@chpset_lib.skx_ext_b(chips)!SKX_EXT_B_BGA1-IC,TBD!!!F75!VSS(546)!!!!
S!GND!U5D1!BV25!@baseboard_fab2_lib.baseboard_fab2(sch_1):page41_i283@chpset_lib.skx_ext_b(chips)!SKX_EXT_B_BGA1-IC,TBD!!!F75!VSS(547)!!!!
S!GND!U5D1!BV17!@baseboard_fab2_lib.baseboard_fab2(sch_1):page41_i283@chpset_lib.skx_ext_b(chips)!SKX_EXT_B_BGA1-IC,TBD!!!F75!VSS(548)!!!!
S!GND!U5D1!BU10!@baseboard_fab2_lib.baseboard_fab2(sch_1):page41_i283@chpset_lib.skx_ext_b(chips)!SKX_EXT_B_BGA1-IC,TBD!!!F75!VSS(549)!!!!
S!GND!U5D1!BV5!@baseboard_fab2_lib.baseboard_fab2(sch_1):page41_i283@chpset_lib.skx_ext_b(chips)!SKX_EXT_B_BGA1-IC,TBD!!!F75!VSS(550)!!!!
S!GND!U5D1!BU8!@baseboard_fab2_lib.baseboard_fab2(sch_1):page41_i283@chpset_lib.skx_ext_b(chips)!SKX_EXT_B_BGA1-IC,TBD!!!F75!VSS(551)!!!!
S!GND!U5D1!BT25!@baseboard_fab2_lib.baseboard_fab2(sch_1):page41_i283@chpset_lib.skx_ext_b(chips)!SKX_EXT_B_BGA1-IC,TBD!!!F75!VSS(552)!!!!
S!GND!U5D1!BT23!@baseboard_fab2_lib.baseboard_fab2(sch_1):page41_i283@chpset_lib.skx_ext_b(chips)!SKX_EXT_B_BGA1-IC,TBD!!!F75!VSS(553)!!!!
S!GND!U5D1!BT21!@baseboard_fab2_lib.baseboard_fab2(sch_1):page41_i283@chpset_lib.skx_ext_b(chips)!SKX_EXT_B_BGA1-IC,TBD!!!F75!VSS(554)!!!!
S!GND!U5D1!BT5!@baseboard_fab2_lib.baseboard_fab2(sch_1):page41_i283@chpset_lib.skx_ext_b(chips)!SKX_EXT_B_BGA1-IC,TBD!!!F75!VSS(555)!!!!
S!GND!U5D1!BT3!@baseboard_fab2_lib.baseboard_fab2(sch_1):page41_i283@chpset_lib.skx_ext_b(chips)!SKX_EXT_B_BGA1-IC,TBD!!!F75!VSS(556)!!!!
S!GND!U5D1!BR82!@baseboard_fab2_lib.baseboard_fab2(sch_1):page41_i283@chpset_lib.skx_ext_b(chips)!SKX_EXT_B_BGA1-IC,TBD!!!F75!VSS(557)!!!!
S!GND!U5D1!BR80!@baseboard_fab2_lib.baseboard_fab2(sch_1):page41_i283@chpset_lib.skx_ext_b(chips)!SKX_EXT_B_BGA1-IC,TBD!!!F75!VSS(558)!!!!
S!GND!U5D1!BR78!@baseboard_fab2_lib.baseboard_fab2(sch_1):page41_i283@chpset_lib.skx_ext_b(chips)!SKX_EXT_B_BGA1-IC,TBD!!!F75!VSS(559)!!!!
S!GND!U5D1!BR76!@baseboard_fab2_lib.baseboard_fab2(sch_1):page41_i283@chpset_lib.skx_ext_b(chips)!SKX_EXT_B_BGA1-IC,TBD!!!F75!VSS(560)!!!!
S!GND!U5D1!BR74!@baseboard_fab2_lib.baseboard_fab2(sch_1):page41_i283@chpset_lib.skx_ext_b(chips)!SKX_EXT_B_BGA1-IC,TBD!!!F75!VSS(561)!!!!
S!GND!U5D1!BR72!@baseboard_fab2_lib.baseboard_fab2(sch_1):page41_i283@chpset_lib.skx_ext_b(chips)!SKX_EXT_B_BGA1-IC,TBD!!!F75!VSS(562)!!!!
S!GND!U5D1!BR70!@baseboard_fab2_lib.baseboard_fab2(sch_1):page41_i283@chpset_lib.skx_ext_b(chips)!SKX_EXT_B_BGA1-IC,TBD!!!F75!VSS(563)!!!!
S!GND!U5D1!BR68!@baseboard_fab2_lib.baseboard_fab2(sch_1):page41_i283@chpset_lib.skx_ext_b(chips)!SKX_EXT_B_BGA1-IC,TBD!!!F75!VSS(564)!!!!
S!GND!U5D1!BR66!@baseboard_fab2_lib.baseboard_fab2(sch_1):page41_i283@chpset_lib.skx_ext_b(chips)!SKX_EXT_B_BGA1-IC,TBD!!!F75!VSS(565)!!!!
S!GND!U5D1!BR64!@baseboard_fab2_lib.baseboard_fab2(sch_1):page41_i283@chpset_lib.skx_ext_b(chips)!SKX_EXT_B_BGA1-IC,TBD!!!F75!VSS(566)!!!!
S!GND!U5D1!P57!@baseboard_fab2_lib.baseboard_fab2(sch_1):page41_i283@chpset_lib.skx_ext_b(chips)!SKX_EXT_B_BGA1-IC,TBD!!!F75!VSS(567)!!!!
S!GND!U5D1!BR16!@baseboard_fab2_lib.baseboard_fab2(sch_1):page41_i283@chpset_lib.skx_ext_b(chips)!SKX_EXT_B_BGA1-IC,TBD!!!F75!VSS(568)!!!!
S!GND!U5D1!BR10!@baseboard_fab2_lib.baseboard_fab2(sch_1):page41_i283@chpset_lib.skx_ext_b(chips)!SKX_EXT_B_BGA1-IC,TBD!!!F75!VSS(569)!!!!
S!GND!U5D1!BR6!@baseboard_fab2_lib.baseboard_fab2(sch_1):page41_i283@chpset_lib.skx_ext_b(chips)!SKX_EXT_B_BGA1-IC,TBD!!!F75!VSS(570)!!!!
S!GND!U5D1!BP27!@baseboard_fab2_lib.baseboard_fab2(sch_1):page41_i283@chpset_lib.skx_ext_b(chips)!SKX_EXT_B_BGA1-IC,TBD!!!F75!VSS(571)!!!!
S!GND!U5D1!BP3!@baseboard_fab2_lib.baseboard_fab2(sch_1):page41_i283@chpset_lib.skx_ext_b(chips)!SKX_EXT_B_BGA1-IC,TBD!!!F75!VSS(572)!!!!
S!GND!U5D1!BN26!@baseboard_fab2_lib.baseboard_fab2(sch_1):page41_i283@chpset_lib.skx_ext_b(chips)!SKX_EXT_B_BGA1-IC,TBD!!!F75!VSS(573)!!!!
S!GND!U5D1!BN20!@baseboard_fab2_lib.baseboard_fab2(sch_1):page41_i283@chpset_lib.skx_ext_b(chips)!SKX_EXT_B_BGA1-IC,TBD!!!F75!VSS(574)!!!!
S!GND!U5D1!BN10!@baseboard_fab2_lib.baseboard_fab2(sch_1):page41_i283@chpset_lib.skx_ext_b(chips)!SKX_EXT_B_BGA1-IC,TBD!!!F75!VSS(575)!!!!
S!GND!U5D1!BN6!@baseboard_fab2_lib.baseboard_fab2(sch_1):page41_i283@chpset_lib.skx_ext_b(chips)!SKX_EXT_B_BGA1-IC,TBD!!!F75!VSS(576)!!!!
S!GND!U5D1!BM25!@baseboard_fab2_lib.baseboard_fab2(sch_1):page41_i283@chpset_lib.skx_ext_b(chips)!SKX_EXT_B_BGA1-IC,TBD!!!F75!VSS(577)!!!!
S!GND!U5D1!P59!@baseboard_fab2_lib.baseboard_fab2(sch_1):page41_i283@chpset_lib.skx_ext_b(chips)!SKX_EXT_B_BGA1-IC,TBD!!!F75!VSS(578)!!!!
S!GND!U5D1!BM15!@baseboard_fab2_lib.baseboard_fab2(sch_1):page41_i283@chpset_lib.skx_ext_b(chips)!SKX_EXT_B_BGA1-IC,TBD!!!F75!VSS(579)!!!!
S!GND!U5D1!BM13!@baseboard_fab2_lib.baseboard_fab2(sch_1):page41_i283@chpset_lib.skx_ext_b(chips)!SKX_EXT_B_BGA1-IC,TBD!!!F75!VSS(580)!!!!
S!GND!U5D1!BM9!@baseboard_fab2_lib.baseboard_fab2(sch_1):page41_i283@chpset_lib.skx_ext_b(chips)!SKX_EXT_B_BGA1-IC,TBD!!!F75!VSS(581)!!!!
S!GND!U5D1!BL82!@baseboard_fab2_lib.baseboard_fab2(sch_1):page41_i283@chpset_lib.skx_ext_b(chips)!SKX_EXT_B_BGA1-IC,TBD!!!F75!VSS(582)!!!!
S!GND!U5D1!BL80!@baseboard_fab2_lib.baseboard_fab2(sch_1):page41_i283@chpset_lib.skx_ext_b(chips)!SKX_EXT_B_BGA1-IC,TBD!!!F75!VSS(583)!!!!
S!GND!U5D1!BL78!@baseboard_fab2_lib.baseboard_fab2(sch_1):page41_i283@chpset_lib.skx_ext_b(chips)!SKX_EXT_B_BGA1-IC,TBD!!!F75!VSS(584)!!!!
S!GND!U5D1!BL76!@baseboard_fab2_lib.baseboard_fab2(sch_1):page41_i283@chpset_lib.skx_ext_b(chips)!SKX_EXT_B_BGA1-IC,TBD!!!F75!VSS(585)!!!!
S!GND!U5D1!BL74!@baseboard_fab2_lib.baseboard_fab2(sch_1):page41_i283@chpset_lib.skx_ext_b(chips)!SKX_EXT_B_BGA1-IC,TBD!!!F75!VSS(586)!!!!
S!GND!U5D1!BL72!@baseboard_fab2_lib.baseboard_fab2(sch_1):page41_i283@chpset_lib.skx_ext_b(chips)!SKX_EXT_B_BGA1-IC,TBD!!!F75!VSS(587)!!!!
S!GND!U5D1!DC38!@baseboard_fab2_lib.baseboard_fab2(sch_1):page41_i285@chpset_lib.skx_ext_b(chips)!SKX_EXT_B_BGA1-IC,TBD!!!F73!VSS(268)!!!!
S!GND!U5D1!DC32!@baseboard_fab2_lib.baseboard_fab2(sch_1):page41_i285@chpset_lib.skx_ext_b(chips)!SKX_EXT_B_BGA1-IC,TBD!!!F73!VSS(269)!!!!
S!GND!U5D1!DC26!@baseboard_fab2_lib.baseboard_fab2(sch_1):page41_i285@chpset_lib.skx_ext_b(chips)!SKX_EXT_B_BGA1-IC,TBD!!!F73!VSS(270)!!!!
S!GND!U5D1!DC24!@baseboard_fab2_lib.baseboard_fab2(sch_1):page41_i285@chpset_lib.skx_ext_b(chips)!SKX_EXT_B_BGA1-IC,TBD!!!F73!VSS(271)!!!!
S!GND!U5D1!DC14!@baseboard_fab2_lib.baseboard_fab2(sch_1):page41_i285@chpset_lib.skx_ext_b(chips)!SKX_EXT_B_BGA1-IC,TBD!!!F73!VSS(272)!!!!
S!GND!U5D1!DB85!@baseboard_fab2_lib.baseboard_fab2(sch_1):page41_i285@chpset_lib.skx_ext_b(chips)!SKX_EXT_B_BGA1-IC,TBD!!!F73!VSS(273)!!!!
S!GND!U5D1!DB83!@baseboard_fab2_lib.baseboard_fab2(sch_1):page41_i285@chpset_lib.skx_ext_b(chips)!SKX_EXT_B_BGA1-IC,TBD!!!F73!VSS(274)!!!!
S!GND!U5D1!DB77!@baseboard_fab2_lib.baseboard_fab2(sch_1):page41_i285@chpset_lib.skx_ext_b(chips)!SKX_EXT_B_BGA1-IC,TBD!!!F73!VSS(275)!!!!
S!GND!U5D1!DB73!@baseboard_fab2_lib.baseboard_fab2(sch_1):page41_i285@chpset_lib.skx_ext_b(chips)!SKX_EXT_B_BGA1-IC,TBD!!!F73!VSS(276)!!!!
S!GND!U5D1!DB49!@baseboard_fab2_lib.baseboard_fab2(sch_1):page41_i285@chpset_lib.skx_ext_b(chips)!SKX_EXT_B_BGA1-IC,TBD!!!F73!VSS(277)!!!!
S!GND!U5D1!DB47!@baseboard_fab2_lib.baseboard_fab2(sch_1):page41_i285@chpset_lib.skx_ext_b(chips)!SKX_EXT_B_BGA1-IC,TBD!!!F73!VSS(278)!!!!
S!GND!U5D1!DB41!@baseboard_fab2_lib.baseboard_fab2(sch_1):page41_i285@chpset_lib.skx_ext_b(chips)!SKX_EXT_B_BGA1-IC,TBD!!!F73!VSS(279)!!!!
S!GND!U5D1!DB39!@baseboard_fab2_lib.baseboard_fab2(sch_1):page41_i285@chpset_lib.skx_ext_b(chips)!SKX_EXT_B_BGA1-IC,TBD!!!F73!VSS(280)!!!!
S!GND!U5D1!DB25!@baseboard_fab2_lib.baseboard_fab2(sch_1):page41_i285@chpset_lib.skx_ext_b(chips)!SKX_EXT_B_BGA1-IC,TBD!!!F73!VSS(281)!!!!
S!GND!U5D1!DB23!@baseboard_fab2_lib.baseboard_fab2(sch_1):page41_i285@chpset_lib.skx_ext_b(chips)!SKX_EXT_B_BGA1-IC,TBD!!!F73!VSS(282)!!!!
S!GND!U5D1!DB17!@baseboard_fab2_lib.baseboard_fab2(sch_1):page41_i285@chpset_lib.skx_ext_b(chips)!SKX_EXT_B_BGA1-IC,TBD!!!F73!VSS(283)!!!!
S!GND!U5D1!DB13!@baseboard_fab2_lib.baseboard_fab2(sch_1):page41_i285@chpset_lib.skx_ext_b(chips)!SKX_EXT_B_BGA1-IC,TBD!!!F73!VSS(284)!!!!
S!GND!U5D1!DB3!@baseboard_fab2_lib.baseboard_fab2(sch_1):page41_i285@chpset_lib.skx_ext_b(chips)!SKX_EXT_B_BGA1-IC,TBD!!!F73!VSS(285)!!!!
S!GND!U5D1!DA80!@baseboard_fab2_lib.baseboard_fab2(sch_1):page41_i285@chpset_lib.skx_ext_b(chips)!SKX_EXT_B_BGA1-IC,TBD!!!F73!VSS(286)!!!!
S!GND!U5D1!DA78!@baseboard_fab2_lib.baseboard_fab2(sch_1):page41_i285@chpset_lib.skx_ext_b(chips)!SKX_EXT_B_BGA1-IC,TBD!!!F73!VSS(287)!!!!
S!GND!U5D1!DA76!@baseboard_fab2_lib.baseboard_fab2(sch_1):page41_i285@chpset_lib.skx_ext_b(chips)!SKX_EXT_B_BGA1-IC,TBD!!!F73!VSS(288)!!!!
S!GND!U5D1!DA74!@baseboard_fab2_lib.baseboard_fab2(sch_1):page41_i285@chpset_lib.skx_ext_b(chips)!SKX_EXT_B_BGA1-IC,TBD!!!F73!VSS(289)!!!!
S!GND!U5D1!DA70!@baseboard_fab2_lib.baseboard_fab2(sch_1):page41_i285@chpset_lib.skx_ext_b(chips)!SKX_EXT_B_BGA1-IC,TBD!!!F73!VSS(290)!!!!
S!GND!U5D1!DA64!@baseboard_fab2_lib.baseboard_fab2(sch_1):page41_i285@chpset_lib.skx_ext_b(chips)!SKX_EXT_B_BGA1-IC,TBD!!!F73!VSS(291)!!!!
S!GND!U5D1!DA50!@baseboard_fab2_lib.baseboard_fab2(sch_1):page41_i285@chpset_lib.skx_ext_b(chips)!SKX_EXT_B_BGA1-IC,TBD!!!F73!VSS(292)!!!!
S!GND!U5D1!DA48!@baseboard_fab2_lib.baseboard_fab2(sch_1):page41_i285@chpset_lib.skx_ext_b(chips)!SKX_EXT_B_BGA1-IC,TBD!!!F73!VSS(293)!!!!
S!GND!U5D1!DA46!@baseboard_fab2_lib.baseboard_fab2(sch_1):page41_i284@chpset_lib.skx_ext_b(chips)!SKX_EXT_B_BGA1-IC,TBD!!!F74!VSS(294)!!!!
S!GND!U5D1!DA44!@baseboard_fab2_lib.baseboard_fab2(sch_1):page41_i284@chpset_lib.skx_ext_b(chips)!SKX_EXT_B_BGA1-IC,TBD!!!F74!VSS(295)!!!!
S!GND!U5D1!DA38!@baseboard_fab2_lib.baseboard_fab2(sch_1):page41_i284@chpset_lib.skx_ext_b(chips)!SKX_EXT_B_BGA1-IC,TBD!!!F74!VSS(296)!!!!
S!GND!U5D1!DA36!@baseboard_fab2_lib.baseboard_fab2(sch_1):page41_i284@chpset_lib.skx_ext_b(chips)!SKX_EXT_B_BGA1-IC,TBD!!!F74!VSS(297)!!!!
S!GND!U5D1!DA34!@baseboard_fab2_lib.baseboard_fab2(sch_1):page41_i284@chpset_lib.skx_ext_b(chips)!SKX_EXT_B_BGA1-IC,TBD!!!F74!VSS(298)!!!!
S!GND!U5D1!DA32!@baseboard_fab2_lib.baseboard_fab2(sch_1):page41_i284@chpset_lib.skx_ext_b(chips)!SKX_EXT_B_BGA1-IC,TBD!!!F74!VSS(299)!!!!
S!GND!U5D1!DA30!@baseboard_fab2_lib.baseboard_fab2(sch_1):page41_i284@chpset_lib.skx_ext_b(chips)!SKX_EXT_B_BGA1-IC,TBD!!!F74!VSS(300)!!!!
S!GND!U5D1!DA28!@baseboard_fab2_lib.baseboard_fab2(sch_1):page41_i284@chpset_lib.skx_ext_b(chips)!SKX_EXT_B_BGA1-IC,TBD!!!F74!VSS(301)!!!!
S!GND!U5D1!DA26!@baseboard_fab2_lib.baseboard_fab2(sch_1):page41_i284@chpset_lib.skx_ext_b(chips)!SKX_EXT_B_BGA1-IC,TBD!!!F74!VSS(302)!!!!
S!GND!U5D1!DA18!@baseboard_fab2_lib.baseboard_fab2(sch_1):page41_i284@chpset_lib.skx_ext_b(chips)!SKX_EXT_B_BGA1-IC,TBD!!!F74!VSS(303)!!!!
S!GND!U5D1!H53!@baseboard_fab2_lib.baseboard_fab2(sch_1):page41_i284@chpset_lib.skx_ext_b(chips)!SKX_EXT_B_BGA1-IC,TBD!!!F74!VSS(304)!!!!
S!GND!U5D1!DA6!@baseboard_fab2_lib.baseboard_fab2(sch_1):page41_i284@chpset_lib.skx_ext_b(chips)!SKX_EXT_B_BGA1-IC,TBD!!!F74!VSS(305)!!!!
S!GND!U5D1!CY85!@baseboard_fab2_lib.baseboard_fab2(sch_1):page41_i284@chpset_lib.skx_ext_b(chips)!SKX_EXT_B_BGA1-IC,TBD!!!F74!VSS(306)!!!!
S!GND!U5D1!CY83!@baseboard_fab2_lib.baseboard_fab2(sch_1):page41_i284@chpset_lib.skx_ext_b(chips)!SKX_EXT_B_BGA1-IC,TBD!!!F74!VSS(307)!!!!
S!GND!U5D1!CY77!@baseboard_fab2_lib.baseboard_fab2(sch_1):page41_i284@chpset_lib.skx_ext_b(chips)!SKX_EXT_B_BGA1-IC,TBD!!!F74!VSS(308)!!!!
S!GND!U5D1!CY75!@baseboard_fab2_lib.baseboard_fab2(sch_1):page41_i284@chpset_lib.skx_ext_b(chips)!SKX_EXT_B_BGA1-IC,TBD!!!F74!VSS(309)!!!!
S!GND!U5D1!CY69!@baseboard_fab2_lib.baseboard_fab2(sch_1):page41_i284@chpset_lib.skx_ext_b(chips)!SKX_EXT_B_BGA1-IC,TBD!!!F74!VSS(310)!!!!
S!GND!U5D1!CY65!@baseboard_fab2_lib.baseboard_fab2(sch_1):page41_i284@chpset_lib.skx_ext_b(chips)!SKX_EXT_B_BGA1-IC,TBD!!!F74!VSS(311)!!!!
S!GND!U5D1!CY61!@baseboard_fab2_lib.baseboard_fab2(sch_1):page41_i284@chpset_lib.skx_ext_b(chips)!SKX_EXT_B_BGA1-IC,TBD!!!F74!VSS(312)!!!!
S!GND!U5D1!CY59!@baseboard_fab2_lib.baseboard_fab2(sch_1):page41_i284@chpset_lib.skx_ext_b(chips)!SKX_EXT_B_BGA1-IC,TBD!!!F74!VSS(313)!!!!
S!GND!U5D1!CY51!@baseboard_fab2_lib.baseboard_fab2(sch_1):page41_i284@chpset_lib.skx_ext_b(chips)!SKX_EXT_B_BGA1-IC,TBD!!!F74!VSS(314)!!!!
S!GND!U5D1!CY45!@baseboard_fab2_lib.baseboard_fab2(sch_1):page41_i284@chpset_lib.skx_ext_b(chips)!SKX_EXT_B_BGA1-IC,TBD!!!F74!VSS(315)!!!!
S!GND!U5D1!CY41!@baseboard_fab2_lib.baseboard_fab2(sch_1):page41_i284@chpset_lib.skx_ext_b(chips)!SKX_EXT_B_BGA1-IC,TBD!!!F74!VSS(316)!!!!
S!GND!U5D1!CY21!@baseboard_fab2_lib.baseboard_fab2(sch_1):page41_i284@chpset_lib.skx_ext_b(chips)!SKX_EXT_B_BGA1-IC,TBD!!!F74!VSS(317)!!!!
S!GND!U5D1!CY15!@baseboard_fab2_lib.baseboard_fab2(sch_1):page41_i284@chpset_lib.skx_ext_b(chips)!SKX_EXT_B_BGA1-IC,TBD!!!F74!VSS(318)!!!!
S!GND!U5D1!CY13!@baseboard_fab2_lib.baseboard_fab2(sch_1):page41_i284@chpset_lib.skx_ext_b(chips)!SKX_EXT_B_BGA1-IC,TBD!!!F74!VSS(319)!!!!
S!GND!U5D1!CY9!@baseboard_fab2_lib.baseboard_fab2(sch_1):page41_i284@chpset_lib.skx_ext_b(chips)!SKX_EXT_B_BGA1-IC,TBD!!!F74!VSS(320)!!!!
S!GND!U5D1!CY1!@baseboard_fab2_lib.baseboard_fab2(sch_1):page41_i284@chpset_lib.skx_ext_b(chips)!SKX_EXT_B_BGA1-IC,TBD!!!F74!VSS(321)!!!!
S!GND!U5D1!CW82!@baseboard_fab2_lib.baseboard_fab2(sch_1):page41_i284@chpset_lib.skx_ext_b(chips)!SKX_EXT_B_BGA1-IC,TBD!!!F74!VSS(322)!!!!
S!GND!U5D1!CW78!@baseboard_fab2_lib.baseboard_fab2(sch_1):page41_i284@chpset_lib.skx_ext_b(chips)!SKX_EXT_B_BGA1-IC,TBD!!!F74!VSS(323)!!!!
S!GND!U5D1!CW74!@baseboard_fab2_lib.baseboard_fab2(sch_1):page41_i284@chpset_lib.skx_ext_b(chips)!SKX_EXT_B_BGA1-IC,TBD!!!F74!VSS(324)!!!!
S!GND!U5D1!CW68!@baseboard_fab2_lib.baseboard_fab2(sch_1):page41_i284@chpset_lib.skx_ext_b(chips)!SKX_EXT_B_BGA1-IC,TBD!!!F74!VSS(325)!!!!
S!GND!U5D1!CW66!@baseboard_fab2_lib.baseboard_fab2(sch_1):page41_i284@chpset_lib.skx_ext_b(chips)!SKX_EXT_B_BGA1-IC,TBD!!!F74!VSS(326)!!!!
S!GND!U5D1!CW64!@baseboard_fab2_lib.baseboard_fab2(sch_1):page41_i284@chpset_lib.skx_ext_b(chips)!SKX_EXT_B_BGA1-IC,TBD!!!F74!VSS(327)!!!!
S!GND!U5D1!CW54!@baseboard_fab2_lib.baseboard_fab2(sch_1):page41_i284@chpset_lib.skx_ext_b(chips)!SKX_EXT_B_BGA1-IC,TBD!!!F74!VSS(328)!!!!
S!GND!U5D1!CW52!@baseboard_fab2_lib.baseboard_fab2(sch_1):page41_i284@chpset_lib.skx_ext_b(chips)!SKX_EXT_B_BGA1-IC,TBD!!!F74!VSS(329)!!!!
S!GND!U5D1!CW42!@baseboard_fab2_lib.baseboard_fab2(sch_1):page41_i284@chpset_lib.skx_ext_b(chips)!SKX_EXT_B_BGA1-IC,TBD!!!F74!VSS(330)!!!!
S!GND!U5D1!CW40!@baseboard_fab2_lib.baseboard_fab2(sch_1):page41_i284@chpset_lib.skx_ext_b(chips)!SKX_EXT_B_BGA1-IC,TBD!!!F74!VSS(331)!!!!
S!GND!U5D1!CW38!@baseboard_fab2_lib.baseboard_fab2(sch_1):page41_i284@chpset_lib.skx_ext_b(chips)!SKX_EXT_B_BGA1-IC,TBD!!!F74!VSS(332)!!!!
S!GND!U5D1!CW32!@baseboard_fab2_lib.baseboard_fab2(sch_1):page41_i284@chpset_lib.skx_ext_b(chips)!SKX_EXT_B_BGA1-IC,TBD!!!F74!VSS(333)!!!!
S!GND!U5D1!CW26!@baseboard_fab2_lib.baseboard_fab2(sch_1):page41_i284@chpset_lib.skx_ext_b(chips)!SKX_EXT_B_BGA1-IC,TBD!!!F74!VSS(334)!!!!
S!GND!U5D1!CW12!@baseboard_fab2_lib.baseboard_fab2(sch_1):page41_i284@chpset_lib.skx_ext_b(chips)!SKX_EXT_B_BGA1-IC,TBD!!!F74!VSS(335)!!!!
S!GND!U5D1!CV83!@baseboard_fab2_lib.baseboard_fab2(sch_1):page41_i284@chpset_lib.skx_ext_b(chips)!SKX_EXT_B_BGA1-IC,TBD!!!F74!VSS(336)!!!!
S!GND!U5D1!CV81!@baseboard_fab2_lib.baseboard_fab2(sch_1):page41_i284@chpset_lib.skx_ext_b(chips)!SKX_EXT_B_BGA1-IC,TBD!!!F74!VSS(337)!!!!
S!GND!U5D1!CV79!@baseboard_fab2_lib.baseboard_fab2(sch_1):page41_i284@chpset_lib.skx_ext_b(chips)!SKX_EXT_B_BGA1-IC,TBD!!!F74!VSS(338)!!!!
S!GND!U5D1!CV73!@baseboard_fab2_lib.baseboard_fab2(sch_1):page41_i284@chpset_lib.skx_ext_b(chips)!SKX_EXT_B_BGA1-IC,TBD!!!F74!VSS(339)!!!!
S!GND!U5D1!CV67!@baseboard_fab2_lib.baseboard_fab2(sch_1):page41_i284@chpset_lib.skx_ext_b(chips)!SKX_EXT_B_BGA1-IC,TBD!!!F74!VSS(340)!!!!
S!GND!U5D1!CV63!@baseboard_fab2_lib.baseboard_fab2(sch_1):page41_i284@chpset_lib.skx_ext_b(chips)!SKX_EXT_B_BGA1-IC,TBD!!!F74!VSS(341)!!!!
S!GND!U5D1!CV55!@baseboard_fab2_lib.baseboard_fab2(sch_1):page41_i284@chpset_lib.skx_ext_b(chips)!SKX_EXT_B_BGA1-IC,TBD!!!F74!VSS(342)!!!!
S!GND!U5D1!CV53!@baseboard_fab2_lib.baseboard_fab2(sch_1):page41_i284@chpset_lib.skx_ext_b(chips)!SKX_EXT_B_BGA1-IC,TBD!!!F74!VSS(343)!!!!
S!GND!U5D1!CV41!@baseboard_fab2_lib.baseboard_fab2(sch_1):page41_i284@chpset_lib.skx_ext_b(chips)!SKX_EXT_B_BGA1-IC,TBD!!!F74!VSS(344)!!!!
S!GND!U5D1!CV39!@baseboard_fab2_lib.baseboard_fab2(sch_1):page41_i284@chpset_lib.skx_ext_b(chips)!SKX_EXT_B_BGA1-IC,TBD!!!F74!VSS(345)!!!!
S!GND!U5D1!CV37!@baseboard_fab2_lib.baseboard_fab2(sch_1):page41_i284@chpset_lib.skx_ext_b(chips)!SKX_EXT_B_BGA1-IC,TBD!!!F74!VSS(346)!!!!
S!GND!U5D1!CV33!@baseboard_fab2_lib.baseboard_fab2(sch_1):page41_i284@chpset_lib.skx_ext_b(chips)!SKX_EXT_B_BGA1-IC,TBD!!!F74!VSS(347)!!!!
S!GND!U5D1!CV31!@baseboard_fab2_lib.baseboard_fab2(sch_1):page41_i284@chpset_lib.skx_ext_b(chips)!SKX_EXT_B_BGA1-IC,TBD!!!F74!VSS(348)!!!!
S!GND!U5D1!CV27!@baseboard_fab2_lib.baseboard_fab2(sch_1):page41_i284@chpset_lib.skx_ext_b(chips)!SKX_EXT_B_BGA1-IC,TBD!!!F74!VSS(349)!!!!
S!GND!U5D1!CV25!@baseboard_fab2_lib.baseboard_fab2(sch_1):page41_i284@chpset_lib.skx_ext_b(chips)!SKX_EXT_B_BGA1-IC,TBD!!!F74!VSS(350)!!!!
S!GND!U5D1!CV17!@baseboard_fab2_lib.baseboard_fab2(sch_1):page41_i284@chpset_lib.skx_ext_b(chips)!SKX_EXT_B_BGA1-IC,TBD!!!F74!VSS(351)!!!!
S!GND!U5D1!H55!@baseboard_fab2_lib.baseboard_fab2(sch_1):page41_i284@chpset_lib.skx_ext_b(chips)!SKX_EXT_B_BGA1-IC,TBD!!!F74!VSS(352)!!!!
S!GND!U5D1!CV1!@baseboard_fab2_lib.baseboard_fab2(sch_1):page41_i284@chpset_lib.skx_ext_b(chips)!SKX_EXT_B_BGA1-IC,TBD!!!F74!VSS(353)!!!!
S!GND!U5D1!CU86!@baseboard_fab2_lib.baseboard_fab2(sch_1):page41_i284@chpset_lib.skx_ext_b(chips)!SKX_EXT_B_BGA1-IC,TBD!!!F74!VSS(354)!!!!
S!GND!U5D1!CU82!@baseboard_fab2_lib.baseboard_fab2(sch_1):page41_i284@chpset_lib.skx_ext_b(chips)!SKX_EXT_B_BGA1-IC,TBD!!!F74!VSS(355)!!!!
S!GND!U5D1!CU80!@baseboard_fab2_lib.baseboard_fab2(sch_1):page41_i284@chpset_lib.skx_ext_b(chips)!SKX_EXT_B_BGA1-IC,TBD!!!F74!VSS(356)!!!!
S!GND!U5D1!CU78!@baseboard_fab2_lib.baseboard_fab2(sch_1):page41_i284@chpset_lib.skx_ext_b(chips)!SKX_EXT_B_BGA1-IC,TBD!!!F74!VSS(357)!!!!
S!GND!U5D1!CU76!@baseboard_fab2_lib.baseboard_fab2(sch_1):page41_i284@chpset_lib.skx_ext_b(chips)!SKX_EXT_B_BGA1-IC,TBD!!!F74!VSS(358)!!!!
S!GND!U5D1!CU68!@baseboard_fab2_lib.baseboard_fab2(sch_1):page41_i284@chpset_lib.skx_ext_b(chips)!SKX_EXT_B_BGA1-IC,TBD!!!F74!VSS(359)!!!!
S!GND!U5D1!CU62!@baseboard_fab2_lib.baseboard_fab2(sch_1):page41_i284@chpset_lib.skx_ext_b(chips)!SKX_EXT_B_BGA1-IC,TBD!!!F74!VSS(360)!!!!
S!GND!U5D1!CU56!@baseboard_fab2_lib.baseboard_fab2(sch_1):page41_i284@chpset_lib.skx_ext_b(chips)!SKX_EXT_B_BGA1-IC,TBD!!!F74!VSS(361)!!!!
S!GND!U5D1!CU36!@baseboard_fab2_lib.baseboard_fab2(sch_1):page41_i284@chpset_lib.skx_ext_b(chips)!SKX_EXT_B_BGA1-IC,TBD!!!F74!VSS(362)!!!!
S!GND!U5D1!CU34!@baseboard_fab2_lib.baseboard_fab2(sch_1):page41_i284@chpset_lib.skx_ext_b(chips)!SKX_EXT_B_BGA1-IC,TBD!!!F74!VSS(363)!!!!
S!GND!U5D1!CU30!@baseboard_fab2_lib.baseboard_fab2(sch_1):page41_i284@chpset_lib.skx_ext_b(chips)!SKX_EXT_B_BGA1-IC,TBD!!!F74!VSS(364)!!!!
S!GND!U5D1!CU28!@baseboard_fab2_lib.baseboard_fab2(sch_1):page41_i284@chpset_lib.skx_ext_b(chips)!SKX_EXT_B_BGA1-IC,TBD!!!F74!VSS(365)!!!!
S!GND!U5D1!CU22!@baseboard_fab2_lib.baseboard_fab2(sch_1):page41_i284@chpset_lib.skx_ext_b(chips)!SKX_EXT_B_BGA1-IC,TBD!!!F74!VSS(366)!!!!
S!GND!U5D1!CU4!@baseboard_fab2_lib.baseboard_fab2(sch_1):page41_i284@chpset_lib.skx_ext_b(chips)!SKX_EXT_B_BGA1-IC,TBD!!!F74!VSS(367)!!!!
S!GND!U5D1!CT85!@baseboard_fab2_lib.baseboard_fab2(sch_1):page41_i284@chpset_lib.skx_ext_b(chips)!SKX_EXT_B_BGA1-IC,TBD!!!F74!VSS(368)!!!!
S!GND!U5D1!CT83!@baseboard_fab2_lib.baseboard_fab2(sch_1):page41_i284@chpset_lib.skx_ext_b(chips)!SKX_EXT_B_BGA1-IC,TBD!!!F74!VSS(369)!!!!
S!GND!U5D1!CT79!@baseboard_fab2_lib.baseboard_fab2(sch_1):page41_i284@chpset_lib.skx_ext_b(chips)!SKX_EXT_B_BGA1-IC,TBD!!!F74!VSS(370)!!!!
S!GND!U5D1!CT73!@baseboard_fab2_lib.baseboard_fab2(sch_1):page41_i284@chpset_lib.skx_ext_b(chips)!SKX_EXT_B_BGA1-IC,TBD!!!F74!VSS(371)!!!!
S!GND!U5D1!CT57!@baseboard_fab2_lib.baseboard_fab2(sch_1):page41_i284@chpset_lib.skx_ext_b(chips)!SKX_EXT_B_BGA1-IC,TBD!!!F74!VSS(372)!!!!
S!GND!U5D1!CT35!@baseboard_fab2_lib.baseboard_fab2(sch_1):page41_i284@chpset_lib.skx_ext_b(chips)!SKX_EXT_B_BGA1-IC,TBD!!!F74!VSS(373)!!!!
S!GND!U5D1!CT33!@baseboard_fab2_lib.baseboard_fab2(sch_1):page41_i284@chpset_lib.skx_ext_b(chips)!SKX_EXT_B_BGA1-IC,TBD!!!F74!VSS(374)!!!!
S!GND!U5D1!CT29!@baseboard_fab2_lib.baseboard_fab2(sch_1):page41_i284@chpset_lib.skx_ext_b(chips)!SKX_EXT_B_BGA1-IC,TBD!!!F74!VSS(375)!!!!
S!GND!U5D1!CT27!@baseboard_fab2_lib.baseboard_fab2(sch_1):page41_i284@chpset_lib.skx_ext_b(chips)!SKX_EXT_B_BGA1-IC,TBD!!!F74!VSS(376)!!!!
S!GND!U5D1!CT19!@baseboard_fab2_lib.baseboard_fab2(sch_1):page41_i284@chpset_lib.skx_ext_b(chips)!SKX_EXT_B_BGA1-IC,TBD!!!F74!VSS(377)!!!!
S!GND!U5D1!CT13!@baseboard_fab2_lib.baseboard_fab2(sch_1):page41_i284@chpset_lib.skx_ext_b(chips)!SKX_EXT_B_BGA1-IC,TBD!!!F74!VSS(378)!!!!
S!GND!U5D1!H57!@baseboard_fab2_lib.baseboard_fab2(sch_1):page41_i284@chpset_lib.skx_ext_b(chips)!SKX_EXT_B_BGA1-IC,TBD!!!F74!VSS(379)!!!!
S!GND!U5D1!CR86!@baseboard_fab2_lib.baseboard_fab2(sch_1):page41_i284@chpset_lib.skx_ext_b(chips)!SKX_EXT_B_BGA1-IC,TBD!!!F74!VSS(380)!!!!
S!GND!U5D1!CR78!@baseboard_fab2_lib.baseboard_fab2(sch_1):page41_i284@chpset_lib.skx_ext_b(chips)!SKX_EXT_B_BGA1-IC,TBD!!!F74!VSS(381)!!!!
S!GND!U5D1!CR68!@baseboard_fab2_lib.baseboard_fab2(sch_1):page41_i284@chpset_lib.skx_ext_b(chips)!SKX_EXT_B_BGA1-IC,TBD!!!F74!VSS(382)!!!!
S!GND!U5D1!CR66!@baseboard_fab2_lib.baseboard_fab2(sch_1):page41_i284@chpset_lib.skx_ext_b(chips)!SKX_EXT_B_BGA1-IC,TBD!!!F74!VSS(383)!!!!
S!GND!U5D1!CR64!@baseboard_fab2_lib.baseboard_fab2(sch_1):page41_i284@chpset_lib.skx_ext_b(chips)!SKX_EXT_B_BGA1-IC,TBD!!!F74!VSS(384)!!!!
S!GND!U5D1!CR62!@baseboard_fab2_lib.baseboard_fab2(sch_1):page41_i284@chpset_lib.skx_ext_b(chips)!SKX_EXT_B_BGA1-IC,TBD!!!F74!VSS(385)!!!!
S!GND!U5D1!CR58!@baseboard_fab2_lib.baseboard_fab2(sch_1):page41_i284@chpset_lib.skx_ext_b(chips)!SKX_EXT_B_BGA1-IC,TBD!!!F74!VSS(386)!!!!
S!GND!U5D1!CR32!@baseboard_fab2_lib.baseboard_fab2(sch_1):page41_i284@chpset_lib.skx_ext_b(chips)!SKX_EXT_B_BGA1-IC,TBD!!!F74!VSS(387)!!!!
S!GND!U5D1!CR24!@baseboard_fab2_lib.baseboard_fab2(sch_1):page41_i284@chpset_lib.skx_ext_b(chips)!SKX_EXT_B_BGA1-IC,TBD!!!F74!VSS(388)!!!!
S!GND!U5D1!CR22!@baseboard_fab2_lib.baseboard_fab2(sch_1):page41_i284@chpset_lib.skx_ext_b(chips)!SKX_EXT_B_BGA1-IC,TBD!!!F74!VSS(389)!!!!
S!GND!U5D1!CR10!@baseboard_fab2_lib.baseboard_fab2(sch_1):page41_i284@chpset_lib.skx_ext_b(chips)!SKX_EXT_B_BGA1-IC,TBD!!!F74!VSS(390)!!!!
S!GND!U5D1!CR6!@baseboard_fab2_lib.baseboard_fab2(sch_1):page41_i284@chpset_lib.skx_ext_b(chips)!SKX_EXT_B_BGA1-IC,TBD!!!F74!VSS(391)!!!!
S!GND!U5D1!CP83!@baseboard_fab2_lib.baseboard_fab2(sch_1):page41_i284@chpset_lib.skx_ext_b(chips)!SKX_EXT_B_BGA1-IC,TBD!!!F74!VSS(392)!!!!
S!GND!U5D1!CP81!@baseboard_fab2_lib.baseboard_fab2(sch_1):page41_i284@chpset_lib.skx_ext_b(chips)!SKX_EXT_B_BGA1-IC,TBD!!!F74!VSS(393)!!!!
S!GND!U5D1!CP75!@baseboard_fab2_lib.baseboard_fab2(sch_1):page41_i284@chpset_lib.skx_ext_b(chips)!SKX_EXT_B_BGA1-IC,TBD!!!F74!VSS(394)!!!!
S!GND!U5D1!CP73!@baseboard_fab2_lib.baseboard_fab2(sch_1):page41_i284@chpset_lib.skx_ext_b(chips)!SKX_EXT_B_BGA1-IC,TBD!!!F74!VSS(395)!!!!
S!GND!U5D1!CP69!@baseboard_fab2_lib.baseboard_fab2(sch_1):page41_i284@chpset_lib.skx_ext_b(chips)!SKX_EXT_B_BGA1-IC,TBD!!!F74!VSS(396)!!!!
S!GND!U5D1!CP59!@baseboard_fab2_lib.baseboard_fab2(sch_1):page41_i284@chpset_lib.skx_ext_b(chips)!SKX_EXT_B_BGA1-IC,TBD!!!F74!VSS(397)!!!!
S!GND!U5D1!CP25!@baseboard_fab2_lib.baseboard_fab2(sch_1):page41_i284@chpset_lib.skx_ext_b(chips)!SKX_EXT_B_BGA1-IC,TBD!!!F74!VSS(398)!!!!
S!GND!U5D1!H59!@baseboard_fab2_lib.baseboard_fab2(sch_1):page41_i284@chpset_lib.skx_ext_b(chips)!SKX_EXT_B_BGA1-IC,TBD!!!F74!VSS(399)!!!!
S!GND!U5D1!CP1!@baseboard_fab2_lib.baseboard_fab2(sch_1):page41_i284@chpset_lib.skx_ext_b(chips)!SKX_EXT_B_BGA1-IC,TBD!!!F74!VSS(400)!!!!
S!GND!U5D1!CN78!@baseboard_fab2_lib.baseboard_fab2(sch_1):page41_i284@chpset_lib.skx_ext_b(chips)!SKX_EXT_B_BGA1-IC,TBD!!!F74!VSS(401)!!!!
S!GND!U5D1!CN68!@baseboard_fab2_lib.baseboard_fab2(sch_1):page41_i284@chpset_lib.skx_ext_b(chips)!SKX_EXT_B_BGA1-IC,TBD!!!F74!VSS(402)!!!!
S!GND!U5D1!CN62!@baseboard_fab2_lib.baseboard_fab2(sch_1):page41_i284@chpset_lib.skx_ext_b(chips)!SKX_EXT_B_BGA1-IC,TBD!!!F74!VSS(403)!!!!
S!GND!U5D1!CN60!@baseboard_fab2_lib.baseboard_fab2(sch_1):page41_i284@chpset_lib.skx_ext_b(chips)!SKX_EXT_B_BGA1-IC,TBD!!!F74!VSS(404)!!!!
S!GND!U5D1!CN32!@baseboard_fab2_lib.baseboard_fab2(sch_1):page41_i284@chpset_lib.skx_ext_b(chips)!SKX_EXT_B_BGA1-IC,TBD!!!F74!VSS(405)!!!!
S!GND!U5D1!CN26!@baseboard_fab2_lib.baseboard_fab2(sch_1):page41_i284@chpset_lib.skx_ext_b(chips)!SKX_EXT_B_BGA1-IC,TBD!!!F74!VSS(406)!!!!
S!GND!U5D1!H61!@baseboard_fab2_lib.baseboard_fab2(sch_1):page41_i284@chpset_lib.skx_ext_b(chips)!SKX_EXT_B_BGA1-IC,TBD!!!F74!VSS(407)!!!!
S!GND!U5D1!CN12!@baseboard_fab2_lib.baseboard_fab2(sch_1):page41_i284@chpset_lib.skx_ext_b(chips)!SKX_EXT_B_BGA1-IC,TBD!!!F74!VSS(408)!!!!
S!GND!U5D1!CN2!@baseboard_fab2_lib.baseboard_fab2(sch_1):page41_i284@chpset_lib.skx_ext_b(chips)!SKX_EXT_B_BGA1-IC,TBD!!!F74!VSS(409)!!!!
S!GND!U5D1!CM85!@baseboard_fab2_lib.baseboard_fab2(sch_1):page41_i284@chpset_lib.skx_ext_b(chips)!SKX_EXT_B_BGA1-IC,TBD!!!F74!VSS(410)!!!!
S!GND!U5D1!CM83!@baseboard_fab2_lib.baseboard_fab2(sch_1):page41_i284@chpset_lib.skx_ext_b(chips)!SKX_EXT_B_BGA1-IC,TBD!!!F74!VSS(411)!!!!
S!GND!U5D1!CM77!@baseboard_fab2_lib.baseboard_fab2(sch_1):page41_i284@chpset_lib.skx_ext_b(chips)!SKX_EXT_B_BGA1-IC,TBD!!!F74!VSS(412)!!!!
S!GND!U5D1!CM73!@baseboard_fab2_lib.baseboard_fab2(sch_1):page41_i284@chpset_lib.skx_ext_b(chips)!SKX_EXT_B_BGA1-IC,TBD!!!F74!VSS(413)!!!!
S!GND!U5D1!CM67!@baseboard_fab2_lib.baseboard_fab2(sch_1):page41_i284@chpset_lib.skx_ext_b(chips)!SKX_EXT_B_BGA1-IC,TBD!!!F74!VSS(414)!!!!
S!GND!U5D1!CM63!@baseboard_fab2_lib.baseboard_fab2(sch_1):page41_i284@chpset_lib.skx_ext_b(chips)!SKX_EXT_B_BGA1-IC,TBD!!!F74!VSS(415)!!!!
S!GND!U5D1!CM61!@baseboard_fab2_lib.baseboard_fab2(sch_1):page41_i284@chpset_lib.skx_ext_b(chips)!SKX_EXT_B_BGA1-IC,TBD!!!F74!VSS(416)!!!!
S!GND!U5D1!CM31!@baseboard_fab2_lib.baseboard_fab2(sch_1):page41_i284@chpset_lib.skx_ext_b(chips)!SKX_EXT_B_BGA1-IC,TBD!!!F74!VSS(417)!!!!
S!GND!U5D1!CM5!@baseboard_fab2_lib.baseboard_fab2(sch_1):page41_i284@chpset_lib.skx_ext_b(chips)!SKX_EXT_B_BGA1-IC,TBD!!!F74!VSS(418)!!!!
S!GND!U5D1!CM29!@baseboard_fab2_lib.baseboard_fab2(sch_1):page41_i284@chpset_lib.skx_ext_b(chips)!SKX_EXT_B_BGA1-IC,TBD!!!F74!VSS(419)!!!!
S!GND!U5D1!CM19!@baseboard_fab2_lib.baseboard_fab2(sch_1):page41_i284@chpset_lib.skx_ext_b(chips)!SKX_EXT_B_BGA1-IC,TBD!!!F74!VSS(420)!!!!
S!GND!U5D1!CL80!@baseboard_fab2_lib.baseboard_fab2(sch_1):page41_i284@chpset_lib.skx_ext_b(chips)!SKX_EXT_B_BGA1-IC,TBD!!!F74!VSS(421)!!!!
S!GND!U5D1!CL78!@baseboard_fab2_lib.baseboard_fab2(sch_1):page41_i284@chpset_lib.skx_ext_b(chips)!SKX_EXT_B_BGA1-IC,TBD!!!F74!VSS(422)!!!!
S!GND!U5D1!CL76!@baseboard_fab2_lib.baseboard_fab2(sch_1):page41_i284@chpset_lib.skx_ext_b(chips)!SKX_EXT_B_BGA1-IC,TBD!!!F74!VSS(423)!!!!
S!GND!U5D1!CL74!@baseboard_fab2_lib.baseboard_fab2(sch_1):page41_i284@chpset_lib.skx_ext_b(chips)!SKX_EXT_B_BGA1-IC,TBD!!!F74!VSS(424)!!!!
S!GND!U5D1!CL66!@baseboard_fab2_lib.baseboard_fab2(sch_1):page41_i284@chpset_lib.skx_ext_b(chips)!SKX_EXT_B_BGA1-IC,TBD!!!F74!VSS(425)!!!!
S!GND!U5D1!CL64!@baseboard_fab2_lib.baseboard_fab2(sch_1):page41_i284@chpset_lib.skx_ext_b(chips)!SKX_EXT_B_BGA1-IC,TBD!!!F74!VSS(426)!!!!
S!GND!U5D1!CL62!@baseboard_fab2_lib.baseboard_fab2(sch_1):page41_i284@chpset_lib.skx_ext_b(chips)!SKX_EXT_B_BGA1-IC,TBD!!!F74!VSS(427)!!!!
S!GND!U5D1!DR72!@baseboard_fab2_lib.baseboard_fab2(sch_1):page41_i286@chpset_lib.skx_ext_b(chips)!SKX_EXT_B_BGA1-IC,TBD!!!F72!VSS(108)!!!!
S!GND!U5D1!DR70!@baseboard_fab2_lib.baseboard_fab2(sch_1):page41_i286@chpset_lib.skx_ext_b(chips)!SKX_EXT_B_BGA1-IC,TBD!!!F72!VSS(109)!!!!
S!GND!U5D1!DR68!@baseboard_fab2_lib.baseboard_fab2(sch_1):page41_i286@chpset_lib.skx_ext_b(chips)!SKX_EXT_B_BGA1-IC,TBD!!!F72!VSS(110)!!!!
S!GND!U5D1!DR66!@baseboard_fab2_lib.baseboard_fab2(sch_1):page41_i286@chpset_lib.skx_ext_b(chips)!SKX_EXT_B_BGA1-IC,TBD!!!F72!VSS(111)!!!!
S!GND!U5D1!DR42!@baseboard_fab2_lib.baseboard_fab2(sch_1):page41_i286@chpset_lib.skx_ext_b(chips)!SKX_EXT_B_BGA1-IC,TBD!!!F72!VSS(112)!!!!
S!GND!U5D1!DR40!@baseboard_fab2_lib.baseboard_fab2(sch_1):page41_i286@chpset_lib.skx_ext_b(chips)!SKX_EXT_B_BGA1-IC,TBD!!!F72!VSS(113)!!!!
S!GND!U5D1!DR38!@baseboard_fab2_lib.baseboard_fab2(sch_1):page41_i286@chpset_lib.skx_ext_b(chips)!SKX_EXT_B_BGA1-IC,TBD!!!F72!VSS(114)!!!!
S!GND!U5D1!DR36!@baseboard_fab2_lib.baseboard_fab2(sch_1):page41_i286@chpset_lib.skx_ext_b(chips)!SKX_EXT_B_BGA1-IC,TBD!!!F72!VSS(115)!!!!
S!GND!U5D1!DR34!@baseboard_fab2_lib.baseboard_fab2(sch_1):page41_i286@chpset_lib.skx_ext_b(chips)!SKX_EXT_B_BGA1-IC,TBD!!!F72!VSS(116)!!!!
S!GND!U5D1!DR32!@baseboard_fab2_lib.baseboard_fab2(sch_1):page41_i286@chpset_lib.skx_ext_b(chips)!SKX_EXT_B_BGA1-IC,TBD!!!F72!VSS(117)!!!!
S!GND!U5D1!DR30!@baseboard_fab2_lib.baseboard_fab2(sch_1):page41_i286@chpset_lib.skx_ext_b(chips)!SKX_EXT_B_BGA1-IC,TBD!!!F72!VSS(118)!!!!
S!GND!U5D1!DR28!@baseboard_fab2_lib.baseboard_fab2(sch_1):page41_i286@chpset_lib.skx_ext_b(chips)!SKX_EXT_B_BGA1-IC,TBD!!!F72!VSS(119)!!!!
S!GND!U5D1!DR26!@baseboard_fab2_lib.baseboard_fab2(sch_1):page41_i286@chpset_lib.skx_ext_b(chips)!SKX_EXT_B_BGA1-IC,TBD!!!F72!VSS(120)!!!!
S!GND!U5D1!DR24!@baseboard_fab2_lib.baseboard_fab2(sch_1):page41_i286@chpset_lib.skx_ext_b(chips)!SKX_EXT_B_BGA1-IC,TBD!!!F72!VSS(121)!!!!
S!GND!U5D1!DR22!@baseboard_fab2_lib.baseboard_fab2(sch_1):page41_i286@chpset_lib.skx_ext_b(chips)!SKX_EXT_B_BGA1-IC,TBD!!!F72!VSS(122)!!!!
S!GND!U5D1!DR20!@baseboard_fab2_lib.baseboard_fab2(sch_1):page41_i286@chpset_lib.skx_ext_b(chips)!SKX_EXT_B_BGA1-IC,TBD!!!F72!VSS(123)!!!!
S!GND!U5D1!CL22!@baseboard_fab2_lib.baseboard_fab2(sch_1):page41_i286@chpset_lib.skx_ext_b(chips)!SKX_EXT_B_BGA1-IC,TBD!!!F72!VSS(124)!!!!
S!GND!U5D1!CA20!@baseboard_fab2_lib.baseboard_fab2(sch_1):page41_i286@chpset_lib.skx_ext_b(chips)!SKX_EXT_B_BGA1-IC,TBD!!!F72!VSS(125)!!!!
S!GND!U5D1!DR6!@baseboard_fab2_lib.baseboard_fab2(sch_1):page41_i286@chpset_lib.skx_ext_b(chips)!SKX_EXT_B_BGA1-IC,TBD!!!F72!VSS(126)!!!!
S!GND!U5D1!BR26!@baseboard_fab2_lib.baseboard_fab2(sch_1):page41_i286@chpset_lib.skx_ext_b(chips)!SKX_EXT_B_BGA1-IC,TBD!!!F72!VSS(127)!!!!
S!GND!U5D1!DP83!@baseboard_fab2_lib.baseboard_fab2(sch_1):page41_i286@chpset_lib.skx_ext_b(chips)!SKX_EXT_B_BGA1-IC,TBD!!!F72!VSS(128)!!!!
S!GND!U5D1!DP81!@baseboard_fab2_lib.baseboard_fab2(sch_1):page41_i286@chpset_lib.skx_ext_b(chips)!SKX_EXT_B_BGA1-IC,TBD!!!F72!VSS(129)!!!!
S!GND!U5D1!DP71!@baseboard_fab2_lib.baseboard_fab2(sch_1):page41_i286@chpset_lib.skx_ext_b(chips)!SKX_EXT_B_BGA1-IC,TBD!!!F72!VSS(130)!!!!
S!GND!U5D1!DP69!@baseboard_fab2_lib.baseboard_fab2(sch_1):page41_i286@chpset_lib.skx_ext_b(chips)!SKX_EXT_B_BGA1-IC,TBD!!!F72!VSS(131)!!!!
S!GND!U5D1!DP67!@baseboard_fab2_lib.baseboard_fab2(sch_1):page41_i286@chpset_lib.skx_ext_b(chips)!SKX_EXT_B_BGA1-IC,TBD!!!F72!VSS(132)!!!!
S!GND!U5D1!DN78!@baseboard_fab2_lib.baseboard_fab2(sch_1):page41_i286@chpset_lib.skx_ext_b(chips)!SKX_EXT_B_BGA1-IC,TBD!!!F72!VSS(133)!!!!
S!GND!U5D1!DN72!@baseboard_fab2_lib.baseboard_fab2(sch_1):page41_i285@chpset_lib.skx_ext_b(chips)!SKX_EXT_B_BGA1-IC,TBD!!!F73!VSS(134)!!!!
S!GND!U5D1!DN68!@baseboard_fab2_lib.baseboard_fab2(sch_1):page41_i285@chpset_lib.skx_ext_b(chips)!SKX_EXT_B_BGA1-IC,TBD!!!F73!VSS(135)!!!!
S!GND!U5D1!DN38!@baseboard_fab2_lib.baseboard_fab2(sch_1):page41_i285@chpset_lib.skx_ext_b(chips)!SKX_EXT_B_BGA1-IC,TBD!!!F73!VSS(136)!!!!
S!GND!U5D1!DN32!@baseboard_fab2_lib.baseboard_fab2(sch_1):page41_i285@chpset_lib.skx_ext_b(chips)!SKX_EXT_B_BGA1-IC,TBD!!!F73!VSS(137)!!!!
S!GND!U5D1!DN26!@baseboard_fab2_lib.baseboard_fab2(sch_1):page41_i285@chpset_lib.skx_ext_b(chips)!SKX_EXT_B_BGA1-IC,TBD!!!F73!VSS(138)!!!!
S!GND!U5D1!DN22!@baseboard_fab2_lib.baseboard_fab2(sch_1):page41_i285@chpset_lib.skx_ext_b(chips)!SKX_EXT_B_BGA1-IC,TBD!!!F73!VSS(139)!!!!
S!GND!U5D1!DN12!@baseboard_fab2_lib.baseboard_fab2(sch_1):page41_i285@chpset_lib.skx_ext_b(chips)!SKX_EXT_B_BGA1-IC,TBD!!!F73!VSS(140)!!!!
S!GND!U5D1!BH17!@baseboard_fab2_lib.baseboard_fab2(sch_1):page41_i285@chpset_lib.skx_ext_b(chips)!SKX_EXT_B_BGA1-IC,TBD!!!F73!VSS(141)!!!!
S!GND!U5D1!DN2!@baseboard_fab2_lib.baseboard_fab2(sch_1):page41_i285@chpset_lib.skx_ext_b(chips)!SKX_EXT_B_BGA1-IC,TBD!!!F73!VSS(142)!!!!
S!GND!U5D1!DM83!@baseboard_fab2_lib.baseboard_fab2(sch_1):page41_i285@chpset_lib.skx_ext_b(chips)!SKX_EXT_B_BGA1-IC,TBD!!!F73!VSS(143)!!!!
S!GND!U5D1!DM77!@baseboard_fab2_lib.baseboard_fab2(sch_1):page41_i285@chpset_lib.skx_ext_b(chips)!SKX_EXT_B_BGA1-IC,TBD!!!F73!VSS(144)!!!!
S!GND!U5D1!DM73!@baseboard_fab2_lib.baseboard_fab2(sch_1):page41_i285@chpset_lib.skx_ext_b(chips)!SKX_EXT_B_BGA1-IC,TBD!!!F73!VSS(145)!!!!
S!GND!U5D1!DM65!@baseboard_fab2_lib.baseboard_fab2(sch_1):page41_i285@chpset_lib.skx_ext_b(chips)!SKX_EXT_B_BGA1-IC,TBD!!!F73!VSS(146)!!!!
S!GND!U5D1!DM39!@baseboard_fab2_lib.baseboard_fab2(sch_1):page41_i285@chpset_lib.skx_ext_b(chips)!SKX_EXT_B_BGA1-IC,TBD!!!F73!VSS(147)!!!!
S!GND!U5D1!DM37!@baseboard_fab2_lib.baseboard_fab2(sch_1):page41_i285@chpset_lib.skx_ext_b(chips)!SKX_EXT_B_BGA1-IC,TBD!!!F73!VSS(148)!!!!
S!GND!U5D1!DM33!@baseboard_fab2_lib.baseboard_fab2(sch_1):page41_i285@chpset_lib.skx_ext_b(chips)!SKX_EXT_B_BGA1-IC,TBD!!!F73!VSS(149)!!!!
S!GND!U5D1!DM31!@baseboard_fab2_lib.baseboard_fab2(sch_1):page41_i285@chpset_lib.skx_ext_b(chips)!SKX_EXT_B_BGA1-IC,TBD!!!F73!VSS(150)!!!!
S!GND!U5D1!DM27!@baseboard_fab2_lib.baseboard_fab2(sch_1):page41_i285@chpset_lib.skx_ext_b(chips)!SKX_EXT_B_BGA1-IC,TBD!!!F73!VSS(151)!!!!
S!GND!U5D1!DM25!@baseboard_fab2_lib.baseboard_fab2(sch_1):page41_i285@chpset_lib.skx_ext_b(chips)!SKX_EXT_B_BGA1-IC,TBD!!!F73!VSS(152)!!!!
S!GND!U5D1!H45!@baseboard_fab2_lib.baseboard_fab2(sch_1):page41_i285@chpset_lib.skx_ext_b(chips)!SKX_EXT_B_BGA1-IC,TBD!!!F73!VSS(153)!!!!
S!GND!U5D1!DM15!@baseboard_fab2_lib.baseboard_fab2(sch_1):page41_i285@chpset_lib.skx_ext_b(chips)!SKX_EXT_B_BGA1-IC,TBD!!!F73!VSS(154)!!!!
S!GND!U5D1!DL80!@baseboard_fab2_lib.baseboard_fab2(sch_1):page41_i285@chpset_lib.skx_ext_b(chips)!SKX_EXT_B_BGA1-IC,TBD!!!F73!VSS(155)!!!!
S!GND!U5D1!DL78!@baseboard_fab2_lib.baseboard_fab2(sch_1):page41_i285@chpset_lib.skx_ext_b(chips)!SKX_EXT_B_BGA1-IC,TBD!!!F73!VSS(156)!!!!
S!GND!U5D1!DL76!@baseboard_fab2_lib.baseboard_fab2(sch_1):page41_i285@chpset_lib.skx_ext_b(chips)!SKX_EXT_B_BGA1-IC,TBD!!!F73!VSS(157)!!!!
S!GND!U5D1!DL74!@baseboard_fab2_lib.baseboard_fab2(sch_1):page41_i285@chpset_lib.skx_ext_b(chips)!SKX_EXT_B_BGA1-IC,TBD!!!F73!VSS(158)!!!!
S!GND!U5D1!DL70!@baseboard_fab2_lib.baseboard_fab2(sch_1):page41_i285@chpset_lib.skx_ext_b(chips)!SKX_EXT_B_BGA1-IC,TBD!!!F73!VSS(159)!!!!
S!GND!U5D1!DL68!@baseboard_fab2_lib.baseboard_fab2(sch_1):page41_i285@chpset_lib.skx_ext_b(chips)!SKX_EXT_B_BGA1-IC,TBD!!!F73!VSS(160)!!!!
S!GND!U5D1!DL40!@baseboard_fab2_lib.baseboard_fab2(sch_1):page41_i285@chpset_lib.skx_ext_b(chips)!SKX_EXT_B_BGA1-IC,TBD!!!F73!VSS(161)!!!!
S!GND!U5D1!DL36!@baseboard_fab2_lib.baseboard_fab2(sch_1):page41_i285@chpset_lib.skx_ext_b(chips)!SKX_EXT_B_BGA1-IC,TBD!!!F73!VSS(162)!!!!
S!GND!U5D1!DL34!@baseboard_fab2_lib.baseboard_fab2(sch_1):page41_i285@chpset_lib.skx_ext_b(chips)!SKX_EXT_B_BGA1-IC,TBD!!!F73!VSS(163)!!!!
S!GND!U5D1!DL30!@baseboard_fab2_lib.baseboard_fab2(sch_1):page41_i285@chpset_lib.skx_ext_b(chips)!SKX_EXT_B_BGA1-IC,TBD!!!F73!VSS(164)!!!!
S!GND!U5D1!DL28!@baseboard_fab2_lib.baseboard_fab2(sch_1):page41_i285@chpset_lib.skx_ext_b(chips)!SKX_EXT_B_BGA1-IC,TBD!!!F73!VSS(165)!!!!
S!GND!U5D1!DL24!@baseboard_fab2_lib.baseboard_fab2(sch_1):page41_i285@chpset_lib.skx_ext_b(chips)!SKX_EXT_B_BGA1-IC,TBD!!!F73!VSS(166)!!!!
S!GND!U5D1!DL22!@baseboard_fab2_lib.baseboard_fab2(sch_1):page41_i285@chpset_lib.skx_ext_b(chips)!SKX_EXT_B_BGA1-IC,TBD!!!F73!VSS(167)!!!!
S!GND!U5D1!DL4!@baseboard_fab2_lib.baseboard_fab2(sch_1):page41_i285@chpset_lib.skx_ext_b(chips)!SKX_EXT_B_BGA1-IC,TBD!!!F73!VSS(168)!!!!
S!GND!U5D1!DL18!@baseboard_fab2_lib.baseboard_fab2(sch_1):page41_i285@chpset_lib.skx_ext_b(chips)!SKX_EXT_B_BGA1-IC,TBD!!!F73!VSS(169)!!!!
S!GND!U5D1!DL16!@baseboard_fab2_lib.baseboard_fab2(sch_1):page41_i285@chpset_lib.skx_ext_b(chips)!SKX_EXT_B_BGA1-IC,TBD!!!F73!VSS(170)!!!!
S!GND!U5D1!DK85!@baseboard_fab2_lib.baseboard_fab2(sch_1):page41_i285@chpset_lib.skx_ext_b(chips)!SKX_EXT_B_BGA1-IC,TBD!!!F73!VSS(171)!!!!
S!GND!U5D1!DK83!@baseboard_fab2_lib.baseboard_fab2(sch_1):page41_i285@chpset_lib.skx_ext_b(chips)!SKX_EXT_B_BGA1-IC,TBD!!!F73!VSS(172)!!!!
S!GND!U5D1!DK77!@baseboard_fab2_lib.baseboard_fab2(sch_1):page41_i285@chpset_lib.skx_ext_b(chips)!SKX_EXT_B_BGA1-IC,TBD!!!F73!VSS(173)!!!!
S!GND!U5D1!DK75!@baseboard_fab2_lib.baseboard_fab2(sch_1):page41_i285@chpset_lib.skx_ext_b(chips)!SKX_EXT_B_BGA1-IC,TBD!!!F73!VSS(174)!!!!
S!GND!U5D1!DK73!@baseboard_fab2_lib.baseboard_fab2(sch_1):page41_i285@chpset_lib.skx_ext_b(chips)!SKX_EXT_B_BGA1-IC,TBD!!!F73!VSS(175)!!!!
S!GND!U5D1!DK41!@baseboard_fab2_lib.baseboard_fab2(sch_1):page41_i285@chpset_lib.skx_ext_b(chips)!SKX_EXT_B_BGA1-IC,TBD!!!F73!VSS(176)!!!!
S!GND!U5D1!DK39!@baseboard_fab2_lib.baseboard_fab2(sch_1):page41_i285@chpset_lib.skx_ext_b(chips)!SKX_EXT_B_BGA1-IC,TBD!!!F73!VSS(177)!!!!
S!GND!U5D1!DK35!@baseboard_fab2_lib.baseboard_fab2(sch_1):page41_i285@chpset_lib.skx_ext_b(chips)!SKX_EXT_B_BGA1-IC,TBD!!!F73!VSS(178)!!!!
S!GND!U5D1!DK29!@baseboard_fab2_lib.baseboard_fab2(sch_1):page41_i285@chpset_lib.skx_ext_b(chips)!SKX_EXT_B_BGA1-IC,TBD!!!F73!VSS(179)!!!!
S!GND!U5D1!DK23!@baseboard_fab2_lib.baseboard_fab2(sch_1):page41_i285@chpset_lib.skx_ext_b(chips)!SKX_EXT_B_BGA1-IC,TBD!!!F73!VSS(180)!!!!
S!GND!U5D1!DK7!@baseboard_fab2_lib.baseboard_fab2(sch_1):page41_i285@chpset_lib.skx_ext_b(chips)!SKX_EXT_B_BGA1-IC,TBD!!!F73!VSS(181)!!!!
S!GND!U5D1!DJ84!@baseboard_fab2_lib.baseboard_fab2(sch_1):page41_i285@chpset_lib.skx_ext_b(chips)!SKX_EXT_B_BGA1-IC,TBD!!!F73!VSS(182)!!!!
S!GND!U5D1!DJ82!@baseboard_fab2_lib.baseboard_fab2(sch_1):page41_i285@chpset_lib.skx_ext_b(chips)!SKX_EXT_B_BGA1-IC,TBD!!!F73!VSS(183)!!!!
S!GND!U5D1!DJ78!@baseboard_fab2_lib.baseboard_fab2(sch_1):page41_i285@chpset_lib.skx_ext_b(chips)!SKX_EXT_B_BGA1-IC,TBD!!!F73!VSS(184)!!!!
S!GND!U5D1!DJ74!@baseboard_fab2_lib.baseboard_fab2(sch_1):page41_i285@chpset_lib.skx_ext_b(chips)!SKX_EXT_B_BGA1-IC,TBD!!!F73!VSS(185)!!!!
S!GND!U5D1!DJ68!@baseboard_fab2_lib.baseboard_fab2(sch_1):page41_i285@chpset_lib.skx_ext_b(chips)!SKX_EXT_B_BGA1-IC,TBD!!!F73!VSS(186)!!!!
S!GND!U5D1!DJ42!@baseboard_fab2_lib.baseboard_fab2(sch_1):page41_i285@chpset_lib.skx_ext_b(chips)!SKX_EXT_B_BGA1-IC,TBD!!!F73!VSS(187)!!!!
S!GND!U5D1!DJ38!@baseboard_fab2_lib.baseboard_fab2(sch_1):page41_i285@chpset_lib.skx_ext_b(chips)!SKX_EXT_B_BGA1-IC,TBD!!!F73!VSS(188)!!!!
S!GND!U5D1!DJ22!@baseboard_fab2_lib.baseboard_fab2(sch_1):page41_i285@chpset_lib.skx_ext_b(chips)!SKX_EXT_B_BGA1-IC,TBD!!!F73!VSS(189)!!!!
S!GND!U5D1!H47!@baseboard_fab2_lib.baseboard_fab2(sch_1):page41_i285@chpset_lib.skx_ext_b(chips)!SKX_EXT_B_BGA1-IC,TBD!!!F73!VSS(190)!!!!
S!GND!U5D1!DJ10!@baseboard_fab2_lib.baseboard_fab2(sch_1):page41_i285@chpset_lib.skx_ext_b(chips)!SKX_EXT_B_BGA1-IC,TBD!!!F73!VSS(191)!!!!
S!GND!U5D1!DJ2!@baseboard_fab2_lib.baseboard_fab2(sch_1):page41_i285@chpset_lib.skx_ext_b(chips)!SKX_EXT_B_BGA1-IC,TBD!!!F73!VSS(192)!!!!
S!GND!U5D1!DH83!@baseboard_fab2_lib.baseboard_fab2(sch_1):page41_i285@chpset_lib.skx_ext_b(chips)!SKX_EXT_B_BGA1-IC,TBD!!!F73!VSS(193)!!!!
S!GND!U5D1!DH81!@baseboard_fab2_lib.baseboard_fab2(sch_1):page41_i285@chpset_lib.skx_ext_b(chips)!SKX_EXT_B_BGA1-IC,TBD!!!F73!VSS(194)!!!!
S!GND!U5D1!DH79!@baseboard_fab2_lib.baseboard_fab2(sch_1):page41_i285@chpset_lib.skx_ext_b(chips)!SKX_EXT_B_BGA1-IC,TBD!!!F73!VSS(195)!!!!
S!GND!U5D1!DH73!@baseboard_fab2_lib.baseboard_fab2(sch_1):page41_i285@chpset_lib.skx_ext_b(chips)!SKX_EXT_B_BGA1-IC,TBD!!!F73!VSS(196)!!!!
S!GND!U5D1!DH71!@baseboard_fab2_lib.baseboard_fab2(sch_1):page41_i285@chpset_lib.skx_ext_b(chips)!SKX_EXT_B_BGA1-IC,TBD!!!F73!VSS(197)!!!!
S!GND!U5D1!DH67!@baseboard_fab2_lib.baseboard_fab2(sch_1):page41_i285@chpset_lib.skx_ext_b(chips)!SKX_EXT_B_BGA1-IC,TBD!!!F73!VSS(198)!!!!
S!GND!U5D1!DH41!@baseboard_fab2_lib.baseboard_fab2(sch_1):page41_i285@chpset_lib.skx_ext_b(chips)!SKX_EXT_B_BGA1-IC,TBD!!!F73!VSS(199)!!!!
S!GND!U5D1!DH37!@baseboard_fab2_lib.baseboard_fab2(sch_1):page41_i285@chpset_lib.skx_ext_b(chips)!SKX_EXT_B_BGA1-IC,TBD!!!F73!VSS(200)!!!!
S!GND!U5D1!DH35!@baseboard_fab2_lib.baseboard_fab2(sch_1):page41_i285@chpset_lib.skx_ext_b(chips)!SKX_EXT_B_BGA1-IC,TBD!!!F73!VSS(201)!!!!
S!GND!U5D1!DH33!@baseboard_fab2_lib.baseboard_fab2(sch_1):page41_i285@chpset_lib.skx_ext_b(chips)!SKX_EXT_B_BGA1-IC,TBD!!!F73!VSS(202)!!!!
S!GND!U5D1!DH31!@baseboard_fab2_lib.baseboard_fab2(sch_1):page41_i285@chpset_lib.skx_ext_b(chips)!SKX_EXT_B_BGA1-IC,TBD!!!F73!VSS(203)!!!!
S!GND!U5D1!DH29!@baseboard_fab2_lib.baseboard_fab2(sch_1):page41_i285@chpset_lib.skx_ext_b(chips)!SKX_EXT_B_BGA1-IC,TBD!!!F73!VSS(204)!!!!
S!GND!U5D1!DH27!@baseboard_fab2_lib.baseboard_fab2(sch_1):page41_i285@chpset_lib.skx_ext_b(chips)!SKX_EXT_B_BGA1-IC,TBD!!!F73!VSS(205)!!!!
S!GND!U5D1!DH25!@baseboard_fab2_lib.baseboard_fab2(sch_1):page41_i285@chpset_lib.skx_ext_b(chips)!SKX_EXT_B_BGA1-IC,TBD!!!F73!VSS(206)!!!!
S!GND!U5D1!DH23!@baseboard_fab2_lib.baseboard_fab2(sch_1):page41_i285@chpset_lib.skx_ext_b(chips)!SKX_EXT_B_BGA1-IC,TBD!!!F73!VSS(207)!!!!
S!GND!U5D1!DH15!@baseboard_fab2_lib.baseboard_fab2(sch_1):page41_i285@chpset_lib.skx_ext_b(chips)!SKX_EXT_B_BGA1-IC,TBD!!!F73!VSS(208)!!!!
S!GND!U5D1!DH13!@baseboard_fab2_lib.baseboard_fab2(sch_1):page41_i285@chpset_lib.skx_ext_b(chips)!SKX_EXT_B_BGA1-IC,TBD!!!F73!VSS(209)!!!!
S!GND!U5D1!DG82!@baseboard_fab2_lib.baseboard_fab2(sch_1):page41_i285@chpset_lib.skx_ext_b(chips)!SKX_EXT_B_BGA1-IC,TBD!!!F73!VSS(210)!!!!
S!GND!U5D1!DG80!@baseboard_fab2_lib.baseboard_fab2(sch_1):page41_i285@chpset_lib.skx_ext_b(chips)!SKX_EXT_B_BGA1-IC,TBD!!!F73!VSS(211)!!!!
S!GND!U5D1!DG78!@baseboard_fab2_lib.baseboard_fab2(sch_1):page41_i285@chpset_lib.skx_ext_b(chips)!SKX_EXT_B_BGA1-IC,TBD!!!F73!VSS(212)!!!!
S!GND!U5D1!DG76!@baseboard_fab2_lib.baseboard_fab2(sch_1):page41_i285@chpset_lib.skx_ext_b(chips)!SKX_EXT_B_BGA1-IC,TBD!!!F73!VSS(213)!!!!
S!GND!U5D1!DG68!@baseboard_fab2_lib.baseboard_fab2(sch_1):page41_i285@chpset_lib.skx_ext_b(chips)!SKX_EXT_B_BGA1-IC,TBD!!!F73!VSS(214)!!!!
S!GND!U5D1!DG66!@baseboard_fab2_lib.baseboard_fab2(sch_1):page41_i285@chpset_lib.skx_ext_b(chips)!SKX_EXT_B_BGA1-IC,TBD!!!F73!VSS(215)!!!!
S!GND!U5D1!DG24!@baseboard_fab2_lib.baseboard_fab2(sch_1):page41_i285@chpset_lib.skx_ext_b(chips)!SKX_EXT_B_BGA1-IC,TBD!!!F73!VSS(216)!!!!
S!GND!U5D1!DG16!@baseboard_fab2_lib.baseboard_fab2(sch_1):page41_i285@chpset_lib.skx_ext_b(chips)!SKX_EXT_B_BGA1-IC,TBD!!!F73!VSS(217)!!!!
S!GND!U5D1!DG14!@baseboard_fab2_lib.baseboard_fab2(sch_1):page41_i285@chpset_lib.skx_ext_b(chips)!SKX_EXT_B_BGA1-IC,TBD!!!F73!VSS(218)!!!!
S!GND!U5D1!H49!@baseboard_fab2_lib.baseboard_fab2(sch_1):page41_i285@chpset_lib.skx_ext_b(chips)!SKX_EXT_B_BGA1-IC,TBD!!!F73!VSS(219)!!!!
S!GND!U5D1!DG2!@baseboard_fab2_lib.baseboard_fab2(sch_1):page41_i285@chpset_lib.skx_ext_b(chips)!SKX_EXT_B_BGA1-IC,TBD!!!F73!VSS(220)!!!!
S!GND!U5D1!DF85!@baseboard_fab2_lib.baseboard_fab2(sch_1):page41_i285@chpset_lib.skx_ext_b(chips)!SKX_EXT_B_BGA1-IC,TBD!!!F73!VSS(221)!!!!
S!GND!U5D1!DF83!@baseboard_fab2_lib.baseboard_fab2(sch_1):page41_i285@chpset_lib.skx_ext_b(chips)!SKX_EXT_B_BGA1-IC,TBD!!!F73!VSS(222)!!!!
S!GND!U5D1!DF79!@baseboard_fab2_lib.baseboard_fab2(sch_1):page41_i285@chpset_lib.skx_ext_b(chips)!SKX_EXT_B_BGA1-IC,TBD!!!F73!VSS(223)!!!!
S!GND!U5D1!DF73!@baseboard_fab2_lib.baseboard_fab2(sch_1):page41_i285@chpset_lib.skx_ext_b(chips)!SKX_EXT_B_BGA1-IC,TBD!!!F73!VSS(224)!!!!
S!GND!U5D1!DF69!@baseboard_fab2_lib.baseboard_fab2(sch_1):page41_i285@chpset_lib.skx_ext_b(chips)!SKX_EXT_B_BGA1-IC,TBD!!!F73!VSS(225)!!!!
S!GND!U5D1!DF65!@baseboard_fab2_lib.baseboard_fab2(sch_1):page41_i285@chpset_lib.skx_ext_b(chips)!SKX_EXT_B_BGA1-IC,TBD!!!F73!VSS(226)!!!!
S!GND!U5D1!DF41!@baseboard_fab2_lib.baseboard_fab2(sch_1):page41_i285@chpset_lib.skx_ext_b(chips)!SKX_EXT_B_BGA1-IC,TBD!!!F73!VSS(227)!!!!
S!GND!U5D1!DF39!@baseboard_fab2_lib.baseboard_fab2(sch_1):page41_i285@chpset_lib.skx_ext_b(chips)!SKX_EXT_B_BGA1-IC,TBD!!!F73!VSS(228)!!!!
S!GND!U5D1!DF37!@baseboard_fab2_lib.baseboard_fab2(sch_1):page41_i285@chpset_lib.skx_ext_b(chips)!SKX_EXT_B_BGA1-IC,TBD!!!F73!VSS(229)!!!!
S!GND!U5D1!DF35!@baseboard_fab2_lib.baseboard_fab2(sch_1):page41_i285@chpset_lib.skx_ext_b(chips)!SKX_EXT_B_BGA1-IC,TBD!!!F73!VSS(230)!!!!
S!GND!U5D1!DF29!@baseboard_fab2_lib.baseboard_fab2(sch_1):page41_i285@chpset_lib.skx_ext_b(chips)!SKX_EXT_B_BGA1-IC,TBD!!!F73!VSS(231)!!!!
S!GND!U5D1!DF19!@baseboard_fab2_lib.baseboard_fab2(sch_1):page41_i285@chpset_lib.skx_ext_b(chips)!SKX_EXT_B_BGA1-IC,TBD!!!F73!VSS(232)!!!!
S!GND!U5D1!H51!@baseboard_fab2_lib.baseboard_fab2(sch_1):page41_i285@chpset_lib.skx_ext_b(chips)!SKX_EXT_B_BGA1-IC,TBD!!!F73!VSS(233)!!!!
S!GND!U5D1!DF7!@baseboard_fab2_lib.baseboard_fab2(sch_1):page41_i285@chpset_lib.skx_ext_b(chips)!SKX_EXT_B_BGA1-IC,TBD!!!F73!VSS(234)!!!!
S!GND!U5D1!DF5!@baseboard_fab2_lib.baseboard_fab2(sch_1):page41_i285@chpset_lib.skx_ext_b(chips)!SKX_EXT_B_BGA1-IC,TBD!!!F73!VSS(235)!!!!
S!GND!U5D1!DE78!@baseboard_fab2_lib.baseboard_fab2(sch_1):page41_i285@chpset_lib.skx_ext_b(chips)!SKX_EXT_B_BGA1-IC,TBD!!!F73!VSS(236)!!!!
S!GND!U5D1!DE72!@baseboard_fab2_lib.baseboard_fab2(sch_1):page41_i285@chpset_lib.skx_ext_b(chips)!SKX_EXT_B_BGA1-IC,TBD!!!F73!VSS(237)!!!!
S!GND!U5D1!DE70!@baseboard_fab2_lib.baseboard_fab2(sch_1):page41_i285@chpset_lib.skx_ext_b(chips)!SKX_EXT_B_BGA1-IC,TBD!!!F73!VSS(238)!!!!
S!GND!U5D1!DE64!@baseboard_fab2_lib.baseboard_fab2(sch_1):page41_i285@chpset_lib.skx_ext_b(chips)!SKX_EXT_B_BGA1-IC,TBD!!!F73!VSS(239)!!!!
S!GND!U5D1!DE36!@baseboard_fab2_lib.baseboard_fab2(sch_1):page41_i285@chpset_lib.skx_ext_b(chips)!SKX_EXT_B_BGA1-IC,TBD!!!F73!VSS(240)!!!!
S!GND!U5D1!DE34!@baseboard_fab2_lib.baseboard_fab2(sch_1):page41_i285@chpset_lib.skx_ext_b(chips)!SKX_EXT_B_BGA1-IC,TBD!!!F73!VSS(241)!!!!
S!GND!U5D1!DE30!@baseboard_fab2_lib.baseboard_fab2(sch_1):page41_i285@chpset_lib.skx_ext_b(chips)!SKX_EXT_B_BGA1-IC,TBD!!!F73!VSS(242)!!!!
S!GND!U5D1!DE28!@baseboard_fab2_lib.baseboard_fab2(sch_1):page41_i285@chpset_lib.skx_ext_b(chips)!SKX_EXT_B_BGA1-IC,TBD!!!F73!VSS(243)!!!!
S!GND!U5D1!DE24!@baseboard_fab2_lib.baseboard_fab2(sch_1):page41_i285@chpset_lib.skx_ext_b(chips)!SKX_EXT_B_BGA1-IC,TBD!!!F73!VSS(244)!!!!
S!GND!U5D1!DE20!@baseboard_fab2_lib.baseboard_fab2(sch_1):page41_i285@chpset_lib.skx_ext_b(chips)!SKX_EXT_B_BGA1-IC,TBD!!!F73!VSS(245)!!!!
S!GND!U5D1!DE18!@baseboard_fab2_lib.baseboard_fab2(sch_1):page41_i285@chpset_lib.skx_ext_b(chips)!SKX_EXT_B_BGA1-IC,TBD!!!F73!VSS(246)!!!!
S!GND!U5D1!DE8!@baseboard_fab2_lib.baseboard_fab2(sch_1):page41_i285@chpset_lib.skx_ext_b(chips)!SKX_EXT_B_BGA1-IC,TBD!!!F73!VSS(247)!!!!
S!GND!U5D1!DE6!@baseboard_fab2_lib.baseboard_fab2(sch_1):page41_i285@chpset_lib.skx_ext_b(chips)!SKX_EXT_B_BGA1-IC,TBD!!!F73!VSS(248)!!!!
S!GND!U5D1!DD83!@baseboard_fab2_lib.baseboard_fab2(sch_1):page41_i285@chpset_lib.skx_ext_b(chips)!SKX_EXT_B_BGA1-IC,TBD!!!F73!VSS(249)!!!!
S!GND!U5D1!DD81!@baseboard_fab2_lib.baseboard_fab2(sch_1):page41_i285@chpset_lib.skx_ext_b(chips)!SKX_EXT_B_BGA1-IC,TBD!!!F73!VSS(250)!!!!
S!GND!U5D1!DD75!@baseboard_fab2_lib.baseboard_fab2(sch_1):page41_i285@chpset_lib.skx_ext_b(chips)!SKX_EXT_B_BGA1-IC,TBD!!!F73!VSS(251)!!!!
S!GND!U5D1!DD73!@baseboard_fab2_lib.baseboard_fab2(sch_1):page41_i285@chpset_lib.skx_ext_b(chips)!SKX_EXT_B_BGA1-IC,TBD!!!F73!VSS(252)!!!!
S!GND!U5D1!DD71!@baseboard_fab2_lib.baseboard_fab2(sch_1):page41_i285@chpset_lib.skx_ext_b(chips)!SKX_EXT_B_BGA1-IC,TBD!!!F73!VSS(253)!!!!
S!GND!U5D1!DD37!@baseboard_fab2_lib.baseboard_fab2(sch_1):page41_i285@chpset_lib.skx_ext_b(chips)!SKX_EXT_B_BGA1-IC,TBD!!!F73!VSS(254)!!!!
S!GND!U5D1!DD33!@baseboard_fab2_lib.baseboard_fab2(sch_1):page41_i285@chpset_lib.skx_ext_b(chips)!SKX_EXT_B_BGA1-IC,TBD!!!F73!VSS(255)!!!!
S!GND!U5D1!DD31!@baseboard_fab2_lib.baseboard_fab2(sch_1):page41_i285@chpset_lib.skx_ext_b(chips)!SKX_EXT_B_BGA1-IC,TBD!!!F73!VSS(256)!!!!
S!GND!U5D1!DD27!@baseboard_fab2_lib.baseboard_fab2(sch_1):page41_i285@chpset_lib.skx_ext_b(chips)!SKX_EXT_B_BGA1-IC,TBD!!!F73!VSS(257)!!!!
S!GND!U5D1!DD23!@baseboard_fab2_lib.baseboard_fab2(sch_1):page41_i285@chpset_lib.skx_ext_b(chips)!SKX_EXT_B_BGA1-IC,TBD!!!F73!VSS(258)!!!!
S!GND!U5D1!DD11!@baseboard_fab2_lib.baseboard_fab2(sch_1):page41_i285@chpset_lib.skx_ext_b(chips)!SKX_EXT_B_BGA1-IC,TBD!!!F73!VSS(259)!!!!
S!GND!U5D1!DC86!@baseboard_fab2_lib.baseboard_fab2(sch_1):page41_i285@chpset_lib.skx_ext_b(chips)!SKX_EXT_B_BGA1-IC,TBD!!!F73!VSS(260)!!!!
S!GND!U5D1!DC84!@baseboard_fab2_lib.baseboard_fab2(sch_1):page41_i285@chpset_lib.skx_ext_b(chips)!SKX_EXT_B_BGA1-IC,TBD!!!F73!VSS(261)!!!!
S!GND!U5D1!DC78!@baseboard_fab2_lib.baseboard_fab2(sch_1):page41_i285@chpset_lib.skx_ext_b(chips)!SKX_EXT_B_BGA1-IC,TBD!!!F73!VSS(262)!!!!
S!GND!U5D1!DC70!@baseboard_fab2_lib.baseboard_fab2(sch_1):page41_i285@chpset_lib.skx_ext_b(chips)!SKX_EXT_B_BGA1-IC,TBD!!!F73!VSS(263)!!!!
S!GND!U5D1!DC68!@baseboard_fab2_lib.baseboard_fab2(sch_1):page41_i285@chpset_lib.skx_ext_b(chips)!SKX_EXT_B_BGA1-IC,TBD!!!F73!VSS(264)!!!!
S!GND!U5D1!DC66!@baseboard_fab2_lib.baseboard_fab2(sch_1):page41_i285@chpset_lib.skx_ext_b(chips)!SKX_EXT_B_BGA1-IC,TBD!!!F73!VSS(265)!!!!
S!GND!U5D1!DC64!@baseboard_fab2_lib.baseboard_fab2(sch_1):page41_i285@chpset_lib.skx_ext_b(chips)!SKX_EXT_B_BGA1-IC,TBD!!!F73!VSS(266)!!!!
S!GND!U5D1!DC42!@baseboard_fab2_lib.baseboard_fab2(sch_1):page41_i285@chpset_lib.skx_ext_b(chips)!SKX_EXT_B_BGA1-IC,TBD!!!F73!VSS(267)!!!!
S!GND!U5D1!EF79!@baseboard_fab2_lib.baseboard_fab2(sch_1):page41_i286@chpset_lib.skx_ext_b(chips)!SKX_EXT_B_BGA1-IC,TBD!!!F72!VSS(0)!!!!
S!GND!U5D1!DT69!@baseboard_fab2_lib.baseboard_fab2(sch_1):page41_i286@chpset_lib.skx_ext_b(chips)!SKX_EXT_B_BGA1-IC,TBD!!!F72!VSS(100)!!!!
S!GND!U5D1!DT65!@baseboard_fab2_lib.baseboard_fab2(sch_1):page41_i286@chpset_lib.skx_ext_b(chips)!SKX_EXT_B_BGA1-IC,TBD!!!F72!VSS(101)!!!!
S!GND!U5D1!DH21!@baseboard_fab2_lib.baseboard_fab2(sch_1):page41_i286@chpset_lib.skx_ext_b(chips)!SKX_EXT_B_BGA1-IC,TBD!!!F72!VSS(102)!!!!
S!GND!U5D1!DT17!@baseboard_fab2_lib.baseboard_fab2(sch_1):page41_i286@chpset_lib.skx_ext_b(chips)!SKX_EXT_B_BGA1-IC,TBD!!!F72!VSS(103)!!!!
S!GND!U5D1!DT3!@baseboard_fab2_lib.baseboard_fab2(sch_1):page41_i286@chpset_lib.skx_ext_b(chips)!SKX_EXT_B_BGA1-IC,TBD!!!F72!VSS(104)!!!!
S!GND!U5D1!DR78!@baseboard_fab2_lib.baseboard_fab2(sch_1):page41_i286@chpset_lib.skx_ext_b(chips)!SKX_EXT_B_BGA1-IC,TBD!!!F72!VSS(105)!!!!
S!GND!U5D1!DR76!@baseboard_fab2_lib.baseboard_fab2(sch_1):page41_i286@chpset_lib.skx_ext_b(chips)!SKX_EXT_B_BGA1-IC,TBD!!!F72!VSS(106)!!!!
S!GND!U5D1!DR74!@baseboard_fab2_lib.baseboard_fab2(sch_1):page41_i286@chpset_lib.skx_ext_b(chips)!SKX_EXT_B_BGA1-IC,TBD!!!F72!VSS(107)!!!!
S!GND!U5D1!EE24!@baseboard_fab2_lib.baseboard_fab2(sch_1):page41_i286@chpset_lib.skx_ext_b(chips)!SKX_EXT_B_BGA1-IC,TBD!!!F72!VSS(10)!!!!
S!GND!U5D1!ED77!@baseboard_fab2_lib.baseboard_fab2(sch_1):page41_i286@chpset_lib.skx_ext_b(chips)!SKX_EXT_B_BGA1-IC,TBD!!!F72!VSS(11)!!!!
S!GND!U5D1!ED35!@baseboard_fab2_lib.baseboard_fab2(sch_1):page41_i286@chpset_lib.skx_ext_b(chips)!SKX_EXT_B_BGA1-IC,TBD!!!F72!VSS(12)!!!!
S!GND!U5D1!ED29!@baseboard_fab2_lib.baseboard_fab2(sch_1):page41_i286@chpset_lib.skx_ext_b(chips)!SKX_EXT_B_BGA1-IC,TBD!!!F72!VSS(13)!!!!
S!GND!U5D1!ED23!@baseboard_fab2_lib.baseboard_fab2(sch_1):page41_i286@chpset_lib.skx_ext_b(chips)!SKX_EXT_B_BGA1-IC,TBD!!!F72!VSS(14)!!!!
S!GND!U5D1!ED15!@baseboard_fab2_lib.baseboard_fab2(sch_1):page41_i286@chpset_lib.skx_ext_b(chips)!SKX_EXT_B_BGA1-IC,TBD!!!F72!VSS(15)!!!!
S!GND!U5D1!ED11!@baseboard_fab2_lib.baseboard_fab2(sch_1):page41_i286@chpset_lib.skx_ext_b(chips)!SKX_EXT_B_BGA1-IC,TBD!!!F72!VSS(16)!!!!
S!GND!U5D1!EC76!@baseboard_fab2_lib.baseboard_fab2(sch_1):page41_i286@chpset_lib.skx_ext_b(chips)!SKX_EXT_B_BGA1-IC,TBD!!!F72!VSS(17)!!!!
S!GND!U5D1!EC74!@baseboard_fab2_lib.baseboard_fab2(sch_1):page41_i286@chpset_lib.skx_ext_b(chips)!SKX_EXT_B_BGA1-IC,TBD!!!F72!VSS(18)!!!!
S!GND!U5D1!EC72!@baseboard_fab2_lib.baseboard_fab2(sch_1):page41_i286@chpset_lib.skx_ext_b(chips)!SKX_EXT_B_BGA1-IC,TBD!!!F72!VSS(19)!!!!
S!GND!U5D1!EF75!@baseboard_fab2_lib.baseboard_fab2(sch_1):page41_i286@chpset_lib.skx_ext_b(chips)!SKX_EXT_B_BGA1-IC,TBD!!!F72!VSS(1)!!!!
S!GND!U5D1!EC70!@baseboard_fab2_lib.baseboard_fab2(sch_1):page41_i286@chpset_lib.skx_ext_b(chips)!SKX_EXT_B_BGA1-IC,TBD!!!F72!VSS(20)!!!!
S!GND!U5D1!EC10!@baseboard_fab2_lib.baseboard_fab2(sch_1):page41_i286@chpset_lib.skx_ext_b(chips)!SKX_EXT_B_BGA1-IC,TBD!!!F72!VSS(21)!!!!
S!GND!U5D1!EB69!@baseboard_fab2_lib.baseboard_fab2(sch_1):page41_i286@chpset_lib.skx_ext_b(chips)!SKX_EXT_B_BGA1-IC,TBD!!!F72!VSS(22)!!!!
S!GND!U5D1!EB65!@baseboard_fab2_lib.baseboard_fab2(sch_1):page41_i286@chpset_lib.skx_ext_b(chips)!SKX_EXT_B_BGA1-IC,TBD!!!F72!VSS(23)!!!!
S!GND!U5D1!EB41!@baseboard_fab2_lib.baseboard_fab2(sch_1):page41_i286@chpset_lib.skx_ext_b(chips)!SKX_EXT_B_BGA1-IC,TBD!!!F72!VSS(24)!!!!
S!GND!U5D1!EB39!@baseboard_fab2_lib.baseboard_fab2(sch_1):page41_i286@chpset_lib.skx_ext_b(chips)!SKX_EXT_B_BGA1-IC,TBD!!!F72!VSS(25)!!!!
S!GND!U5D1!EB37!@baseboard_fab2_lib.baseboard_fab2(sch_1):page41_i286@chpset_lib.skx_ext_b(chips)!SKX_EXT_B_BGA1-IC,TBD!!!F72!VSS(26)!!!!
S!GND!U5D1!EB35!@baseboard_fab2_lib.baseboard_fab2(sch_1):page41_i286@chpset_lib.skx_ext_b(chips)!SKX_EXT_B_BGA1-IC,TBD!!!F72!VSS(27)!!!!
S!GND!U5D1!EB33!@baseboard_fab2_lib.baseboard_fab2(sch_1):page41_i286@chpset_lib.skx_ext_b(chips)!SKX_EXT_B_BGA1-IC,TBD!!!F72!VSS(28)!!!!
S!GND!U5D1!EB31!@baseboard_fab2_lib.baseboard_fab2(sch_1):page41_i286@chpset_lib.skx_ext_b(chips)!SKX_EXT_B_BGA1-IC,TBD!!!F72!VSS(29)!!!!
S!GND!U5D1!EF71!@baseboard_fab2_lib.baseboard_fab2(sch_1):page41_i286@chpset_lib.skx_ext_b(chips)!SKX_EXT_B_BGA1-IC,TBD!!!F72!VSS(2)!!!!
S!GND!U5D1!EB29!@baseboard_fab2_lib.baseboard_fab2(sch_1):page41_i286@chpset_lib.skx_ext_b(chips)!SKX_EXT_B_BGA1-IC,TBD!!!F72!VSS(30)!!!!
S!GND!U5D1!EB27!@baseboard_fab2_lib.baseboard_fab2(sch_1):page41_i286@chpset_lib.skx_ext_b(chips)!SKX_EXT_B_BGA1-IC,TBD!!!F72!VSS(31)!!!!
S!GND!U5D1!EB25!@baseboard_fab2_lib.baseboard_fab2(sch_1):page41_i286@chpset_lib.skx_ext_b(chips)!SKX_EXT_B_BGA1-IC,TBD!!!F72!VSS(32)!!!!
S!GND!U5D1!EB23!@baseboard_fab2_lib.baseboard_fab2(sch_1):page41_i286@chpset_lib.skx_ext_b(chips)!SKX_EXT_B_BGA1-IC,TBD!!!F72!VSS(33)!!!!
S!GND!U5D1!BR18!@baseboard_fab2_lib.baseboard_fab2(sch_1):page41_i286@chpset_lib.skx_ext_b(chips)!SKX_EXT_B_BGA1-IC,TBD!!!F72!VSS(34)!!!!
S!GND!U5D1!EB13!@baseboard_fab2_lib.baseboard_fab2(sch_1):page41_i286@chpset_lib.skx_ext_b(chips)!SKX_EXT_B_BGA1-IC,TBD!!!F72!VSS(35)!!!!
S!GND!U5D1!EA82!@baseboard_fab2_lib.baseboard_fab2(sch_1):page41_i286@chpset_lib.skx_ext_b(chips)!SKX_EXT_B_BGA1-IC,TBD!!!F72!VSS(36)!!!!
S!GND!U5D1!EA80!@baseboard_fab2_lib.baseboard_fab2(sch_1):page41_i286@chpset_lib.skx_ext_b(chips)!SKX_EXT_B_BGA1-IC,TBD!!!F72!VSS(37)!!!!
S!GND!U5D1!EA78!@baseboard_fab2_lib.baseboard_fab2(sch_1):page41_i286@chpset_lib.skx_ext_b(chips)!SKX_EXT_B_BGA1-IC,TBD!!!F72!VSS(38)!!!!
S!GND!U5D1!EA76!@baseboard_fab2_lib.baseboard_fab2(sch_1):page41_i286@chpset_lib.skx_ext_b(chips)!SKX_EXT_B_BGA1-IC,TBD!!!F72!VSS(39)!!!!
S!GND!U5D1!EE78!@baseboard_fab2_lib.baseboard_fab2(sch_1):page41_i286@chpset_lib.skx_ext_b(chips)!SKX_EXT_B_BGA1-IC,TBD!!!F72!VSS(3)!!!!
S!GND!U5D1!EA70!@baseboard_fab2_lib.baseboard_fab2(sch_1):page41_i286@chpset_lib.skx_ext_b(chips)!SKX_EXT_B_BGA1-IC,TBD!!!F72!VSS(40)!!!!
S!GND!U5D1!EA64!@baseboard_fab2_lib.baseboard_fab2(sch_1):page41_i286@chpset_lib.skx_ext_b(chips)!SKX_EXT_B_BGA1-IC,TBD!!!F72!VSS(41)!!!!
S!GND!U5D1!EA42!@baseboard_fab2_lib.baseboard_fab2(sch_1):page41_i286@chpset_lib.skx_ext_b(chips)!SKX_EXT_B_BGA1-IC,TBD!!!F72!VSS(42)!!!!
S!GND!U5D1!EA22!@baseboard_fab2_lib.baseboard_fab2(sch_1):page41_i286@chpset_lib.skx_ext_b(chips)!SKX_EXT_B_BGA1-IC,TBD!!!F72!VSS(43)!!!!
S!GND!U5D1!EA20!@baseboard_fab2_lib.baseboard_fab2(sch_1):page41_i286@chpset_lib.skx_ext_b(chips)!SKX_EXT_B_BGA1-IC,TBD!!!F72!VSS(44)!!!!
S!GND!U5D1!EA16!@baseboard_fab2_lib.baseboard_fab2(sch_1):page41_i286@chpset_lib.skx_ext_b(chips)!SKX_EXT_B_BGA1-IC,TBD!!!F72!VSS(45)!!!!
S!GND!U5D1!J16!@baseboard_fab2_lib.baseboard_fab2(sch_1):page41_i286@chpset_lib.skx_ext_b(chips)!SKX_EXT_B_BGA1-IC,TBD!!!F72!VSS(46)!!!!
S!GND!U5D1!EA6!@baseboard_fab2_lib.baseboard_fab2(sch_1):page41_i286@chpset_lib.skx_ext_b(chips)!SKX_EXT_B_BGA1-IC,TBD!!!F72!VSS(47)!!!!
S!GND!U5D1!DY75!@baseboard_fab2_lib.baseboard_fab2(sch_1):page41_i286@chpset_lib.skx_ext_b(chips)!SKX_EXT_B_BGA1-IC,TBD!!!F72!VSS(48)!!!!
S!GND!U5D1!DY71!@baseboard_fab2_lib.baseboard_fab2(sch_1):page41_i286@chpset_lib.skx_ext_b(chips)!SKX_EXT_B_BGA1-IC,TBD!!!F72!VSS(49)!!!!
S!GND!U5D1!EE76!@baseboard_fab2_lib.baseboard_fab2(sch_1):page41_i286@chpset_lib.skx_ext_b(chips)!SKX_EXT_B_BGA1-IC,TBD!!!F72!VSS(4)!!!!
S!GND!U5D1!DY41!@baseboard_fab2_lib.baseboard_fab2(sch_1):page41_i286@chpset_lib.skx_ext_b(chips)!SKX_EXT_B_BGA1-IC,TBD!!!F72!VSS(50)!!!!
S!GND!U5D1!DY35!@baseboard_fab2_lib.baseboard_fab2(sch_1):page41_i286@chpset_lib.skx_ext_b(chips)!SKX_EXT_B_BGA1-IC,TBD!!!F72!VSS(51)!!!!
S!GND!U5D1!DY29!@baseboard_fab2_lib.baseboard_fab2(sch_1):page41_i286@chpset_lib.skx_ext_b(chips)!SKX_EXT_B_BGA1-IC,TBD!!!F72!VSS(52)!!!!
S!GND!U5D1!DY23!@baseboard_fab2_lib.baseboard_fab2(sch_1):page41_i286@chpset_lib.skx_ext_b(chips)!SKX_EXT_B_BGA1-IC,TBD!!!F72!VSS(53)!!!!
S!GND!U5D1!DY19!@baseboard_fab2_lib.baseboard_fab2(sch_1):page41_i286@chpset_lib.skx_ext_b(chips)!SKX_EXT_B_BGA1-IC,TBD!!!F72!VSS(54)!!!!
S!GND!U5D1!DY5!@baseboard_fab2_lib.baseboard_fab2(sch_1):page41_i286@chpset_lib.skx_ext_b(chips)!SKX_EXT_B_BGA1-IC,TBD!!!F72!VSS(55)!!!!
S!GND!U5D1!DW84!@baseboard_fab2_lib.baseboard_fab2(sch_1):page41_i286@chpset_lib.skx_ext_b(chips)!SKX_EXT_B_BGA1-IC,TBD!!!F72!VSS(56)!!!!
S!GND!U5D1!DW82!@baseboard_fab2_lib.baseboard_fab2(sch_1):page41_i286@chpset_lib.skx_ext_b(chips)!SKX_EXT_B_BGA1-IC,TBD!!!F72!VSS(57)!!!!
S!GND!U5D1!DW8!@baseboard_fab2_lib.baseboard_fab2(sch_1):page41_i286@chpset_lib.skx_ext_b(chips)!SKX_EXT_B_BGA1-IC,TBD!!!F72!VSS(58)!!!!
S!GND!U5D1!DW76!@baseboard_fab2_lib.baseboard_fab2(sch_1):page41_i286@chpset_lib.skx_ext_b(chips)!SKX_EXT_B_BGA1-IC,TBD!!!F72!VSS(59)!!!!
S!GND!U5D1!EE70!@baseboard_fab2_lib.baseboard_fab2(sch_1):page41_i286@chpset_lib.skx_ext_b(chips)!SKX_EXT_B_BGA1-IC,TBD!!!F72!VSS(5)!!!!
S!GND!U5D1!DW74!@baseboard_fab2_lib.baseboard_fab2(sch_1):page41_i286@chpset_lib.skx_ext_b(chips)!SKX_EXT_B_BGA1-IC,TBD!!!F72!VSS(60)!!!!
S!GND!U5D1!DW72!@baseboard_fab2_lib.baseboard_fab2(sch_1):page41_i286@chpset_lib.skx_ext_b(chips)!SKX_EXT_B_BGA1-IC,TBD!!!F72!VSS(61)!!!!
S!GND!U5D1!DW70!@baseboard_fab2_lib.baseboard_fab2(sch_1):page41_i286@chpset_lib.skx_ext_b(chips)!SKX_EXT_B_BGA1-IC,TBD!!!F72!VSS(62)!!!!
S!GND!U5D1!DW68!@baseboard_fab2_lib.baseboard_fab2(sch_1):page41_i286@chpset_lib.skx_ext_b(chips)!SKX_EXT_B_BGA1-IC,TBD!!!F72!VSS(63)!!!!
S!GND!U5D1!DW66!@baseboard_fab2_lib.baseboard_fab2(sch_1):page41_i286@chpset_lib.skx_ext_b(chips)!SKX_EXT_B_BGA1-IC,TBD!!!F72!VSS(64)!!!!
S!GND!U5D1!DW64!@baseboard_fab2_lib.baseboard_fab2(sch_1):page41_i286@chpset_lib.skx_ext_b(chips)!SKX_EXT_B_BGA1-IC,TBD!!!F72!VSS(65)!!!!
S!GND!U5D1!DW40!@baseboard_fab2_lib.baseboard_fab2(sch_1):page41_i286@chpset_lib.skx_ext_b(chips)!SKX_EXT_B_BGA1-IC,TBD!!!F72!VSS(66)!!!!
S!GND!U5D1!DW36!@baseboard_fab2_lib.baseboard_fab2(sch_1):page41_i286@chpset_lib.skx_ext_b(chips)!SKX_EXT_B_BGA1-IC,TBD!!!F72!VSS(67)!!!!
S!GND!U5D1!DW34!@baseboard_fab2_lib.baseboard_fab2(sch_1):page41_i286@chpset_lib.skx_ext_b(chips)!SKX_EXT_B_BGA1-IC,TBD!!!F72!VSS(68)!!!!
S!GND!U5D1!DW30!@baseboard_fab2_lib.baseboard_fab2(sch_1):page41_i286@chpset_lib.skx_ext_b(chips)!SKX_EXT_B_BGA1-IC,TBD!!!F72!VSS(69)!!!!
S!GND!U5D1!EE36!@baseboard_fab2_lib.baseboard_fab2(sch_1):page41_i286@chpset_lib.skx_ext_b(chips)!SKX_EXT_B_BGA1-IC,TBD!!!F72!VSS(6)!!!!
S!GND!U5D1!DW28!@baseboard_fab2_lib.baseboard_fab2(sch_1):page41_i286@chpset_lib.skx_ext_b(chips)!SKX_EXT_B_BGA1-IC,TBD!!!F72!VSS(70)!!!!
S!GND!U5D1!DW24!@baseboard_fab2_lib.baseboard_fab2(sch_1):page41_i286@chpset_lib.skx_ext_b(chips)!SKX_EXT_B_BGA1-IC,TBD!!!F72!VSS(71)!!!!
S!GND!U5D1!DW20!@baseboard_fab2_lib.baseboard_fab2(sch_1):page41_i286@chpset_lib.skx_ext_b(chips)!SKX_EXT_B_BGA1-IC,TBD!!!F72!VSS(72)!!!!
S!GND!U5D1!DW12!@baseboard_fab2_lib.baseboard_fab2(sch_1):page41_i286@chpset_lib.skx_ext_b(chips)!SKX_EXT_B_BGA1-IC,TBD!!!F72!VSS(73)!!!!
S!GND!U5D1!DV81!@baseboard_fab2_lib.baseboard_fab2(sch_1):page41_i286@chpset_lib.skx_ext_b(chips)!SKX_EXT_B_BGA1-IC,TBD!!!F72!VSS(74)!!!!
S!GND!U5D1!DV77!@baseboard_fab2_lib.baseboard_fab2(sch_1):page41_i286@chpset_lib.skx_ext_b(chips)!SKX_EXT_B_BGA1-IC,TBD!!!F72!VSS(75)!!!!
S!GND!U5D1!DV73!@baseboard_fab2_lib.baseboard_fab2(sch_1):page41_i286@chpset_lib.skx_ext_b(chips)!SKX_EXT_B_BGA1-IC,TBD!!!F72!VSS(76)!!!!
S!GND!U5D1!DV39!@baseboard_fab2_lib.baseboard_fab2(sch_1):page41_i286@chpset_lib.skx_ext_b(chips)!SKX_EXT_B_BGA1-IC,TBD!!!F72!VSS(77)!!!!
S!GND!U5D1!DV37!@baseboard_fab2_lib.baseboard_fab2(sch_1):page41_i286@chpset_lib.skx_ext_b(chips)!SKX_EXT_B_BGA1-IC,TBD!!!F72!VSS(78)!!!!
S!GND!U5D1!DV33!@baseboard_fab2_lib.baseboard_fab2(sch_1):page41_i286@chpset_lib.skx_ext_b(chips)!SKX_EXT_B_BGA1-IC,TBD!!!F72!VSS(79)!!!!
S!GND!U5D1!EE34!@baseboard_fab2_lib.baseboard_fab2(sch_1):page41_i286@chpset_lib.skx_ext_b(chips)!SKX_EXT_B_BGA1-IC,TBD!!!F72!VSS(7)!!!!
S!GND!U5D1!DV31!@baseboard_fab2_lib.baseboard_fab2(sch_1):page41_i286@chpset_lib.skx_ext_b(chips)!SKX_EXT_B_BGA1-IC,TBD!!!F72!VSS(80)!!!!
S!GND!U5D1!DV27!@baseboard_fab2_lib.baseboard_fab2(sch_1):page41_i286@chpset_lib.skx_ext_b(chips)!SKX_EXT_B_BGA1-IC,TBD!!!F72!VSS(81)!!!!
S!GND!U5D1!DV25!@baseboard_fab2_lib.baseboard_fab2(sch_1):page41_i286@chpset_lib.skx_ext_b(chips)!SKX_EXT_B_BGA1-IC,TBD!!!F72!VSS(82)!!!!
S!GND!U5D1!DV21!@baseboard_fab2_lib.baseboard_fab2(sch_1):page41_i286@chpset_lib.skx_ext_b(chips)!SKX_EXT_B_BGA1-IC,TBD!!!F72!VSS(83)!!!!
S!GND!U5D1!DU84!@baseboard_fab2_lib.baseboard_fab2(sch_1):page41_i286@chpset_lib.skx_ext_b(chips)!SKX_EXT_B_BGA1-IC,TBD!!!F72!VSS(84)!!!!
S!GND!U5D1!DU82!@baseboard_fab2_lib.baseboard_fab2(sch_1):page41_i286@chpset_lib.skx_ext_b(chips)!SKX_EXT_B_BGA1-IC,TBD!!!F72!VSS(85)!!!!
S!GND!U5D1!DU80!@baseboard_fab2_lib.baseboard_fab2(sch_1):page41_i286@chpset_lib.skx_ext_b(chips)!SKX_EXT_B_BGA1-IC,TBD!!!F72!VSS(86)!!!!
S!GND!U5D1!DU78!@baseboard_fab2_lib.baseboard_fab2(sch_1):page41_i286@chpset_lib.skx_ext_b(chips)!SKX_EXT_B_BGA1-IC,TBD!!!F72!VSS(87)!!!!
S!GND!U5D1!DU72!@baseboard_fab2_lib.baseboard_fab2(sch_1):page41_i286@chpset_lib.skx_ext_b(chips)!SKX_EXT_B_BGA1-IC,TBD!!!F72!VSS(88)!!!!
S!GND!U5D1!DU70!@baseboard_fab2_lib.baseboard_fab2(sch_1):page41_i286@chpset_lib.skx_ext_b(chips)!SKX_EXT_B_BGA1-IC,TBD!!!F72!VSS(89)!!!!
S!GND!U5D1!EE30!@baseboard_fab2_lib.baseboard_fab2(sch_1):page41_i286@chpset_lib.skx_ext_b(chips)!SKX_EXT_B_BGA1-IC,TBD!!!F72!VSS(8)!!!!
S!GND!U5D1!DU38!@baseboard_fab2_lib.baseboard_fab2(sch_1):page41_i286@chpset_lib.skx_ext_b(chips)!SKX_EXT_B_BGA1-IC,TBD!!!F72!VSS(90)!!!!
S!GND!U5D1!DU32!@baseboard_fab2_lib.baseboard_fab2(sch_1):page41_i286@chpset_lib.skx_ext_b(chips)!SKX_EXT_B_BGA1-IC,TBD!!!F72!VSS(91)!!!!
S!GND!U5D1!DU26!@baseboard_fab2_lib.baseboard_fab2(sch_1):page41_i286@chpset_lib.skx_ext_b(chips)!SKX_EXT_B_BGA1-IC,TBD!!!F72!VSS(92)!!!!
S!GND!U5D1!DU22!@baseboard_fab2_lib.baseboard_fab2(sch_1):page41_i286@chpset_lib.skx_ext_b(chips)!SKX_EXT_B_BGA1-IC,TBD!!!F72!VSS(93)!!!!
S!GND!U5D1!CN14!@baseboard_fab2_lib.baseboard_fab2(sch_1):page41_i286@chpset_lib.skx_ext_b(chips)!SKX_EXT_B_BGA1-IC,TBD!!!F72!VSS(94)!!!!
S!GND!U5D1!DU14!@baseboard_fab2_lib.baseboard_fab2(sch_1):page41_i286@chpset_lib.skx_ext_b(chips)!SKX_EXT_B_BGA1-IC,TBD!!!F72!VSS(95)!!!!
S!GND!U5D1!DU10!@baseboard_fab2_lib.baseboard_fab2(sch_1):page41_i286@chpset_lib.skx_ext_b(chips)!SKX_EXT_B_BGA1-IC,TBD!!!F72!VSS(96)!!!!
S!GND!U5D1!DT85!@baseboard_fab2_lib.baseboard_fab2(sch_1):page41_i286@chpset_lib.skx_ext_b(chips)!SKX_EXT_B_BGA1-IC,TBD!!!F72!VSS(97)!!!!
S!GND!U5D1!DT83!@baseboard_fab2_lib.baseboard_fab2(sch_1):page41_i286@chpset_lib.skx_ext_b(chips)!SKX_EXT_B_BGA1-IC,TBD!!!F72!VSS(98)!!!!
S!GND!U5D1!DT79!@baseboard_fab2_lib.baseboard_fab2(sch_1):page41_i286@chpset_lib.skx_ext_b(chips)!SKX_EXT_B_BGA1-IC,TBD!!!F72!VSS(99)!!!!
S!GND!U5D1!EE28!@baseboard_fab2_lib.baseboard_fab2(sch_1):page41_i286@chpset_lib.skx_ext_b(chips)!SKX_EXT_B_BGA1-IC,TBD!!!F72!VSS(9)!!!!
S!GND!U5D1!EE80!@baseboard_fab2_lib.baseboard_fab2(sch_1):page40_i20@chpset_lib.skx_ext_b(chips)!SKX_EXT_B_BGA1-IC,TBD!!!F79!VSS(1230)!!!!
S!GND!U5D1!EB83!@baseboard_fab2_lib.baseboard_fab2(sch_1):page40_i20@chpset_lib.skx_ext_b(chips)!SKX_EXT_B_BGA1-IC,TBD!!!F79!VSS(1240)!!!!
S!GND!U5D1!EA84!@baseboard_fab2_lib.baseboard_fab2(sch_1):page40_i20@chpset_lib.skx_ext_b(chips)!SKX_EXT_B_BGA1-IC,TBD!!!F79!VSS(1241)!!!!
S!GND!U5D1!DY85!@baseboard_fab2_lib.baseboard_fab2(sch_1):page40_i20@chpset_lib.skx_ext_b(chips)!SKX_EXT_B_BGA1-IC,TBD!!!F79!VSS(1242)!!!!
S!GND!U5D1!J86!@baseboard_fab2_lib.baseboard_fab2(sch_1):page40_i20@chpset_lib.skx_ext_b(chips)!SKX_EXT_B_BGA1-IC,TBD!!!F79!VSS(1243)!!!!
S!GND!U5D1!E82!@baseboard_fab2_lib.baseboard_fab2(sch_1):page40_i20@chpset_lib.skx_ext_b(chips)!SKX_EXT_B_BGA1-IC,TBD!!!F79!VSS(1244)!!!!
S!GND!U5D1!D81!@baseboard_fab2_lib.baseboard_fab2(sch_1):page40_i20@chpset_lib.skx_ext_b(chips)!SKX_EXT_B_BGA1-IC,TBD!!!F79!VSS(1245)!!!!
S!GND!U5D1!D3!@baseboard_fab2_lib.baseboard_fab2(sch_1):page40_i20@chpset_lib.skx_ext_b(chips)!SKX_EXT_B_BGA1-IC,TBD!!!F79!VSS(1246)!!!!
S!GND!U5D1!C80!@baseboard_fab2_lib.baseboard_fab2(sch_1):page40_i20@chpset_lib.skx_ext_b(chips)!SKX_EXT_B_BGA1-IC,TBD!!!F79!VSS(1247)!!!!
S!GND!U5D1!C4!@baseboard_fab2_lib.baseboard_fab2(sch_1):page40_i20@chpset_lib.skx_ext_b(chips)!SKX_EXT_B_BGA1-IC,TBD!!!F79!VSS(1248)!!!!
S!GND!U5D1!B79!@baseboard_fab2_lib.baseboard_fab2(sch_1):page40_i20@chpset_lib.skx_ext_b(chips)!SKX_EXT_B_BGA1-IC,TBD!!!F79!VSS(1249)!!!!
S!GND!U5D1!EE8!@baseboard_fab2_lib.baseboard_fab2(sch_1):page40_i20@chpset_lib.skx_ext_b(chips)!SKX_EXT_B_BGA1-IC,TBD!!!F79!VSS(1231)!!!!
S!GND!U5D1!B5!@baseboard_fab2_lib.baseboard_fab2(sch_1):page40_i20@chpset_lib.skx_ext_b(chips)!SKX_EXT_B_BGA1-IC,TBD!!!F79!VSS(1250)!!!!
S!GND!U5D1!B43!@baseboard_fab2_lib.baseboard_fab2(sch_1):page40_i20@chpset_lib.skx_ext_b(chips)!SKX_EXT_B_BGA1-IC,TBD!!!F79!VSS(1251)!!!!
S!GND!U5D1!A42!@baseboard_fab2_lib.baseboard_fab2(sch_1):page40_i20@chpset_lib.skx_ext_b(chips)!SKX_EXT_B_BGA1-IC,TBD!!!F79!VSS(1252)!!!!
S!GND!U5D1!EE40!@baseboard_fab2_lib.baseboard_fab2(sch_1):page40_i20@chpset_lib.skx_ext_b(chips)!SKX_EXT_B_BGA1-IC,TBD!!!F79!VSS(1232)!!!!
S!GND!U5D1!ED81!@baseboard_fab2_lib.baseboard_fab2(sch_1):page40_i20@chpset_lib.skx_ext_b(chips)!SKX_EXT_B_BGA1-IC,TBD!!!F79!VSS(1233)!!!!
S!GND!U5D1!ED7!@baseboard_fab2_lib.baseboard_fab2(sch_1):page40_i20@chpset_lib.skx_ext_b(chips)!SKX_EXT_B_BGA1-IC,TBD!!!F79!VSS(1234)!!!!
S!GND!U5D1!ED41!@baseboard_fab2_lib.baseboard_fab2(sch_1):page40_i20@chpset_lib.skx_ext_b(chips)!SKX_EXT_B_BGA1-IC,TBD!!!F79!VSS(1235)!!!!
S!GND!U5D1!EC82!@baseboard_fab2_lib.baseboard_fab2(sch_1):page40_i20@chpset_lib.skx_ext_b(chips)!SKX_EXT_B_BGA1-IC,TBD!!!F79!VSS(1236)!!!!
S!GND!U5D1!EC6!@baseboard_fab2_lib.baseboard_fab2(sch_1):page40_i20@chpset_lib.skx_ext_b(chips)!SKX_EXT_B_BGA1-IC,TBD!!!F79!VSS(1237)!!!!
S!GND!U5D1!EC42!@baseboard_fab2_lib.baseboard_fab2(sch_1):page40_i20@chpset_lib.skx_ext_b(chips)!SKX_EXT_B_BGA1-IC,TBD!!!F79!VSS(1238)!!!!
S!GND!U5D1!DW2!@baseboard_fab2_lib.baseboard_fab2(sch_1):page40_i20@chpset_lib.skx_ext_b(chips)!SKX_EXT_B_BGA1-IC,TBD!!!F79!VSS(1239)!!!!
S!CLK_100M_CPU1_BCLK0_DN!U2D1!AU24!@baseboard_fab2_lib.baseboard_fab2(sch_1):page55_i172@chpset_lib.skx_ext_b(chips)!SKX_EXT_B_BGA1-IC,TBD!!!F131!BCLK0_DN!!!!
S!CLK_100M_CPU1_BCLK0_DP!U2D1!AW24!@baseboard_fab2_lib.baseboard_fab2(sch_1):page55_i172@chpset_lib.skx_ext_b(chips)!SKX_EXT_B_BGA1-IC,TBD!!!F131!BCLK0_DP!!!!
S!CLK_100M_CPU1_BCLK1_DN!U2D1!CR26!@baseboard_fab2_lib.baseboard_fab2(sch_1):page55_i172@chpset_lib.skx_ext_b(chips)!SKX_EXT_B_BGA1-IC,TBD!!!F131!BCLK1_DN!!!!
S!CLK_100M_CPU1_BCLK1_DP!U2D1!CP27!@baseboard_fab2_lib.baseboard_fab2(sch_1):page55_i172@chpset_lib.skx_ext_b(chips)!SKX_EXT_B_BGA1-IC,TBD!!!F131!BCLK1_DP!!!!
S!CLK_100M_CPU1_BCLK2_DN!U2D1!CT25!@baseboard_fab2_lib.baseboard_fab2(sch_1):page55_i172@chpset_lib.skx_ext_b(chips)!SKX_EXT_B_BGA1-IC,TBD!!!F131!BCLK2_DN!!!!
S!CLK_100M_CPU1_BCLK2_DP!U2D1!CU26!@baseboard_fab2_lib.baseboard_fab2(sch_1):page55_i172@chpset_lib.skx_ext_b(chips)!SKX_EXT_B_BGA1-IC,TBD!!!F131!BCLK2_DP!!!!
S!H_CPU1_BMCINIT!U2D1!BD23!@baseboard_fab2_lib.baseboard_fab2(sch_1):page55_i172@chpset_lib.skx_ext_b(chips)!SKX_EXT_B_BGA1-IC,TBD!!!F131!BMCINIT!!!!
S!H_CPU1_CATERR_G_N!U2D1!AL14!@baseboard_fab2_lib.baseboard_fab2(sch_1):page55_i172@chpset_lib.skx_ext_b(chips)!SKX_EXT_B_BGA1-IC,TBD!!!F131!CATERR_N!!!!
S!PWRGD_CPU1_DRAMPWROK_GHJ_G!U2D1!AN30!@baseboard_fab2_lib.baseboard_fab2(sch_1):page55_i172@chpset_lib.skx_ext_b(chips)!SKX_EXT_B_BGA1-IC,TBD!!!F131!DDR012_DRAM_PWR_OK!!!!
S!H_CPU1_MEMGHJ_MEMHOT_G_N!U2D1!AH13!@baseboard_fab2_lib.baseboard_fab2(sch_1):page55_i172@chpset_lib.skx_ext_b(chips)!SKX_EXT_B_BGA1-IC,TBD!!!F131!MEM_HOT_C012_N!!!!
S!A_CPU1_GHJ_RCOMP0!U2D1!Y43!@baseboard_fab2_lib.baseboard_fab2(sch_1):page55_i172@chpset_lib.skx_ext_b(chips)!SKX_EXT_B_BGA1-IC,TBD!!!F131!DDR012_RCOMP(0)!!!!
S!A_CPU1_GHJ_RCOMP1!U2D1!AB43!@baseboard_fab2_lib.baseboard_fab2(sch_1):page55_i172@chpset_lib.skx_ext_b(chips)!SKX_EXT_B_BGA1-IC,TBD!!!F131!DDR012_RCOMP(1)!!!!
S!A_CPU1_GHJ_RCOMP2!U2D1!AC42!@baseboard_fab2_lib.baseboard_fab2(sch_1):page55_i172@chpset_lib.skx_ext_b(chips)!SKX_EXT_B_BGA1-IC,TBD!!!F131!DDR012_RCOMP(2)!!!!
S!M_GHJ_RST_N!U2D1!U64!@baseboard_fab2_lib.baseboard_fab2(sch_1):page55_i172@chpset_lib.skx_ext_b(chips)!SKX_EXT_B_BGA1-IC,TBD!!!F131!DDR012_RESET_N!!!!
S!M_G_CPU_VREF!U2D1!AJ64!@baseboard_fab2_lib.baseboard_fab2(sch_1):page55_i172@chpset_lib.skx_ext_b(chips)!SKX_EXT_B_BGA1-IC,TBD!!!F131!DDR0_CAVREF!!!!
S!M_H_CPU_VREF!U2D1!AK63!@baseboard_fab2_lib.baseboard_fab2(sch_1):page55_i172@chpset_lib.skx_ext_b(chips)!SKX_EXT_B_BGA1-IC,TBD!!!F131!DDR1_CAVREF!!!!
S!M_J_CPU_VREF!U2D1!AH63!@baseboard_fab2_lib.baseboard_fab2(sch_1):page55_i172@chpset_lib.skx_ext_b(chips)!SKX_EXT_B_BGA1-IC,TBD!!!F131!DDR2_CAVREF!!!!
S!PWRGD_CPU1_DRAMPWROK_KLM_G!U2D1!CR28!@baseboard_fab2_lib.baseboard_fab2(sch_1):page55_i172@chpset_lib.skx_ext_b(chips)!SKX_EXT_B_BGA1-IC,TBD!!!F131!DDR345_DRAM_PWR_OK!!!!
S!H_CPU1_MEMKLM_MEMHOT_G_N!U2D1!AF13!@baseboard_fab2_lib.baseboard_fab2(sch_1):page55_i172@chpset_lib.skx_ext_b(chips)!SKX_EXT_B_BGA1-IC,TBD!!!F131!MEM_HOT_C345_N!!!!
S!A_CPU1_KLM_RCOMP0!U2D1!DC48!@baseboard_fab2_lib.baseboard_fab2(sch_1):page55_i172@chpset_lib.skx_ext_b(chips)!SKX_EXT_B_BGA1-IC,TBD!!!F131!DDR345_RCOMP(0)!!!!
S!A_CPU1_KLM_RCOMP1!U2D1!DD47!@baseboard_fab2_lib.baseboard_fab2(sch_1):page55_i172@chpset_lib.skx_ext_b(chips)!SKX_EXT_B_BGA1-IC,TBD!!!F131!DDR345_RCOMP(1)!!!!
S!A_CPU1_KLM_RCOMP2!U2D1!DD49!@baseboard_fab2_lib.baseboard_fab2(sch_1):page55_i172@chpset_lib.skx_ext_b(chips)!SKX_EXT_B_BGA1-IC,TBD!!!F131!DDR345_RCOMP(2)!!!!
S!M_KLM_RST_N!U2D1!DV63!@baseboard_fab2_lib.baseboard_fab2(sch_1):page55_i172@chpset_lib.skx_ext_b(chips)!SKX_EXT_B_BGA1-IC,TBD!!!F131!DDR345_RESET_N!!!!
S!M_K_CPU_VREF!U2D1!CP61!@baseboard_fab2_lib.baseboard_fab2(sch_1):page55_i172@chpset_lib.skx_ext_b(chips)!SKX_EXT_B_BGA1-IC,TBD!!!F131!DDR3_CAVREF!!!!
S!M_L_CPU_VREF!U2D1!CT61!@baseboard_fab2_lib.baseboard_fab2(sch_1):page55_i172@chpset_lib.skx_ext_b(chips)!SKX_EXT_B_BGA1-IC,TBD!!!F131!DDR4_CAVREF!!!!
S!M_M_CPU_VREF!U2D1!CV61!@baseboard_fab2_lib.baseboard_fab2(sch_1):page55_i172@chpset_lib.skx_ext_b(chips)!SKX_EXT_B_BGA1-IC,TBD!!!F131!DDR5_CAVREF!!!!
S!SMB_DDR_GHJ_SCL_G_R!U2D1!AJ18!@baseboard_fab2_lib.baseboard_fab2(sch_1):page55_i172@chpset_lib.skx_ext_b(chips)!SKX_EXT_B_BGA1-IC,TBD!!!F131!DDR012_SPDSCL!!!!
S!SMB_DDR_KLM_SCL_G_R!U2D1!AE18!@baseboard_fab2_lib.baseboard_fab2(sch_1):page55_i172@chpset_lib.skx_ext_b(chips)!SKX_EXT_B_BGA1-IC,TBD!!!F131!DDR345_SPDSCL!!!!
S!SMB_DDR_GHJ_SDA_G_R!U2D1!AF17!@baseboard_fab2_lib.baseboard_fab2(sch_1):page55_i172@chpset_lib.skx_ext_b(chips)!SKX_EXT_B_BGA1-IC,TBD!!!F131!DDR012_SPDSDA!!!!
S!SMB_DDR_KLM_SDA_G_R!U2D1!AD17!@baseboard_fab2_lib.baseboard_fab2(sch_1):page55_i172@chpset_lib.skx_ext_b(chips)!SKX_EXT_B_BGA1-IC,TBD!!!F131!DDR345_SPDSDA!!!!
S!PU_CPU1_EAR_N!U2D1!AJ14!@baseboard_fab2_lib.baseboard_fab2(sch_1):page55_i172@chpset_lib.skx_ext_b(chips)!SKX_EXT_B_BGA1-IC,TBD!!!F131!EAR_N!!!!
S!H_CPU1_ERR0_G_N!U2D1!AJ12!@baseboard_fab2_lib.baseboard_fab2(sch_1):page55_i172@chpset_lib.skx_ext_b(chips)!SKX_EXT_B_BGA1-IC,TBD!!!F131!ERROR_N(0)!!!!
S!H_CPU1_ERR1_G_N!U2D1!AK11!@baseboard_fab2_lib.baseboard_fab2(sch_1):page55_i172@chpset_lib.skx_ext_b(chips)!SKX_EXT_B_BGA1-IC,TBD!!!F131!ERROR_N(1)!!!!
S!H_CPU1_ERR2_G_N!U2D1!AL12!@baseboard_fab2_lib.baseboard_fab2(sch_1):page55_i172@chpset_lib.skx_ext_b(chips)!SKX_EXT_B_BGA1-IC,TBD!!!F131!ERROR_N(2)!!!!
S!A_CPU1_UPI01_RBIAS!U2D1!AT29!@baseboard_fab2_lib.baseboard_fab2(sch_1):page55_i172@chpset_lib.skx_ext_b(chips)!SKX_EXT_B_BGA1-IC,TBD!!!F131!UPI01_RBIAS(0)!!!!
S!A_CPU1_UPI01_RBIAS!U2D1!AP29!@baseboard_fab2_lib.baseboard_fab2(sch_1):page55_i172@chpset_lib.skx_ext_b(chips)!SKX_EXT_B_BGA1-IC,TBD!!!F131!UPI01_RBIAS(1)!!!!
S!A_CPU1_UPI2_RBIAS!U2D1!CL28!@baseboard_fab2_lib.baseboard_fab2(sch_1):page55_i172@chpset_lib.skx_ext_b(chips)!SKX_EXT_B_BGA1-IC,TBD!!!F131!UPI2_RBIAS(0)!!!!
S!A_CPU1_UPI2_RBIAS!U2D1!CK29!@baseboard_fab2_lib.baseboard_fab2(sch_1):page55_i172@chpset_lib.skx_ext_b(chips)!SKX_EXT_B_BGA1-IC,TBD!!!F131!UPI2_RBIAS(1)!!!!
S!PU_CPU1_LEGACY_SKT!U2D1!AE20!@baseboard_fab2_lib.baseboard_fab2(sch_1):page55_i172@chpset_lib.skx_ext_b(chips)!SKX_EXT_B_BGA1-IC,TBD!!!F131!LEGACY_SKT!!!!
S!XDP_CPU_MBP0_N!U2D1!AJ10!@baseboard_fab2_lib.baseboard_fab2(sch_1):page55_i172@chpset_lib.skx_ext_b(chips)!SKX_EXT_B_BGA1-IC,TBD!!!F131!BPM_N(0)!!!!
S!XDP_CPU_MBP1_N!U2D1!AH11!@baseboard_fab2_lib.baseboard_fab2(sch_1):page55_i172@chpset_lib.skx_ext_b(chips)!SKX_EXT_B_BGA1-IC,TBD!!!F131!BPM_N(1)!!!!
S!TP_XDP_CPU1_OBSDATA_B0_MBP2_N!U2D1!AG10!@baseboard_fab2_lib.baseboard_fab2(sch_1):page55_i172@chpset_lib.skx_ext_b(chips)!SKX_EXT_B_BGA1-IC,TBD!!!F131!BPM_N(2)!!!!
S!TP_XDP_CPU1_OBSDATA_B1_MBP3_N!U2D1!AF11!@baseboard_fab2_lib.baseboard_fab2(sch_1):page55_i172@chpset_lib.skx_ext_b(chips)!SKX_EXT_B_BGA1-IC,TBD!!!F131!BPM_N(3)!!!!
S!TP_XDP_CPU1_OBSDATA_B2_MBP4_N!U2D1!AA12!@baseboard_fab2_lib.baseboard_fab2(sch_1):page55_i172@chpset_lib.skx_ext_b(chips)!SKX_EXT_B_BGA1-IC,TBD!!!F131!BPM_N(4)!!!!
S!TP_XDP_CPU1_OBSDATA_B3_MBP5_N!U2D1!Y11!@baseboard_fab2_lib.baseboard_fab2(sch_1):page55_i172@chpset_lib.skx_ext_b(chips)!SKX_EXT_B_BGA1-IC,TBD!!!F131!BPM_N(5)!!!!
S!XDP_CPU_OBSFN_B0_MBP6_N!U2D1!AE12!@baseboard_fab2_lib.baseboard_fab2(sch_1):page55_i172@chpset_lib.skx_ext_b(chips)!SKX_EXT_B_BGA1-IC,TBD!!!F131!BPM_N(6)!!!!
S!XDP_CPU_OBSFN_B1_MBP7_N!U2D1!AC12!@baseboard_fab2_lib.baseboard_fab2(sch_1):page55_i172@chpset_lib.skx_ext_b(chips)!SKX_EXT_B_BGA1-IC,TBD!!!F131!BPM_N(7)!!!!
S!PD_CPU1_BIST_ENABLE!U2D1!BA20!@baseboard_fab2_lib.baseboard_fab2(sch_1):page55_i172@chpset_lib.skx_ext_b(chips)!SKX_EXT_B_BGA1-IC,TBD!!!F131!BIST_ENABLE!!!!
S!PU_CPU1_FRMAGENT!U2D1!AV17!@baseboard_fab2_lib.baseboard_fab2(sch_1):page55_i172@chpset_lib.skx_ext_b(chips)!SKX_EXT_B_BGA1-IC,TBD!!!F131!FRMAGENT!!!!
S!PU_CPU1_SAFE_MODE_BOOT!U2D1!AR18!@baseboard_fab2_lib.baseboard_fab2(sch_1):page55_i172@chpset_lib.skx_ext_b(chips)!SKX_EXT_B_BGA1-IC,TBD!!!F131!SAFE_MODE_BOOT!!!!
S!PU_CPU1_SOCKET_ID_0!U2D1!AU22!@baseboard_fab2_lib.baseboard_fab2(sch_1):page55_i172@chpset_lib.skx_ext_b(chips)!SKX_EXT_B_BGA1-IC,TBD!!!F131!SOCKET_ID(0)!!!!
S!PU_CPU1_SOCKET_ID_1!U2D1!AU16!@baseboard_fab2_lib.baseboard_fab2(sch_1):page55_i172@chpset_lib.skx_ext_b(chips)!SKX_EXT_B_BGA1-IC,TBD!!!F131!SOCKET_ID(1)!!!!
S!PU_CPU1_TXT_AGENT!U2D1!AW18!@baseboard_fab2_lib.baseboard_fab2(sch_1):page55_i172@chpset_lib.skx_ext_b(chips)!SKX_EXT_B_BGA1-IC,TBD!!!F131!TXT_AGENT!!!!
S!PD_CPU1_TXT_PLTEN!U2D1!AV15!@baseboard_fab2_lib.baseboard_fab2(sch_1):page55_i172@chpset_lib.skx_ext_b(chips)!SKX_EXT_B_BGA1-IC,TBD!!!F131!TXT_PLTEN!!!!
S!A_CPU1_MCP01_RBIAS!U2D1!CT31!@baseboard_fab2_lib.baseboard_fab2(sch_1):page55_i172@chpset_lib.skx_ext_b(chips)!SKX_EXT_B_BGA1-IC,TBD!!!F131!MCP01_RBIAS(1)!!!!
S!A_CPU1_PE3_RBIAS!U2D1!CR30!@baseboard_fab2_lib.baseboard_fab2(sch_1):page55_i172@chpset_lib.skx_ext_b(chips)!SKX_EXT_B_BGA1-IC,TBD!!!F131!PE3_RBIAS(1)!!!!
S!H_CPU1_MSMI_G_N!U2D1!AN20!@baseboard_fab2_lib.baseboard_fab2(sch_1):page55_i172@chpset_lib.skx_ext_b(chips)!SKX_EXT_B_BGA1-IC,TBD!!!F131!MSMI_N!!!!
S!TP_CPU1_NMI!U2D1!AP11!@baseboard_fab2_lib.baseboard_fab2(sch_1):page55_i172@chpset_lib.skx_ext_b(chips)!SKX_EXT_B_BGA1-IC,TBD!!!F131!NMI!!!!
S!TP_CPU1_RSVD_TEST_4!U2D1!AN12!@baseboard_fab2_lib.baseboard_fab2(sch_1):page56_i169@chpset_lib.skx_ext_b(chips)!SKX_EXT_B_BGA1-IC,TBD!!!F130!TEST_4!!!!
S!TP_CPU1_RSVD_TEST_3!U2D1!AM13!@baseboard_fab2_lib.baseboard_fab2(sch_1):page56_i169@chpset_lib.skx_ext_b(chips)!SKX_EXT_B_BGA1-IC,TBD!!!F130!TEST_3!!!!
S!TP_CPU1_RSVD_TEST_5!U2D1!AN14!@baseboard_fab2_lib.baseboard_fab2(sch_1):page56_i169@chpset_lib.skx_ext_b(chips)!SKX_EXT_B_BGA1-IC,TBD!!!F130!TEST_5!!!!
S!A_CPU1_PE012_RBIAS!U2D1!CN30!@baseboard_fab2_lib.baseboard_fab2(sch_1):page55_i172@chpset_lib.skx_ext_b(chips)!SKX_EXT_B_BGA1-IC,TBD!!!F131!PE012_RBIAS(0)!!!!
S!A_CPU1_PE012_RBIAS!U2D1!CL30!@baseboard_fab2_lib.baseboard_fab2(sch_1):page55_i172@chpset_lib.skx_ext_b(chips)!SKX_EXT_B_BGA1-IC,TBD!!!F131!PE012_RBIAS(1)!!!!
S!A_CPU1_PE3_RBIAS!U2D1!CP29!@baseboard_fab2_lib.baseboard_fab2(sch_1):page55_i172@chpset_lib.skx_ext_b(chips)!SKX_EXT_B_BGA1-IC,TBD!!!F131!PE3_RBIAS(0)!!!!
S!PD_CPU1_MCP01_DMON!U2D1!CN28!@baseboard_fab2_lib.baseboard_fab2(sch_1):page73_i107@chpset_lib.skx_ext_b(chips)!SKX_EXT_B_BGA1-IC,TBD!!!F110!RSVD(75)!!!!
S!PECI_CPU_G!U2D1!AU12!@baseboard_fab2_lib.baseboard_fab2(sch_1):page55_i172@chpset_lib.skx_ext_b(chips)!SKX_EXT_B_BGA1-IC,TBD!!!F131!PECI!!!!
S!SMB_CPU1_PE_HP_GTL_SCL!U2D1!AM19!@baseboard_fab2_lib.baseboard_fab2(sch_1):page55_i172@chpset_lib.skx_ext_b(chips)!SKX_EXT_B_BGA1-IC,TBD!!!F131!PE_HP_SCL!!!!
S!SMB_CPU1_PE_HP_GTL_SDA!U2D1!AL18!@baseboard_fab2_lib.baseboard_fab2(sch_1):page55_i172@chpset_lib.skx_ext_b(chips)!SKX_EXT_B_BGA1-IC,TBD!!!F131!PE_HP_SDA!!!!
S!PU_PIROM_CPU1_ADDR0!U2D1!CU58!@baseboard_fab2_lib.baseboard_fab2(sch_1):page55_i172@chpset_lib.skx_ext_b(chips)!SKX_EXT_B_BGA1-IC,TBD!!!F131!PIROM_ADDR(0)!!!!
S!PD_PIROM_CPU1_ADDR1!U2D1!CV57!@baseboard_fab2_lib.baseboard_fab2(sch_1):page55_i172@chpset_lib.skx_ext_b(chips)!SKX_EXT_B_BGA1-IC,TBD!!!F131!PIROM_ADDR(1)!!!!
S!PD_PIROM_CPU1_ADDR2!U2D1!CW56!@baseboard_fab2_lib.baseboard_fab2(sch_1):page55_i172@chpset_lib.skx_ext_b(chips)!SKX_EXT_B_BGA1-IC,TBD!!!F131!PIROM_ADDR(2)!!!!
S!FM_CPU1_PKGID0!U2D1!DC72!@baseboard_fab2_lib.baseboard_fab2(sch_1):page55_i172@chpset_lib.skx_ext_b(chips)!SKX_EXT_B_BGA1-IC,TBD!!!F131!PKGID(0)!!!!
S!FM_CPU1_PKGID1!U2D1!CW72!@baseboard_fab2_lib.baseboard_fab2(sch_1):page55_i172@chpset_lib.skx_ext_b(chips)!SKX_EXT_B_BGA1-IC,TBD!!!F131!PKGID(1)!!!!
S!FM_CPU1_PKGID2!U2D1!DA72!@baseboard_fab2_lib.baseboard_fab2(sch_1):page55_i172@chpset_lib.skx_ext_b(chips)!SKX_EXT_B_BGA1-IC,TBD!!!F131!PKGID(2)!!!!
S!H_PM_SYNC_GTL_R2!U2D1!AR14!@baseboard_fab2_lib.baseboard_fab2(sch_1):page55_i172@chpset_lib.skx_ext_b(chips)!SKX_EXT_B_BGA1-IC,TBD!!!F131!PMSYNC!!!!
S!H_PMSYNC_CLK_24M_CPU1!U2D1!AT19!@baseboard_fab2_lib.baseboard_fab2(sch_1):page55_i172@chpset_lib.skx_ext_b(chips)!SKX_EXT_B_BGA1-IC,TBD!!!F131!PMSYNC_CLK!!!!
S!H_CPU1_FAST_WAKE_N!U2D1!AF15!@baseboard_fab2_lib.baseboard_fab2(sch_1):page55_i172@chpset_lib.skx_ext_b(chips)!SKX_EXT_B_BGA1-IC,TBD!!!F131!PM_FAST_WAKE_N!!!!
S!XDP_CPU_PRDY_N!U2D1!AG16!@baseboard_fab2_lib.baseboard_fab2(sch_1):page55_i172@chpset_lib.skx_ext_b(chips)!SKX_EXT_B_BGA1-IC,TBD!!!F131!PRDY_N!!!!
S!XDP_CPU_PREQ_N!U2D1!AR12!@baseboard_fab2_lib.baseboard_fab2(sch_1):page55_i172@chpset_lib.skx_ext_b(chips)!SKX_EXT_B_BGA1-IC,TBD!!!F131!PREQ_N!!!!
S!TP_CPU1_PROC_DIS_G_N!U2D1!AB17!@baseboard_fab2_lib.baseboard_fab2(sch_1):page55_i172@chpset_lib.skx_ext_b(chips)!SKX_EXT_B_BGA1-IC,TBD!!!F131!PROCDIS_N!!!!
S!H_CPU1_PROCHOT_G_N!U2D1!AC16!@baseboard_fab2_lib.baseboard_fab2(sch_1):page55_i172@chpset_lib.skx_ext_b(chips)!SKX_EXT_B_BGA1-IC,TBD!!!F131!PROCHOT_N!!!!
S!FM_CPU1_PROC_ID0!U2D1!CY71!@baseboard_fab2_lib.baseboard_fab2(sch_1):page55_i172@chpset_lib.skx_ext_b(chips)!SKX_EXT_B_BGA1-IC,TBD!!!F131!PROC_ID(0)!!!!
S!FM_CPU1_PROC_ID1!U2D1!DB71!@baseboard_fab2_lib.baseboard_fab2(sch_1):page55_i172@chpset_lib.skx_ext_b(chips)!SKX_EXT_B_BGA1-IC,TBD!!!F131!PROC_ID(1)!!!!
S!PWRGD_CPU1_G!U2D1!BC24!@baseboard_fab2_lib.baseboard_fab2(sch_1):page55_i172@chpset_lib.skx_ext_b(chips)!SKX_EXT_B_BGA1-IC,TBD!!!F131!PWRGOOD!!!!
S!RST_CPU1_G_N!U2D1!AP21!@baseboard_fab2_lib.baseboard_fab2(sch_1):page55_i172@chpset_lib.skx_ext_b(chips)!SKX_EXT_B_BGA1-IC,TBD!!!F131!RESET_N!!!!
S!FM_CPU1_SKTOCC_LVT3_N!U2D1!AB13!@baseboard_fab2_lib.baseboard_fab2(sch_1):page55_i172@chpset_lib.skx_ext_b(chips)!SKX_EXT_B_BGA1-IC,TBD!!!F131!SKTOCC_N!!!!
S!SMB_PIROM_CPU1_SCL!U2D1!CT59!@baseboard_fab2_lib.baseboard_fab2(sch_1):page55_i172@chpset_lib.skx_ext_b(chips)!SKX_EXT_B_BGA1-IC,TBD!!!F131!SMBCLK!!!!
S!SMB_PIROM_CPU1_SDA!U2D1!CW58!@baseboard_fab2_lib.baseboard_fab2(sch_1):page55_i172@chpset_lib.skx_ext_b(chips)!SKX_EXT_B_BGA1-IC,TBD!!!F131!SMBDAT!!!!
S!FM_CPU1_SM_WP!U2D1!CV59!@baseboard_fab2_lib.baseboard_fab2(sch_1):page55_i172@chpset_lib.skx_ext_b(chips)!SKX_EXT_B_BGA1-IC,TBD!!!F131!SM_WP!!!!
S!TP_CPU1_SOCKET_ID_2!U2D1!AU20!@baseboard_fab2_lib.baseboard_fab2(sch_1):page55_i172@chpset_lib.skx_ext_b(chips)!SKX_EXT_B_BGA1-IC,TBD!!!F131!SOCKET_ID(2)!!!!
S!SVID_ALERT0_CPU1_N!U2D1!DE44!@baseboard_fab2_lib.baseboard_fab2(sch_1):page55_i172@chpset_lib.skx_ext_b(chips)!SKX_EXT_B_BGA1-IC,TBD!!!F131!SVIDALERT_N(0)!!!!
S!SVID_ALERT1_CPU1_N!U2D1!DL44!@baseboard_fab2_lib.baseboard_fab2(sch_1):page55_i172@chpset_lib.skx_ext_b(chips)!SKX_EXT_B_BGA1-IC,TBD!!!F131!SVIDALERT_N(1)!!!!
S!SVID_CLK0_CPU1!U2D1!DC44!@baseboard_fab2_lib.baseboard_fab2(sch_1):page55_i172@chpset_lib.skx_ext_b(chips)!SKX_EXT_B_BGA1-IC,TBD!!!F131!SVIDCLK(0)!!!!
S!SVID_CLK1_CPU1!U2D1!DG44!@baseboard_fab2_lib.baseboard_fab2(sch_1):page55_i172@chpset_lib.skx_ext_b(chips)!SKX_EXT_B_BGA1-IC,TBD!!!F131!SVIDCLK(1)!!!!
S!SVID_DIO0_CPU1!U2D1!DB45!@baseboard_fab2_lib.baseboard_fab2(sch_1):page55_i172@chpset_lib.skx_ext_b(chips)!SKX_EXT_B_BGA1-IC,TBD!!!F131!SVIDDATA(0)!!!!
S!SVID_DIO1_CPU1!U2D1!DJ44!@baseboard_fab2_lib.baseboard_fab2(sch_1):page55_i172@chpset_lib.skx_ext_b(chips)!SKX_EXT_B_BGA1-IC,TBD!!!F131!SVIDDATA(1)!!!!
S!XDP_CPU_TCK0!U2D1!AA14!@baseboard_fab2_lib.baseboard_fab2(sch_1):page55_i172@chpset_lib.skx_ext_b(chips)!SKX_EXT_B_BGA1-IC,TBD!!!F131!TCK!!!!
S!XDP_CPU1_TDI!U2D1!AC14!@baseboard_fab2_lib.baseboard_fab2(sch_1):page55_i172@chpset_lib.skx_ext_b(chips)!SKX_EXT_B_BGA1-IC,TBD!!!F131!TDI!!!!
S!XDP_CPU1_TDO!U2D1!AE14!@baseboard_fab2_lib.baseboard_fab2(sch_1):page55_i172@chpset_lib.skx_ext_b(chips)!SKX_EXT_B_BGA1-IC,TBD!!!F131!TDO!!!!
S!H_CPU1_THERMTRIP_G_N!U2D1!AB15!@baseboard_fab2_lib.baseboard_fab2(sch_1):page55_i172@chpset_lib.skx_ext_b(chips)!SKX_EXT_B_BGA1-IC,TBD!!!F131!THERMTRIP_N!!!!
S!XDP_CPU_TMS!U2D1!W14!@baseboard_fab2_lib.baseboard_fab2(sch_1):page55_i172@chpset_lib.skx_ext_b(chips)!SKX_EXT_B_BGA1-IC,TBD!!!F131!TMS!!!!
S!XDP_CPU_TRST_N!U2D1!Y13!@baseboard_fab2_lib.baseboard_fab2(sch_1):page55_i172@chpset_lib.skx_ext_b(chips)!SKX_EXT_B_BGA1-IC,TBD!!!F131!TRST_N!!!!
S!PU_CPU1_TSC_SYNC!U2D1!AM11!@baseboard_fab2_lib.baseboard_fab2(sch_1):page55_i172@chpset_lib.skx_ext_b(chips)!SKX_EXT_B_BGA1-IC,TBD!!!F131!TSC_SYNC!!!!
S!TP_CPU1_RSVD_114!U2D1!CB25!@baseboard_fab2_lib.baseboard_fab2(sch_1):page70_i9@chpset_lib.skx_ext_b(chips)!SKX_EXT_B_BGA1-IC,TBD!!!F116!RSVD(114)!!!!
S!TP_CPU1_RSVD_124!U2D1!BV23!@baseboard_fab2_lib.baseboard_fab2(sch_1):page70_i9@chpset_lib.skx_ext_b(chips)!SKX_EXT_B_BGA1-IC,TBD!!!F116!RSVD(124)!!!!
S!TP_CPU1_RSVD_108!U2D1!CD25!@baseboard_fab2_lib.baseboard_fab2(sch_1):page70_i9@chpset_lib.skx_ext_b(chips)!SKX_EXT_B_BGA1-IC,TBD!!!F116!RSVD(108)!!!!
S!TP_CPU1_RSVD_121!U2D1!BW22!@baseboard_fab2_lib.baseboard_fab2(sch_1):page70_i9@chpset_lib.skx_ext_b(chips)!SKX_EXT_B_BGA1-IC,TBD!!!F116!RSVD(121)!!!!
S!TP_CPU1_RSVD_117!U2D1!CA24!@baseboard_fab2_lib.baseboard_fab2(sch_1):page70_i9@chpset_lib.skx_ext_b(chips)!SKX_EXT_B_BGA1-IC,TBD!!!F116!RSVD(117)!!!!
S!TP_CPU1_RSVD_119!U2D1!BY25!@baseboard_fab2_lib.baseboard_fab2(sch_1):page70_i9@chpset_lib.skx_ext_b(chips)!SKX_EXT_B_BGA1-IC,TBD!!!F116!RSVD(119)!!!!
S!TP_CPU1_RSVD_91!U2D1!CH25!@baseboard_fab2_lib.baseboard_fab2(sch_1):page70_i10@chpset_lib.skx_ext_b(chips)!SKX_EXT_B_BGA1-IC,TBD!!!F115!RSVD(91)!!!!
S!TP_CPU1_RSVD_97!U2D1!CG24!@baseboard_fab2_lib.baseboard_fab2(sch_1):page70_i9@chpset_lib.skx_ext_b(chips)!SKX_EXT_B_BGA1-IC,TBD!!!F116!RSVD(97)!!!!
S!TP_CPU1_RSVD_281!U2D1!E24!@baseboard_fab2_lib.baseboard_fab2(sch_1):page56_i169@chpset_lib.skx_ext_b(chips)!SKX_EXT_B_BGA1-IC,TBD!!!F130!RSVD(281)!!!!
S!TP_CPU1_RSVD_278!U2D1!F23!@baseboard_fab2_lib.baseboard_fab2(sch_1):page56_i169@chpset_lib.skx_ext_b(chips)!SKX_EXT_B_BGA1-IC,TBD!!!F130!RSVD(278)!!!!
S!PD_CPU1_RSVD_TEST_2!U2D1!AG46!@baseboard_fab2_lib.baseboard_fab2(sch_1):page56_i169@chpset_lib.skx_ext_b(chips)!SKX_EXT_B_BGA1-IC,TBD!!!F130!TEST_2!!!!
S!PD_CPU1_RSVD_TEST_1!U2D1!AF45!@baseboard_fab2_lib.baseboard_fab2(sch_1):page56_i169@chpset_lib.skx_ext_b(chips)!SKX_EXT_B_BGA1-IC,TBD!!!F130!TEST_1!!!!
S!PD_CPU1_TEST13!U2D1!DB51!@baseboard_fab2_lib.baseboard_fab2(sch_1):page55_i172@chpset_lib.skx_ext_b(chips)!SKX_EXT_B_BGA1-IC,TBD!!!F131!TEST_13!!!!
S!PD_CPU1_TEST14!U2D1!DC50!@baseboard_fab2_lib.baseboard_fab2(sch_1):page55_i172@chpset_lib.skx_ext_b(chips)!SKX_EXT_B_BGA1-IC,TBD!!!F131!TEST_14!!!!
S!PD_CPU1_DMIMODE_OVERRIDE!U2D1!AW12!@baseboard_fab2_lib.baseboard_fab2(sch_1):page56_i169@chpset_lib.skx_ext_b(chips)!SKX_EXT_B_BGA1-IC,TBD!!!F130!DMIMODE_OVERRIDE!!!!
S!TP_CPU1_TEST_6!U2D1!AR16!@baseboard_fab2_lib.baseboard_fab2(sch_1):page70_i10@chpset_lib.skx_ext_b(chips)!SKX_EXT_B_BGA1-IC,TBD!!!F115!TEST_6!!!!
S!TP_CPU1_RSVD_233!U2D1!AH15!@baseboard_fab2_lib.baseboard_fab2(sch_1):page56_i169@chpset_lib.skx_ext_b(chips)!SKX_EXT_B_BGA1-IC,TBD!!!F130!RSVD(233)!!!!
S!H_CPU1_FIVR_FAULT_G!U2D1!AU14!@baseboard_fab2_lib.baseboard_fab2(sch_1):page56_i169@chpset_lib.skx_ext_b(chips)!SKX_EXT_B_BGA1-IC,TBD!!!F130!FIVR_FAULT!!!!
S!TP_CPU1_RSVD_232!U2D1!AH19!@baseboard_fab2_lib.baseboard_fab2(sch_1):page56_i169@chpset_lib.skx_ext_b(chips)!SKX_EXT_B_BGA1-IC,TBD!!!F130!RSVD(232)!!!!
S!TP_CPU1_RSVD_246!U2D1!AF19!@baseboard_fab2_lib.baseboard_fab2(sch_1):page56_i169@chpset_lib.skx_ext_b(chips)!SKX_EXT_B_BGA1-IC,TBD!!!F130!RSVD(246)!!!!
S!TP_CPU1_RSVD_189!U2D1!AT13!@baseboard_fab2_lib.baseboard_fab2(sch_1):page63_i23@chpset_lib.skx_ext_b(chips)!SKX_EXT_B_BGA1-IC,TBD!!!F123!RSVD(189)!!!!
S!TP_CPU1_RSVD_208!U2D1!AM23!@baseboard_fab2_lib.baseboard_fab2(sch_1):page56_i169@chpset_lib.skx_ext_b(chips)!SKX_EXT_B_BGA1-IC,TBD!!!F130!RSVD(208)!!!!
S!TP_CPU1_RSVD_276!U2D1!F83!@baseboard_fab2_lib.baseboard_fab2(sch_1):page56_i169@chpset_lib.skx_ext_b(chips)!SKX_EXT_B_BGA1-IC,TBD!!!F130!RSVD(276)!!!!
S!TP_CPU1_RSVD_273!U2D1!G84!@baseboard_fab2_lib.baseboard_fab2(sch_1):page56_i169@chpset_lib.skx_ext_b(chips)!SKX_EXT_B_BGA1-IC,TBD!!!F130!RSVD(273)!!!!
S!TP_CPU1_RSVD_16!U2D1!EB85!@baseboard_fab2_lib.baseboard_fab2(sch_1):page73_i107@chpset_lib.skx_ext_b(chips)!SKX_EXT_B_BGA1-IC,TBD!!!F110!RSVD(16)!!!!
S!TP_CPU1_RSVD_9!U2D1!ED83!@baseboard_fab2_lib.baseboard_fab2(sch_1):page73_i107@chpset_lib.skx_ext_b(chips)!SKX_EXT_B_BGA1-IC,TBD!!!F110!RSVD(9)!!!!
S!TP_CPU1_RSVD_12!U2D1!EC84!@baseboard_fab2_lib.baseboard_fab2(sch_1):page73_i107@chpset_lib.skx_ext_b(chips)!SKX_EXT_B_BGA1-IC,TBD!!!F110!RSVD(12)!!!!
S!TP_CPU1_RSVD_214!U2D1!AL22!@baseboard_fab2_lib.baseboard_fab2(sch_1):page56_i169@chpset_lib.skx_ext_b(chips)!SKX_EXT_B_BGA1-IC,TBD!!!F130!RSVD(214)!!!!
S!PD_CPU1_KSFC_DIS!U2D1!AW14!@baseboard_fab2_lib.baseboard_fab2(sch_1):page55_i172@chpset_lib.skx_ext_b(chips)!SKX_EXT_B_BGA1-IC,TBD!!!F131!TEST_15!!!!
S!TP_CPU1_RSVD_291!U2D1!C6!@baseboard_fab2_lib.baseboard_fab2(sch_1):page56_i169@chpset_lib.skx_ext_b(chips)!SKX_EXT_B_BGA1-IC,TBD!!!F130!RSVD(291)!!!!
S!TP_CPU1_RSVD_279!U2D1!F3!@baseboard_fab2_lib.baseboard_fab2(sch_1):page56_i169@chpset_lib.skx_ext_b(chips)!SKX_EXT_B_BGA1-IC,TBD!!!F130!RSVD(279)!!!!
S!TP_CPU1_RSVD_300!U2D1!A24!@baseboard_fab2_lib.baseboard_fab2(sch_1):page56_i169@chpset_lib.skx_ext_b(chips)!SKX_EXT_B_BGA1-IC,TBD!!!F130!RSVD(300)!!!!
S!TP_CPU1_RSVD_289!U2D1!C24!@baseboard_fab2_lib.baseboard_fab2(sch_1):page56_i169@chpset_lib.skx_ext_b(chips)!SKX_EXT_B_BGA1-IC,TBD!!!F130!RSVD(289)!!!!
S!TP_CPU1_RSVD_272!U2D1!H1!@baseboard_fab2_lib.baseboard_fab2(sch_1):page56_i169@chpset_lib.skx_ext_b(chips)!SKX_EXT_B_BGA1-IC,TBD!!!F130!RSVD(272)!!!!
S!TP_CPU1_RSVD_286!U2D1!D17!@baseboard_fab2_lib.baseboard_fab2(sch_1):page56_i169@chpset_lib.skx_ext_b(chips)!SKX_EXT_B_BGA1-IC,TBD!!!F130!RSVD(286)!!!!
S!TP_CPU1_RSVD_290!U2D1!C18!@baseboard_fab2_lib.baseboard_fab2(sch_1):page56_i169@chpset_lib.skx_ext_b(chips)!SKX_EXT_B_BGA1-IC,TBD!!!F130!RSVD(290)!!!!
S!TP_CPU1_RSVD_99!U2D1!CG10!@baseboard_fab2_lib.baseboard_fab2(sch_1):page70_i9@chpset_lib.skx_ext_b(chips)!SKX_EXT_B_BGA1-IC,TBD!!!F116!RSVD(99)!!!!
S!TP_CPU1_KTI2_AMONV!U2D1!CN22!@baseboard_fab2_lib.baseboard_fab2(sch_1):page73_i107@chpset_lib.skx_ext_b(chips)!SKX_EXT_B_BGA1-IC,TBD!!!F110!RSVD(77)!!!!
S!TP_CPU1_KTI2_DFX_DN!U2D1!CW22!@baseboard_fab2_lib.baseboard_fab2(sch_1):page73_i107@chpset_lib.skx_ext_b(chips)!SKX_EXT_B_BGA1-IC,TBD!!!F110!RSVD(63)!!!!
S!TP_CPU1_RSVD_59!U2D1!CY23!@baseboard_fab2_lib.baseboard_fab2(sch_1):page73_i107@chpset_lib.skx_ext_b(chips)!SKX_EXT_B_BGA1-IC,TBD!!!F110!RSVD(59)!!!!
S!TP_CPU1_RSVD_85!U2D1!CK19!@baseboard_fab2_lib.baseboard_fab2(sch_1):page70_i10@chpset_lib.skx_ext_b(chips)!SKX_EXT_B_BGA1-IC,TBD!!!F115!RSVD(85)!!!!
S!TP_CPU1_RSVD_15!U2D1!EC16!@baseboard_fab2_lib.baseboard_fab2(sch_1):page73_i107@chpset_lib.skx_ext_b(chips)!SKX_EXT_B_BGA1-IC,TBD!!!F110!RSVD(15)!!!!
S!TP_CPU1_RSVD_8!U2D1!EE16!@baseboard_fab2_lib.baseboard_fab2(sch_1):page73_i107@chpset_lib.skx_ext_b(chips)!SKX_EXT_B_BGA1-IC,TBD!!!F110!RSVD(8)!!!!
S!XDP_PRESENT_N!U2D1!AV21!@baseboard_fab2_lib.baseboard_fab2(sch_1):page56_i169@chpset_lib.skx_ext_b(chips)!SKX_EXT_B_BGA1-IC,TBD!!!F130!DEBUG_EN_N!!!!
S!TP_CPU1_RSVD_168!U2D1!BB15!@baseboard_fab2_lib.baseboard_fab2(sch_1):page70_i9@chpset_lib.skx_ext_b(chips)!SKX_EXT_B_BGA1-IC,TBD!!!F116!RSVD(168)!!!!
S!TP_CPU1_RSVD_176!U2D1!BA18!@baseboard_fab2_lib.baseboard_fab2(sch_1):page63_i23@chpset_lib.skx_ext_b(chips)!SKX_EXT_B_BGA1-IC,TBD!!!F123!RSVD(176)!!!!
S!TP_CPU1_RSVD_147!U2D1!BE22!@baseboard_fab2_lib.baseboard_fab2(sch_1):page70_i9@chpset_lib.skx_ext_b(chips)!SKX_EXT_B_BGA1-IC,TBD!!!F116!RSVD(147)!!!!
S!TP_CPU1_RSVD_159!U2D1!BC22!@baseboard_fab2_lib.baseboard_fab2(sch_1):page70_i9@chpset_lib.skx_ext_b(chips)!SKX_EXT_B_BGA1-IC,TBD!!!F116!RSVD(159)!!!!
S!TP_CPU1_RSVD_160!U2D1!BC20!@baseboard_fab2_lib.baseboard_fab2(sch_1):page70_i9@chpset_lib.skx_ext_b(chips)!SKX_EXT_B_BGA1-IC,TBD!!!F116!RSVD(160)!!!!
S!TP_CPU1_RSVD_148!U2D1!BE20!@baseboard_fab2_lib.baseboard_fab2(sch_1):page70_i9@chpset_lib.skx_ext_b(chips)!SKX_EXT_B_BGA1-IC,TBD!!!F116!RSVD(148)!!!!
S!TP_CPU1_RSVD_154!U2D1!BD19!@baseboard_fab2_lib.baseboard_fab2(sch_1):page70_i9@chpset_lib.skx_ext_b(chips)!SKX_EXT_B_BGA1-IC,TBD!!!F116!RSVD(154)!!!!
S!TP_CPU1_RSVD_178!U2D1!BA14!@baseboard_fab2_lib.baseboard_fab2(sch_1):page63_i23@chpset_lib.skx_ext_b(chips)!SKX_EXT_B_BGA1-IC,TBD!!!F123!RSVD(178)!!!!
S!TP_CPU1_RSVD_146!U2D1!BF21!@baseboard_fab2_lib.baseboard_fab2(sch_1):page70_i9@chpset_lib.skx_ext_b(chips)!SKX_EXT_B_BGA1-IC,TBD!!!F116!RSVD(146)!!!!
S!TP_CPU1_RSVD_169!U2D1!BB13!@baseboard_fab2_lib.baseboard_fab2(sch_1):page70_i9@chpset_lib.skx_ext_b(chips)!SKX_EXT_B_BGA1-IC,TBD!!!F116!RSVD(169)!!!!
S!TP_CPU1_RSVD_144!U2D1!BG20!@baseboard_fab2_lib.baseboard_fab2(sch_1):page70_i9@chpset_lib.skx_ext_b(chips)!SKX_EXT_B_BGA1-IC,TBD!!!F116!RSVD(144)!!!!
S!TP_CPU1_RSVD_145!U2D1!BG18!@baseboard_fab2_lib.baseboard_fab2(sch_1):page70_i9@chpset_lib.skx_ext_b(chips)!SKX_EXT_B_BGA1-IC,TBD!!!F116!RSVD(145)!!!!
S!TP_CPU1_RSVD_162!U2D1!BC14!@baseboard_fab2_lib.baseboard_fab2(sch_1):page70_i9@chpset_lib.skx_ext_b(chips)!SKX_EXT_B_BGA1-IC,TBD!!!F116!RSVD(162)!!!!
S!TP_CPU1_RSVD_167!U2D1!BB17!@baseboard_fab2_lib.baseboard_fab2(sch_1):page70_i9@chpset_lib.skx_ext_b(chips)!SKX_EXT_B_BGA1-IC,TBD!!!F116!RSVD(167)!!!!
S!TP_CPU1_RSVD_149!U2D1!BE18!@baseboard_fab2_lib.baseboard_fab2(sch_1):page70_i9@chpset_lib.skx_ext_b(chips)!SKX_EXT_B_BGA1-IC,TBD!!!F116!RSVD(149)!!!!
S!TP_CPU1_RSVD_177!U2D1!BA16!@baseboard_fab2_lib.baseboard_fab2(sch_1):page63_i23@chpset_lib.skx_ext_b(chips)!SKX_EXT_B_BGA1-IC,TBD!!!F123!RSVD(177)!!!!
S!TP_CPU1_RSVD_161!U2D1!BC18!@baseboard_fab2_lib.baseboard_fab2(sch_1):page70_i9@chpset_lib.skx_ext_b(chips)!SKX_EXT_B_BGA1-IC,TBD!!!F116!RSVD(161)!!!!
S!TP_CPU1_RSVD_166!U2D1!BB21!@baseboard_fab2_lib.baseboard_fab2(sch_1):page70_i9@chpset_lib.skx_ext_b(chips)!SKX_EXT_B_BGA1-IC,TBD!!!F116!RSVD(166)!!!!
S!TP_CPU1_RSVD_155!U2D1!BD17!@baseboard_fab2_lib.baseboard_fab2(sch_1):page70_i9@chpset_lib.skx_ext_b(chips)!SKX_EXT_B_BGA1-IC,TBD!!!F116!RSVD(155)!!!!
S!TP_CPU1_RSVD_175!U2D1!BA22!@baseboard_fab2_lib.baseboard_fab2(sch_1):page63_i23@chpset_lib.skx_ext_b(chips)!SKX_EXT_B_BGA1-IC,TBD!!!F123!RSVD(175)!!!!
S!TP_CPU1_RSVD_57!U2D1!CY39!@baseboard_fab2_lib.baseboard_fab2(sch_1):page73_i107@chpset_lib.skx_ext_b(chips)!SKX_EXT_B_BGA1-IC,TBD!!!F110!RSVD(57)!!!!
S!TP_CPU1_RSVD_51!U2D1!DA40!@baseboard_fab2_lib.baseboard_fab2(sch_1):page73_i107@chpset_lib.skx_ext_b(chips)!SKX_EXT_B_BGA1-IC,TBD!!!F110!RSVD(51)!!!!
S!TP_CPU1_RSVD_38!U2D1!DK37!@baseboard_fab2_lib.baseboard_fab2(sch_1):page73_i107@chpset_lib.skx_ext_b(chips)!SKX_EXT_B_BGA1-IC,TBD!!!F110!RSVD(38)!!!!
S!TP_CPU1_RSVD_35!U2D1!DL38!@baseboard_fab2_lib.baseboard_fab2(sch_1):page73_i107@chpset_lib.skx_ext_b(chips)!SKX_EXT_B_BGA1-IC,TBD!!!F110!RSVD(35)!!!!
S!A_CPU1_MCP01_RBIAS!U2D1!CU32!@baseboard_fab2_lib.baseboard_fab2(sch_1):page55_i172@chpset_lib.skx_ext_b(chips)!SKX_EXT_B_BGA1-IC,TBD!!!F131!MCP01_RBIAS(0)!!!!
S!TP_CPU1_RSVD_44!U2D1!DG36!@baseboard_fab2_lib.baseboard_fab2(sch_1):page73_i107@chpset_lib.skx_ext_b(chips)!SKX_EXT_B_BGA1-IC,TBD!!!F110!RSVD(44)!!!!
S!TP_CPU1_RSVD_41!U2D1!DJ36!@baseboard_fab2_lib.baseboard_fab2(sch_1):page73_i107@chpset_lib.skx_ext_b(chips)!SKX_EXT_B_BGA1-IC,TBD!!!F110!RSVD(41)!!!!
S!PD_CPU1_TEST12!U2D1!AY19!@baseboard_fab2_lib.baseboard_fab2(sch_1):page55_i172@chpset_lib.skx_ext_b(chips)!SKX_EXT_B_BGA1-IC,TBD!!!F131!TEST_12!!!!
S!TP_CPU1_RSVD_39!U2D1!DK15!@baseboard_fab2_lib.baseboard_fab2(sch_1):page73_i107@chpset_lib.skx_ext_b(chips)!SKX_EXT_B_BGA1-IC,TBD!!!F110!RSVD(39)!!!!
S!TP_CPU1_RSVD_30!U2D1!DP17!@baseboard_fab2_lib.baseboard_fab2(sch_1):page73_i107@chpset_lib.skx_ext_b(chips)!SKX_EXT_B_BGA1-IC,TBD!!!F110!RSVD(30)!!!!
S!TP_CPU1_RSVD_113!U2D1!CB5!@baseboard_fab2_lib.baseboard_fab2(sch_1):page70_i9@chpset_lib.skx_ext_b(chips)!SKX_EXT_B_BGA1-IC,TBD!!!F116!RSVD(113)!!!!
S!TP_CPU1_RSVD_111!U2D1!CC6!@baseboard_fab2_lib.baseboard_fab2(sch_1):page70_i9@chpset_lib.skx_ext_b(chips)!SKX_EXT_B_BGA1-IC,TBD!!!F116!RSVD(111)!!!!
S!TP_CPU1_RSVD_123!U2D1!BW10!@baseboard_fab2_lib.baseboard_fab2(sch_1):page70_i9@chpset_lib.skx_ext_b(chips)!SKX_EXT_B_BGA1-IC,TBD!!!F116!RSVD(123)!!!!
S!TP_CPU1_RSVD_70!U2D1!CT5!@baseboard_fab2_lib.baseboard_fab2(sch_1):page73_i107@chpset_lib.skx_ext_b(chips)!SKX_EXT_B_BGA1-IC,TBD!!!F110!RSVD(70)!!!!
S!TP_CPU1_RSVD_67!U2D1!CU6!@baseboard_fab2_lib.baseboard_fab2(sch_1):page73_i107@chpset_lib.skx_ext_b(chips)!SKX_EXT_B_BGA1-IC,TBD!!!F110!RSVD(67)!!!!
S!TP_CPU1_RSVD_14!U2D1!EC4!@baseboard_fab2_lib.baseboard_fab2(sch_1):page73_i107@chpset_lib.skx_ext_b(chips)!SKX_EXT_B_BGA1-IC,TBD!!!F110!RSVD(14)!!!!
S!TP_CPU1_RSVD_17!U2D1!EB5!@baseboard_fab2_lib.baseboard_fab2(sch_1):page73_i107@chpset_lib.skx_ext_b(chips)!SKX_EXT_B_BGA1-IC,TBD!!!F110!RSVD(17)!!!!
S!TP_CPU1_RSVD_21!U2D1!DY3!@baseboard_fab2_lib.baseboard_fab2(sch_1):page73_i107@chpset_lib.skx_ext_b(chips)!SKX_EXT_B_BGA1-IC,TBD!!!F110!RSVD(21)!!!!
S!TP_CPU1_RSVD_20!U2D1!EA4!@baseboard_fab2_lib.baseboard_fab2(sch_1):page73_i107@chpset_lib.skx_ext_b(chips)!SKX_EXT_B_BGA1-IC,TBD!!!F110!RSVD(20)!!!!
S!TP_CPU1_RSVD_18!U2D1!EB3!@baseboard_fab2_lib.baseboard_fab2(sch_1):page73_i107@chpset_lib.skx_ext_b(chips)!SKX_EXT_B_BGA1-IC,TBD!!!F110!RSVD(18)!!!!
S!TP_CPU1_RSVD_10!U2D1!ED5!@baseboard_fab2_lib.baseboard_fab2(sch_1):page73_i107@chpset_lib.skx_ext_b(chips)!SKX_EXT_B_BGA1-IC,TBD!!!F110!RSVD(10)!!!!
S!TP_CPU1_RSVD_6!U2D1!EE6!@baseboard_fab2_lib.baseboard_fab2(sch_1):page73_i107@chpset_lib.skx_ext_b(chips)!SKX_EXT_B_BGA1-IC,TBD!!!F110!RSVD(6)!!!!
S!XDP_CPU_PWR_DEBUG_N!U2D1!AP17!@baseboard_fab2_lib.baseboard_fab2(sch_1):page56_i169@chpset_lib.skx_ext_b(chips)!SKX_EXT_B_BGA1-IC,TBD!!!F130!PWR_DEBUG_N!!!!
S!TP_CPU1_RSVD_282!U2D1!E4!@baseboard_fab2_lib.baseboard_fab2(sch_1):page56_i169@chpset_lib.skx_ext_b(chips)!SKX_EXT_B_BGA1-IC,TBD!!!F130!RSVD(282)!!!!
S!TP_CPU1_RSVD_287!U2D1!D5!@baseboard_fab2_lib.baseboard_fab2(sch_1):page56_i169@chpset_lib.skx_ext_b(chips)!SKX_EXT_B_BGA1-IC,TBD!!!F130!RSVD(287)!!!!
S!TP_CPU1_RSVD_299!U2D1!B3!@baseboard_fab2_lib.baseboard_fab2(sch_1):page56_i169@chpset_lib.skx_ext_b(chips)!SKX_EXT_B_BGA1-IC,TBD!!!F130!RSVD(299)!!!!
S!TP_CPU1_RSVD_304!U2D1!A4!@baseboard_fab2_lib.baseboard_fab2(sch_1):page56_i169@chpset_lib.skx_ext_b(chips)!SKX_EXT_B_BGA1-IC,TBD!!!F130!RSVD(304)!!!!
S!TP_CPU1_RSVD_303!U2D1!A6!@baseboard_fab2_lib.baseboard_fab2(sch_1):page56_i169@chpset_lib.skx_ext_b(chips)!SKX_EXT_B_BGA1-IC,TBD!!!F130!RSVD(303)!!!!
S!TP_CPU1_RSVD_298!U2D1!B7!@baseboard_fab2_lib.baseboard_fab2(sch_1):page56_i169@chpset_lib.skx_ext_b(chips)!SKX_EXT_B_BGA1-IC,TBD!!!F130!RSVD(298)!!!!
S!TP_CPU1_RSVD_275!U2D1!G2!@baseboard_fab2_lib.baseboard_fab2(sch_1):page56_i169@chpset_lib.skx_ext_b(chips)!SKX_EXT_B_BGA1-IC,TBD!!!F130!RSVD(275)!!!!
S!TP_CPU1_RSVD_283!U2D1!E2!@baseboard_fab2_lib.baseboard_fab2(sch_1):page56_i169@chpset_lib.skx_ext_b(chips)!SKX_EXT_B_BGA1-IC,TBD!!!F130!RSVD(283)!!!!
S!TP_CPU1_RSVD_31!U2D1!DN66!@baseboard_fab2_lib.baseboard_fab2(sch_1):page73_i107@chpset_lib.skx_ext_b(chips)!SKX_EXT_B_BGA1-IC,TBD!!!F110!RSVD(31)!!!!
S!TP_CPU1_RSVD_33!U2D1!DM67!@baseboard_fab2_lib.baseboard_fab2(sch_1):page73_i107@chpset_lib.skx_ext_b(chips)!SKX_EXT_B_BGA1-IC,TBD!!!F110!RSVD(33)!!!!
S!TP_CPU1_RSVD_24!U2D1!DV71!@baseboard_fab2_lib.baseboard_fab2(sch_1):page73_i107@chpset_lib.skx_ext_b(chips)!SKX_EXT_B_BGA1-IC,TBD!!!F110!RSVD(24)!!!!
S!TP_CPU1_RSVD_27!U2D1!DT71!@baseboard_fab2_lib.baseboard_fab2(sch_1):page73_i107@chpset_lib.skx_ext_b(chips)!SKX_EXT_B_BGA1-IC,TBD!!!F110!RSVD(27)!!!!
S!TP_CPU1_RSVD_245!U2D1!AF47!@baseboard_fab2_lib.baseboard_fab2(sch_1):page56_i169@chpset_lib.skx_ext_b(chips)!SKX_EXT_B_BGA1-IC,TBD!!!F130!RSVD(245)!!!!
S!TP_CPU1_RSVD_50!U2D1!DA52!@baseboard_fab2_lib.baseboard_fab2(sch_1):page73_i107@chpset_lib.skx_ext_b(chips)!SKX_EXT_B_BGA1-IC,TBD!!!F110!RSVD(50)!!!!
S!TP_CPU1_RSVD_254!U2D1!AD47!@baseboard_fab2_lib.baseboard_fab2(sch_1):page56_i169@chpset_lib.skx_ext_b(chips)!SKX_EXT_B_BGA1-IC,TBD!!!F130!RSVD(254)!!!!
S!TP_CPU1_RSVD_56!U2D1!CY53!@baseboard_fab2_lib.baseboard_fab2(sch_1):page73_i107@chpset_lib.skx_ext_b(chips)!SKX_EXT_B_BGA1-IC,TBD!!!F110!RSVD(56)!!!!
S!M_G_ACT_N!U2D1!J60!@baseboard_fab2_lib.baseboard_fab2(sch_1):page57_i172@chpset_lib.skx_ext_b(chips)!SKX_EXT_B_BGA1-IC,TBD!!!F129!DDR0_ACT_N!!!!
S!M_G_ALERT_N!U2D1!B61!@baseboard_fab2_lib.baseboard_fab2(sch_1):page57_i172@chpset_lib.skx_ext_b(chips)!SKX_EXT_B_BGA1-IC,TBD!!!F129!DDR0_ALERT_N!!!!
S!M_G_BA<0>!U2D1!C52!@baseboard_fab2_lib.baseboard_fab2(sch_1):page57_i172@chpset_lib.skx_ext_b(chips)!SKX_EXT_B_BGA1-IC,TBD!!!F129!DDR0_BA(0)!!!!
S!M_G_BA<1>!U2D1!G54!@baseboard_fab2_lib.baseboard_fab2(sch_1):page57_i172@chpset_lib.skx_ext_b(chips)!SKX_EXT_B_BGA1-IC,TBD!!!F129!DDR0_BA(1)!!!!
S!M_G_BG<0>!U2D1!D61!@baseboard_fab2_lib.baseboard_fab2(sch_1):page57_i172@chpset_lib.skx_ext_b(chips)!SKX_EXT_B_BGA1-IC,TBD!!!F129!DDR0_BG(0)!!!!
S!M_G_BG<1>!U2D1!F63!@baseboard_fab2_lib.baseboard_fab2(sch_1):page57_i172@chpset_lib.skx_ext_b(chips)!SKX_EXT_B_BGA1-IC,TBD!!!F129!DDR0_BG(1)!!!!
S!M_G_C<2>!U2D1!G46!@baseboard_fab2_lib.baseboard_fab2(sch_1):page57_i172@chpset_lib.skx_ext_b(chips)!SKX_EXT_B_BGA1-IC,TBD!!!F129!DDR0_CID(2)!!!!
S!M_G_CKE<0>!U2D1!C62!@baseboard_fab2_lib.baseboard_fab2(sch_1):page57_i172@chpset_lib.skx_ext_b(chips)!SKX_EXT_B_BGA1-IC,TBD!!!F129!DDR0_CKE(0)!!!!
S!M_G_CKE<1>!U2D1!C64!@baseboard_fab2_lib.baseboard_fab2(sch_1):page57_i172@chpset_lib.skx_ext_b(chips)!SKX_EXT_B_BGA1-IC,TBD!!!F129!DDR0_CKE(1)!!!!
S!M_G_CKE<2>!U2D1!B63!@baseboard_fab2_lib.baseboard_fab2(sch_1):page57_i172@chpset_lib.skx_ext_b(chips)!SKX_EXT_B_BGA1-IC,TBD!!!F129!DDR0_CKE(2)!!!!
S!M_G_CKE<3>!U2D1!D63!@baseboard_fab2_lib.baseboard_fab2(sch_1):page57_i172@chpset_lib.skx_ext_b(chips)!SKX_EXT_B_BGA1-IC,TBD!!!F129!DDR0_CKE(3)!!!!
S!M_G_CLK_DN<0>!U2D1!F55!@baseboard_fab2_lib.baseboard_fab2(sch_1):page57_i172@chpset_lib.skx_ext_b(chips)!SKX_EXT_B_BGA1-IC,TBD!!!F129!DDR0_CLK_DN(0)!!!!
S!M_G_CLK_DN<2>!U2D1!J56!@baseboard_fab2_lib.baseboard_fab2(sch_1):page57_i172@chpset_lib.skx_ext_b(chips)!SKX_EXT_B_BGA1-IC,TBD!!!F129!DDR0_CLK_DN(2)!!!!
S!M_G_CLK_DN<1>!U2D1!C54!@baseboard_fab2_lib.baseboard_fab2(sch_1):page57_i172@chpset_lib.skx_ext_b(chips)!SKX_EXT_B_BGA1-IC,TBD!!!F129!DDR0_CLK_DN(1)!!!!
S!M_G_CLK_DN<3>!U2D1!C56!@baseboard_fab2_lib.baseboard_fab2(sch_1):page57_i172@chpset_lib.skx_ext_b(chips)!SKX_EXT_B_BGA1-IC,TBD!!!F129!DDR0_CLK_DN(3)!!!!
S!M_G_CLK_DP<0>!U2D1!D55!@baseboard_fab2_lib.baseboard_fab2(sch_1):page57_i172@chpset_lib.skx_ext_b(chips)!SKX_EXT_B_BGA1-IC,TBD!!!F129!DDR0_CLK_DP(0)!!!!
S!M_G_CLK_DP<2>!U2D1!G56!@baseboard_fab2_lib.baseboard_fab2(sch_1):page57_i172@chpset_lib.skx_ext_b(chips)!SKX_EXT_B_BGA1-IC,TBD!!!F129!DDR0_CLK_DP(2)!!!!
S!M_G_CLK_DP<1>!U2D1!B55!@baseboard_fab2_lib.baseboard_fab2(sch_1):page57_i172@chpset_lib.skx_ext_b(chips)!SKX_EXT_B_BGA1-IC,TBD!!!F129!DDR0_CLK_DP(1)!!!!
S!M_G_CLK_DP<3>!U2D1!B57!@baseboard_fab2_lib.baseboard_fab2(sch_1):page57_i172@chpset_lib.skx_ext_b(chips)!SKX_EXT_B_BGA1-IC,TBD!!!F129!DDR0_CLK_DP(3)!!!!
S!M_G_CS_N<0>!U2D1!G52!@baseboard_fab2_lib.baseboard_fab2(sch_1):page57_i172@chpset_lib.skx_ext_b(chips)!SKX_EXT_B_BGA1-IC,TBD!!!F129!DDR0_CS_N(0)!!!!
S!M_G_CS_N<1>!U2D1!F49!@baseboard_fab2_lib.baseboard_fab2(sch_1):page57_i172@chpset_lib.skx_ext_b(chips)!SKX_EXT_B_BGA1-IC,TBD!!!F129!DDR0_CS_N(1)!!!!
S!M_G_CS_N<2>!U2D1!D47!@baseboard_fab2_lib.baseboard_fab2(sch_1):page57_i172@chpset_lib.skx_ext_b(chips)!SKX_EXT_B_BGA1-IC,TBD!!!F129!DDR0_CS_N(2)!!!!
S!M_G_CS_N<3>!U2D1!F47!@baseboard_fab2_lib.baseboard_fab2(sch_1):page57_i172@chpset_lib.skx_ext_b(chips)!SKX_EXT_B_BGA1-IC,TBD!!!F129!DDR0_CS_N(3)!!!!
S!M_G_CS_N<4>!U2D1!B51!@baseboard_fab2_lib.baseboard_fab2(sch_1):page57_i172@chpset_lib.skx_ext_b(chips)!SKX_EXT_B_BGA1-IC,TBD!!!F129!DDR0_CS_N(4)!!!!
S!M_G_CS_N<5>!U2D1!D49!@baseboard_fab2_lib.baseboard_fab2(sch_1):page57_i172@chpset_lib.skx_ext_b(chips)!SKX_EXT_B_BGA1-IC,TBD!!!F129!DDR0_CS_N(5)!!!!
S!M_G_CS_N<6>!U2D1!F45!@baseboard_fab2_lib.baseboard_fab2(sch_1):page57_i172@chpset_lib.skx_ext_b(chips)!SKX_EXT_B_BGA1-IC,TBD!!!F129!DDR0_CS_N(6)!!!!
S!M_G_CS_N<7>!U2D1!K45!@baseboard_fab2_lib.baseboard_fab2(sch_1):page57_i172@chpset_lib.skx_ext_b(chips)!SKX_EXT_B_BGA1-IC,TBD!!!F129!DDR0_CS_N(7)!!!!
S!M_G_DQ<0>!U2D1!AN86!@baseboard_fab2_lib.baseboard_fab2(sch_1):page57_i172@chpset_lib.skx_ext_b(chips)!SKX_EXT_B_BGA1-IC,TBD!!!F129!DDR0_DQ(0)!!!!
S!M_G_DQ<10>!U2D1!L86!@baseboard_fab2_lib.baseboard_fab2(sch_1):page57_i172@chpset_lib.skx_ext_b(chips)!SKX_EXT_B_BGA1-IC,TBD!!!F129!DDR0_DQ(10)!!!!
S!M_G_DQ<11>!U2D1!L84!@baseboard_fab2_lib.baseboard_fab2(sch_1):page57_i172@chpset_lib.skx_ext_b(chips)!SKX_EXT_B_BGA1-IC,TBD!!!F129!DDR0_DQ(11)!!!!
S!M_G_DQ<12>!U2D1!AA86!@baseboard_fab2_lib.baseboard_fab2(sch_1):page57_i172@chpset_lib.skx_ext_b(chips)!SKX_EXT_B_BGA1-IC,TBD!!!F129!DDR0_DQ(12)!!!!
S!M_G_DQ<13>!U2D1!AA84!@baseboard_fab2_lib.baseboard_fab2(sch_1):page57_i172@chpset_lib.skx_ext_b(chips)!SKX_EXT_B_BGA1-IC,TBD!!!F129!DDR0_DQ(13)!!!!
S!M_G_DQ<14>!U2D1!N86!@baseboard_fab2_lib.baseboard_fab2(sch_1):page57_i172@chpset_lib.skx_ext_b(chips)!SKX_EXT_B_BGA1-IC,TBD!!!F129!DDR0_DQ(14)!!!!
S!M_G_DQ<15>!U2D1!N84!@baseboard_fab2_lib.baseboard_fab2(sch_1):page57_i172@chpset_lib.skx_ext_b(chips)!SKX_EXT_B_BGA1-IC,TBD!!!F129!DDR0_DQ(15)!!!!
S!M_G_DQ<16>!U2D1!V81!@baseboard_fab2_lib.baseboard_fab2(sch_1):page57_i172@chpset_lib.skx_ext_b(chips)!SKX_EXT_B_BGA1-IC,TBD!!!F129!DDR0_DQ(16)!!!!
S!M_G_DQ<17>!U2D1!T79!@baseboard_fab2_lib.baseboard_fab2(sch_1):page57_i172@chpset_lib.skx_ext_b(chips)!SKX_EXT_B_BGA1-IC,TBD!!!F129!DDR0_DQ(17)!!!!
S!M_G_DQ<18>!U2D1!N82!@baseboard_fab2_lib.baseboard_fab2(sch_1):page57_i172@chpset_lib.skx_ext_b(chips)!SKX_EXT_B_BGA1-IC,TBD!!!F129!DDR0_DQ(18)!!!!
S!M_G_DQ<19>!U2D1!M81!@baseboard_fab2_lib.baseboard_fab2(sch_1):page57_i172@chpset_lib.skx_ext_b(chips)!SKX_EXT_B_BGA1-IC,TBD!!!F129!DDR0_DQ(19)!!!!
S!M_G_DQ<1>!U2D1!AN84!@baseboard_fab2_lib.baseboard_fab2(sch_1):page57_i172@chpset_lib.skx_ext_b(chips)!SKX_EXT_B_BGA1-IC,TBD!!!F129!DDR0_DQ(1)!!!!
S!M_G_DQ<20>!U2D1!W80!@baseboard_fab2_lib.baseboard_fab2(sch_1):page57_i172@chpset_lib.skx_ext_b(chips)!SKX_EXT_B_BGA1-IC,TBD!!!F129!DDR0_DQ(20)!!!!
S!M_G_DQ<21>!U2D1!V79!@baseboard_fab2_lib.baseboard_fab2(sch_1):page57_i172@chpset_lib.skx_ext_b(chips)!SKX_EXT_B_BGA1-IC,TBD!!!F129!DDR0_DQ(21)!!!!
S!M_G_DQ<22>!U2D1!R82!@baseboard_fab2_lib.baseboard_fab2(sch_1):page57_i172@chpset_lib.skx_ext_b(chips)!SKX_EXT_B_BGA1-IC,TBD!!!F129!DDR0_DQ(22)!!!!
S!M_G_DQ<23>!U2D1!N80!@baseboard_fab2_lib.baseboard_fab2(sch_1):page57_i172@chpset_lib.skx_ext_b(chips)!SKX_EXT_B_BGA1-IC,TBD!!!F129!DDR0_DQ(23)!!!!
S!M_G_DQ<24>!U2D1!L76!@baseboard_fab2_lib.baseboard_fab2(sch_1):page57_i172@chpset_lib.skx_ext_b(chips)!SKX_EXT_B_BGA1-IC,TBD!!!F129!DDR0_DQ(24)!!!!
S!M_G_DQ<25>!U2D1!R76!@baseboard_fab2_lib.baseboard_fab2(sch_1):page57_i172@chpset_lib.skx_ext_b(chips)!SKX_EXT_B_BGA1-IC,TBD!!!F129!DDR0_DQ(25)!!!!
S!M_G_DQ<26>!U2D1!M73!@baseboard_fab2_lib.baseboard_fab2(sch_1):page57_i172@chpset_lib.skx_ext_b(chips)!SKX_EXT_B_BGA1-IC,TBD!!!F129!DDR0_DQ(26)!!!!
S!M_G_DQ<27>!U2D1!P73!@baseboard_fab2_lib.baseboard_fab2(sch_1):page57_i172@chpset_lib.skx_ext_b(chips)!SKX_EXT_B_BGA1-IC,TBD!!!F129!DDR0_DQ(27)!!!!
S!M_G_DQ<28>!U2D1!M77!@baseboard_fab2_lib.baseboard_fab2(sch_1):page57_i172@chpset_lib.skx_ext_b(chips)!SKX_EXT_B_BGA1-IC,TBD!!!F129!DDR0_DQ(28)!!!!
S!M_G_DQ<29>!U2D1!P77!@baseboard_fab2_lib.baseboard_fab2(sch_1):page57_i172@chpset_lib.skx_ext_b(chips)!SKX_EXT_B_BGA1-IC,TBD!!!F129!DDR0_DQ(29)!!!!
S!M_G_DQ<2>!U2D1!AE86!@baseboard_fab2_lib.baseboard_fab2(sch_1):page57_i172@chpset_lib.skx_ext_b(chips)!SKX_EXT_B_BGA1-IC,TBD!!!F129!DDR0_DQ(2)!!!!
S!M_G_DQ<30>!U2D1!L74!@baseboard_fab2_lib.baseboard_fab2(sch_1):page57_i172@chpset_lib.skx_ext_b(chips)!SKX_EXT_B_BGA1-IC,TBD!!!F129!DDR0_DQ(30)!!!!
S!M_G_DQ<31>!U2D1!R74!@baseboard_fab2_lib.baseboard_fab2(sch_1):page57_i172@chpset_lib.skx_ext_b(chips)!SKX_EXT_B_BGA1-IC,TBD!!!F129!DDR0_DQ(31)!!!!
S!M_G_DQ<32>!U2D1!C42!@baseboard_fab2_lib.baseboard_fab2(sch_1):page57_i172@chpset_lib.skx_ext_b(chips)!SKX_EXT_B_BGA1-IC,TBD!!!F129!DDR0_DQ(32)!!!!
S!M_G_DQ<33>!U2D1!B41!@baseboard_fab2_lib.baseboard_fab2(sch_1):page57_i172@chpset_lib.skx_ext_b(chips)!SKX_EXT_B_BGA1-IC,TBD!!!F129!DDR0_DQ(33)!!!!
S!M_G_DQ<34>!U2D1!C38!@baseboard_fab2_lib.baseboard_fab2(sch_1):page57_i172@chpset_lib.skx_ext_b(chips)!SKX_EXT_B_BGA1-IC,TBD!!!F129!DDR0_DQ(34)!!!!
S!M_G_DQ<35>!U2D1!E38!@baseboard_fab2_lib.baseboard_fab2(sch_1):page57_i172@chpset_lib.skx_ext_b(chips)!SKX_EXT_B_BGA1-IC,TBD!!!F129!DDR0_DQ(35)!!!!
S!M_G_DQ<36>!U2D1!E42!@baseboard_fab2_lib.baseboard_fab2(sch_1):page57_i172@chpset_lib.skx_ext_b(chips)!SKX_EXT_B_BGA1-IC,TBD!!!F129!DDR0_DQ(36)!!!!
S!M_G_DQ<37>!U2D1!F41!@baseboard_fab2_lib.baseboard_fab2(sch_1):page57_i172@chpset_lib.skx_ext_b(chips)!SKX_EXT_B_BGA1-IC,TBD!!!F129!DDR0_DQ(37)!!!!
S!M_G_DQ<38>!U2D1!B39!@baseboard_fab2_lib.baseboard_fab2(sch_1):page57_i172@chpset_lib.skx_ext_b(chips)!SKX_EXT_B_BGA1-IC,TBD!!!F129!DDR0_DQ(38)!!!!
S!M_G_DQ<39>!U2D1!F39!@baseboard_fab2_lib.baseboard_fab2(sch_1):page57_i172@chpset_lib.skx_ext_b(chips)!SKX_EXT_B_BGA1-IC,TBD!!!F129!DDR0_DQ(39)!!!!
S!M_G_DQ<3>!U2D1!AE84!@baseboard_fab2_lib.baseboard_fab2(sch_1):page57_i172@chpset_lib.skx_ext_b(chips)!SKX_EXT_B_BGA1-IC,TBD!!!F129!DDR0_DQ(3)!!!!
S!M_G_DQ<40>!U2D1!K37!@baseboard_fab2_lib.baseboard_fab2(sch_1):page57_i172@chpset_lib.skx_ext_b(chips)!SKX_EXT_B_BGA1-IC,TBD!!!F129!DDR0_DQ(40)!!!!
S!M_G_DQ<41>!U2D1!P37!@baseboard_fab2_lib.baseboard_fab2(sch_1):page57_i172@chpset_lib.skx_ext_b(chips)!SKX_EXT_B_BGA1-IC,TBD!!!F129!DDR0_DQ(41)!!!!
S!M_G_DQ<42>!U2D1!L34!@baseboard_fab2_lib.baseboard_fab2(sch_1):page57_i172@chpset_lib.skx_ext_b(chips)!SKX_EXT_B_BGA1-IC,TBD!!!F129!DDR0_DQ(42)!!!!
S!M_G_DQ<43>!U2D1!N34!@baseboard_fab2_lib.baseboard_fab2(sch_1):page57_i172@chpset_lib.skx_ext_b(chips)!SKX_EXT_B_BGA1-IC,TBD!!!F129!DDR0_DQ(43)!!!!
S!M_G_DQ<44>!U2D1!L38!@baseboard_fab2_lib.baseboard_fab2(sch_1):page57_i172@chpset_lib.skx_ext_b(chips)!SKX_EXT_B_BGA1-IC,TBD!!!F129!DDR0_DQ(44)!!!!
S!M_G_DQ<45>!U2D1!N38!@baseboard_fab2_lib.baseboard_fab2(sch_1):page57_i172@chpset_lib.skx_ext_b(chips)!SKX_EXT_B_BGA1-IC,TBD!!!F129!DDR0_DQ(45)!!!!
S!M_G_DQ<46>!U2D1!K35!@baseboard_fab2_lib.baseboard_fab2(sch_1):page57_i172@chpset_lib.skx_ext_b(chips)!SKX_EXT_B_BGA1-IC,TBD!!!F129!DDR0_DQ(46)!!!!
S!M_G_DQ<47>!U2D1!P35!@baseboard_fab2_lib.baseboard_fab2(sch_1):page57_i172@chpset_lib.skx_ext_b(chips)!SKX_EXT_B_BGA1-IC,TBD!!!F129!DDR0_DQ(47)!!!!
S!M_G_DQ<48>!U2D1!K31!@baseboard_fab2_lib.baseboard_fab2(sch_1):page57_i172@chpset_lib.skx_ext_b(chips)!SKX_EXT_B_BGA1-IC,TBD!!!F129!DDR0_DQ(48)!!!!
S!M_G_DQ<49>!U2D1!P31!@baseboard_fab2_lib.baseboard_fab2(sch_1):page57_i172@chpset_lib.skx_ext_b(chips)!SKX_EXT_B_BGA1-IC,TBD!!!F129!DDR0_DQ(49)!!!!
S!M_G_DQ<4>!U2D1!AR86!@baseboard_fab2_lib.baseboard_fab2(sch_1):page57_i172@chpset_lib.skx_ext_b(chips)!SKX_EXT_B_BGA1-IC,TBD!!!F129!DDR0_DQ(4)!!!!
S!M_G_DQ<50>!U2D1!L28!@baseboard_fab2_lib.baseboard_fab2(sch_1):page57_i172@chpset_lib.skx_ext_b(chips)!SKX_EXT_B_BGA1-IC,TBD!!!F129!DDR0_DQ(50)!!!!
S!M_G_DQ<51>!U2D1!N28!@baseboard_fab2_lib.baseboard_fab2(sch_1):page57_i172@chpset_lib.skx_ext_b(chips)!SKX_EXT_B_BGA1-IC,TBD!!!F129!DDR0_DQ(51)!!!!
S!M_G_DQ<52>!U2D1!L32!@baseboard_fab2_lib.baseboard_fab2(sch_1):page57_i172@chpset_lib.skx_ext_b(chips)!SKX_EXT_B_BGA1-IC,TBD!!!F129!DDR0_DQ(52)!!!!
S!M_G_DQ<53>!U2D1!N32!@baseboard_fab2_lib.baseboard_fab2(sch_1):page57_i172@chpset_lib.skx_ext_b(chips)!SKX_EXT_B_BGA1-IC,TBD!!!F129!DDR0_DQ(53)!!!!
S!M_G_DQ<54>!U2D1!K29!@baseboard_fab2_lib.baseboard_fab2(sch_1):page57_i172@chpset_lib.skx_ext_b(chips)!SKX_EXT_B_BGA1-IC,TBD!!!F129!DDR0_DQ(54)!!!!
S!M_G_DQ<55>!U2D1!P29!@baseboard_fab2_lib.baseboard_fab2(sch_1):page57_i172@chpset_lib.skx_ext_b(chips)!SKX_EXT_B_BGA1-IC,TBD!!!F129!DDR0_DQ(55)!!!!
S!M_G_DQ<56>!U2D1!K25!@baseboard_fab2_lib.baseboard_fab2(sch_1):page57_i172@chpset_lib.skx_ext_b(chips)!SKX_EXT_B_BGA1-IC,TBD!!!F129!DDR0_DQ(56)!!!!
S!M_G_DQ<57>!U2D1!P25!@baseboard_fab2_lib.baseboard_fab2(sch_1):page57_i172@chpset_lib.skx_ext_b(chips)!SKX_EXT_B_BGA1-IC,TBD!!!F129!DDR0_DQ(57)!!!!
S!M_G_DQ<58>!U2D1!P23!@baseboard_fab2_lib.baseboard_fab2(sch_1):page57_i172@chpset_lib.skx_ext_b(chips)!SKX_EXT_B_BGA1-IC,TBD!!!F129!DDR0_DQ(58)!!!!
S!M_G_DQ<59>!U2D1!T23!@baseboard_fab2_lib.baseboard_fab2(sch_1):page57_i172@chpset_lib.skx_ext_b(chips)!SKX_EXT_B_BGA1-IC,TBD!!!F129!DDR0_DQ(59)!!!!
S!M_G_DQ<5>!U2D1!AR84!@baseboard_fab2_lib.baseboard_fab2(sch_1):page57_i172@chpset_lib.skx_ext_b(chips)!SKX_EXT_B_BGA1-IC,TBD!!!F129!DDR0_DQ(5)!!!!
S!M_G_DQ<60>!U2D1!L26!@baseboard_fab2_lib.baseboard_fab2(sch_1):page57_i172@chpset_lib.skx_ext_b(chips)!SKX_EXT_B_BGA1-IC,TBD!!!F129!DDR0_DQ(60)!!!!
S!M_G_DQ<61>!U2D1!N26!@baseboard_fab2_lib.baseboard_fab2(sch_1):page57_i172@chpset_lib.skx_ext_b(chips)!SKX_EXT_B_BGA1-IC,TBD!!!F129!DDR0_DQ(61)!!!!
S!M_G_DQ<62>!U2D1!H23!@baseboard_fab2_lib.baseboard_fab2(sch_1):page57_i172@chpset_lib.skx_ext_b(chips)!SKX_EXT_B_BGA1-IC,TBD!!!F129!DDR0_DQ(62)!!!!
S!M_G_DQ<63>!U2D1!K23!@baseboard_fab2_lib.baseboard_fab2(sch_1):page57_i172@chpset_lib.skx_ext_b(chips)!SKX_EXT_B_BGA1-IC,TBD!!!F129!DDR0_DQ(63)!!!!
S!M_G_DQ<6>!U2D1!AG86!@baseboard_fab2_lib.baseboard_fab2(sch_1):page57_i172@chpset_lib.skx_ext_b(chips)!SKX_EXT_B_BGA1-IC,TBD!!!F129!DDR0_DQ(6)!!!!
S!M_G_DQ<7>!U2D1!AG84!@baseboard_fab2_lib.baseboard_fab2(sch_1):page57_i172@chpset_lib.skx_ext_b(chips)!SKX_EXT_B_BGA1-IC,TBD!!!F129!DDR0_DQ(7)!!!!
S!M_G_DQ<8>!U2D1!W86!@baseboard_fab2_lib.baseboard_fab2(sch_1):page57_i172@chpset_lib.skx_ext_b(chips)!SKX_EXT_B_BGA1-IC,TBD!!!F129!DDR0_DQ(8)!!!!
S!M_G_DQ<9>!U2D1!W84!@baseboard_fab2_lib.baseboard_fab2(sch_1):page57_i172@chpset_lib.skx_ext_b(chips)!SKX_EXT_B_BGA1-IC,TBD!!!F129!DDR0_DQ(9)!!!!
S!M_G_DQS_DN<0>!U2D1!AJ84!@baseboard_fab2_lib.baseboard_fab2(sch_1):page57_i172@chpset_lib.skx_ext_b(chips)!SKX_EXT_B_BGA1-IC,TBD!!!F129!DDR0_DQS_DN(0)!!!!
S!M_G_DQS_DN<10>!U2D1!U84!@baseboard_fab2_lib.baseboard_fab2(sch_1):page57_i172@chpset_lib.skx_ext_b(chips)!SKX_EXT_B_BGA1-IC,TBD!!!F129!DDR0_DQS_DN(10)!!!!
S!M_G_DQS_DN<11>!U2D1!U82!@baseboard_fab2_lib.baseboard_fab2(sch_1):page57_i172@chpset_lib.skx_ext_b(chips)!SKX_EXT_B_BGA1-IC,TBD!!!F129!DDR0_DQS_DN(11)!!!!
S!M_G_DQS_DN<12>!U2D1!K75!@baseboard_fab2_lib.baseboard_fab2(sch_1):page57_i172@chpset_lib.skx_ext_b(chips)!SKX_EXT_B_BGA1-IC,TBD!!!F129!DDR0_DQS_DN(12)!!!!
S!M_G_DQS_DN<13>!U2D1!A40!@baseboard_fab2_lib.baseboard_fab2(sch_1):page57_i172@chpset_lib.skx_ext_b(chips)!SKX_EXT_B_BGA1-IC,TBD!!!F129!DDR0_DQS_DN(13)!!!!
S!M_G_DQS_DN<14>!U2D1!J36!@baseboard_fab2_lib.baseboard_fab2(sch_1):page57_i172@chpset_lib.skx_ext_b(chips)!SKX_EXT_B_BGA1-IC,TBD!!!F129!DDR0_DQS_DN(14)!!!!
S!M_G_DQS_DN<15>!U2D1!J30!@baseboard_fab2_lib.baseboard_fab2(sch_1):page57_i172@chpset_lib.skx_ext_b(chips)!SKX_EXT_B_BGA1-IC,TBD!!!F129!DDR0_DQS_DN(15)!!!!
S!M_G_DQS_DN<16>!U2D1!J24!@baseboard_fab2_lib.baseboard_fab2(sch_1):page57_i172@chpset_lib.skx_ext_b(chips)!SKX_EXT_B_BGA1-IC,TBD!!!F129!DDR0_DQS_DN(16)!!!!
S!M_G_DQS_DN<17>!U2D1!AB67!@baseboard_fab2_lib.baseboard_fab2(sch_1):page57_i172@chpset_lib.skx_ext_b(chips)!SKX_EXT_B_BGA1-IC,TBD!!!F129!DDR0_DQS_DN(17)!!!!
S!M_G_DQS_DN<1>!U2D1!R84!@baseboard_fab2_lib.baseboard_fab2(sch_1):page57_i172@chpset_lib.skx_ext_b(chips)!SKX_EXT_B_BGA1-IC,TBD!!!F129!DDR0_DQS_DN(1)!!!!
S!M_G_DQS_DN<2>!U2D1!P79!@baseboard_fab2_lib.baseboard_fab2(sch_1):page57_i172@chpset_lib.skx_ext_b(chips)!SKX_EXT_B_BGA1-IC,TBD!!!F129!DDR0_DQS_DN(2)!!!!
S!M_G_DQS_DN<3>!U2D1!T75!@baseboard_fab2_lib.baseboard_fab2(sch_1):page57_i172@chpset_lib.skx_ext_b(chips)!SKX_EXT_B_BGA1-IC,TBD!!!F129!DDR0_DQS_DN(3)!!!!
S!M_G_DQS_DN<4>!U2D1!G40!@baseboard_fab2_lib.baseboard_fab2(sch_1):page57_i172@chpset_lib.skx_ext_b(chips)!SKX_EXT_B_BGA1-IC,TBD!!!F129!DDR0_DQS_DN(4)!!!!
S!M_G_DQS_DN<5>!U2D1!R36!@baseboard_fab2_lib.baseboard_fab2(sch_1):page57_i172@chpset_lib.skx_ext_b(chips)!SKX_EXT_B_BGA1-IC,TBD!!!F129!DDR0_DQS_DN(5)!!!!
S!M_G_DQS_DN<6>!U2D1!R30!@baseboard_fab2_lib.baseboard_fab2(sch_1):page57_i172@chpset_lib.skx_ext_b(chips)!SKX_EXT_B_BGA1-IC,TBD!!!F129!DDR0_DQS_DN(6)!!!!
S!M_G_DQS_DN<7>!U2D1!N24!@baseboard_fab2_lib.baseboard_fab2(sch_1):page57_i172@chpset_lib.skx_ext_b(chips)!SKX_EXT_B_BGA1-IC,TBD!!!F129!DDR0_DQS_DN(7)!!!!
S!M_G_DQS_DN<8>!U2D1!AH67!@baseboard_fab2_lib.baseboard_fab2(sch_1):page57_i172@chpset_lib.skx_ext_b(chips)!SKX_EXT_B_BGA1-IC,TBD!!!F129!DDR0_DQS_DN(8)!!!!
S!M_G_DQS_DN<9>!U2D1!AL84!@baseboard_fab2_lib.baseboard_fab2(sch_1):page57_i172@chpset_lib.skx_ext_b(chips)!SKX_EXT_B_BGA1-IC,TBD!!!F129!DDR0_DQS_DN(9)!!!!
S!M_G_DQS_DP<0>!U2D1!AH85!@baseboard_fab2_lib.baseboard_fab2(sch_1):page57_i172@chpset_lib.skx_ext_b(chips)!SKX_EXT_B_BGA1-IC,TBD!!!F129!DDR0_DQS_DP(0)!!!!
S!M_G_DQS_DP<10>!U2D1!V85!@baseboard_fab2_lib.baseboard_fab2(sch_1):page57_i172@chpset_lib.skx_ext_b(chips)!SKX_EXT_B_BGA1-IC,TBD!!!F129!DDR0_DQS_DP(10)!!!!
S!M_G_DQS_DP<11>!U2D1!T81!@baseboard_fab2_lib.baseboard_fab2(sch_1):page57_i172@chpset_lib.skx_ext_b(chips)!SKX_EXT_B_BGA1-IC,TBD!!!F129!DDR0_DQS_DP(11)!!!!
S!M_G_DQS_DP<12>!U2D1!M75!@baseboard_fab2_lib.baseboard_fab2(sch_1):page57_i172@chpset_lib.skx_ext_b(chips)!SKX_EXT_B_BGA1-IC,TBD!!!F129!DDR0_DQS_DP(12)!!!!
S!M_G_DQS_DP<13>!U2D1!C40!@baseboard_fab2_lib.baseboard_fab2(sch_1):page57_i172@chpset_lib.skx_ext_b(chips)!SKX_EXT_B_BGA1-IC,TBD!!!F129!DDR0_DQS_DP(13)!!!!
S!M_G_DQS_DP<14>!U2D1!L36!@baseboard_fab2_lib.baseboard_fab2(sch_1):page57_i172@chpset_lib.skx_ext_b(chips)!SKX_EXT_B_BGA1-IC,TBD!!!F129!DDR0_DQS_DP(14)!!!!
S!M_G_DQS_DP<15>!U2D1!L30!@baseboard_fab2_lib.baseboard_fab2(sch_1):page57_i172@chpset_lib.skx_ext_b(chips)!SKX_EXT_B_BGA1-IC,TBD!!!F129!DDR0_DQS_DP(15)!!!!
S!M_G_DQS_DP<16>!U2D1!L24!@baseboard_fab2_lib.baseboard_fab2(sch_1):page57_i172@chpset_lib.skx_ext_b(chips)!SKX_EXT_B_BGA1-IC,TBD!!!F129!DDR0_DQS_DP(16)!!!!
S!M_G_DQS_DP<17>!U2D1!AD67!@baseboard_fab2_lib.baseboard_fab2(sch_1):page57_i172@chpset_lib.skx_ext_b(chips)!SKX_EXT_B_BGA1-IC,TBD!!!F129!DDR0_DQS_DP(17)!!!!
S!M_G_DQS_DP<1>!U2D1!P85!@baseboard_fab2_lib.baseboard_fab2(sch_1):page57_i172@chpset_lib.skx_ext_b(chips)!SKX_EXT_B_BGA1-IC,TBD!!!F129!DDR0_DQS_DP(1)!!!!
S!M_G_DQS_DP<2>!U2D1!R80!@baseboard_fab2_lib.baseboard_fab2(sch_1):page57_i172@chpset_lib.skx_ext_b(chips)!SKX_EXT_B_BGA1-IC,TBD!!!F129!DDR0_DQS_DP(2)!!!!
S!M_G_DQS_DP<3>!U2D1!P75!@baseboard_fab2_lib.baseboard_fab2(sch_1):page57_i172@chpset_lib.skx_ext_b(chips)!SKX_EXT_B_BGA1-IC,TBD!!!F129!DDR0_DQS_DP(3)!!!!
S!M_G_DQS_DP<4>!U2D1!E40!@baseboard_fab2_lib.baseboard_fab2(sch_1):page57_i172@chpset_lib.skx_ext_b(chips)!SKX_EXT_B_BGA1-IC,TBD!!!F129!DDR0_DQS_DP(4)!!!!
S!M_G_DQS_DP<5>!U2D1!N36!@baseboard_fab2_lib.baseboard_fab2(sch_1):page57_i172@chpset_lib.skx_ext_b(chips)!SKX_EXT_B_BGA1-IC,TBD!!!F129!DDR0_DQS_DP(5)!!!!
S!M_G_DQS_DP<6>!U2D1!N30!@baseboard_fab2_lib.baseboard_fab2(sch_1):page57_i172@chpset_lib.skx_ext_b(chips)!SKX_EXT_B_BGA1-IC,TBD!!!F129!DDR0_DQS_DP(6)!!!!
S!M_G_DQS_DP<7>!U2D1!R24!@baseboard_fab2_lib.baseboard_fab2(sch_1):page57_i172@chpset_lib.skx_ext_b(chips)!SKX_EXT_B_BGA1-IC,TBD!!!F129!DDR0_DQS_DP(7)!!!!
S!M_G_DQS_DP<8>!U2D1!AF67!@baseboard_fab2_lib.baseboard_fab2(sch_1):page57_i172@chpset_lib.skx_ext_b(chips)!SKX_EXT_B_BGA1-IC,TBD!!!F129!DDR0_DQS_DP(8)!!!!
S!M_G_DQS_DP<9>!U2D1!AM85!@baseboard_fab2_lib.baseboard_fab2(sch_1):page57_i172@chpset_lib.skx_ext_b(chips)!SKX_EXT_B_BGA1-IC,TBD!!!F129!DDR0_DQS_DP(9)!!!!
S!M_G_ECC<0>!U2D1!AC68!@baseboard_fab2_lib.baseboard_fab2(sch_1):page57_i172@chpset_lib.skx_ext_b(chips)!SKX_EXT_B_BGA1-IC,TBD!!!F129!DDR0_ECC(0)!!!!
S!M_G_ECC<1>!U2D1!AG68!@baseboard_fab2_lib.baseboard_fab2(sch_1):page57_i172@chpset_lib.skx_ext_b(chips)!SKX_EXT_B_BGA1-IC,TBD!!!F129!DDR0_ECC(1)!!!!
S!M_G_ECC<2>!U2D1!AD65!@baseboard_fab2_lib.baseboard_fab2(sch_1):page57_i172@chpset_lib.skx_ext_b(chips)!SKX_EXT_B_BGA1-IC,TBD!!!F129!DDR0_ECC(2)!!!!
S!M_G_ECC<3>!U2D1!AF65!@baseboard_fab2_lib.baseboard_fab2(sch_1):page57_i172@chpset_lib.skx_ext_b(chips)!SKX_EXT_B_BGA1-IC,TBD!!!F129!DDR0_ECC(3)!!!!
S!M_G_ECC<4>!U2D1!AD69!@baseboard_fab2_lib.baseboard_fab2(sch_1):page57_i172@chpset_lib.skx_ext_b(chips)!SKX_EXT_B_BGA1-IC,TBD!!!F129!DDR0_ECC(4)!!!!
S!M_G_ECC<5>!U2D1!AF69!@baseboard_fab2_lib.baseboard_fab2(sch_1):page57_i172@chpset_lib.skx_ext_b(chips)!SKX_EXT_B_BGA1-IC,TBD!!!F129!DDR0_ECC(5)!!!!
S!M_G_ECC<6>!U2D1!AC66!@baseboard_fab2_lib.baseboard_fab2(sch_1):page57_i172@chpset_lib.skx_ext_b(chips)!SKX_EXT_B_BGA1-IC,TBD!!!F129!DDR0_ECC(6)!!!!
S!M_G_ECC<7>!U2D1!AG66!@baseboard_fab2_lib.baseboard_fab2(sch_1):page57_i172@chpset_lib.skx_ext_b(chips)!SKX_EXT_B_BGA1-IC,TBD!!!F129!DDR0_ECC(7)!!!!
S!M_G_MA<0>!U2D1!F53!@baseboard_fab2_lib.baseboard_fab2(sch_1):page57_i172@chpset_lib.skx_ext_b(chips)!SKX_EXT_B_BGA1-IC,TBD!!!F129!DDR0_MA(0)!!!!
S!M_G_MA<10>!U2D1!J54!@baseboard_fab2_lib.baseboard_fab2(sch_1):page57_i172@chpset_lib.skx_ext_b(chips)!SKX_EXT_B_BGA1-IC,TBD!!!F129!DDR0_MA(10)!!!!
S!M_G_MA<11>!U2D1!G62!@baseboard_fab2_lib.baseboard_fab2(sch_1):page57_i172@chpset_lib.skx_ext_b(chips)!SKX_EXT_B_BGA1-IC,TBD!!!F129!DDR0_MA(11)!!!!
S!M_G_MA<12>!U2D1!J64!@baseboard_fab2_lib.baseboard_fab2(sch_1):page57_i172@chpset_lib.skx_ext_b(chips)!SKX_EXT_B_BGA1-IC,TBD!!!F129!DDR0_MA(12)!!!!
S!M_G_MA<13>!U2D1!J48!@baseboard_fab2_lib.baseboard_fab2(sch_1):page57_i172@chpset_lib.skx_ext_b(chips)!SKX_EXT_B_BGA1-IC,TBD!!!F129!DDR0_MA(13)!!!!
S!M_G_MA<14>!U2D1!F51!@baseboard_fab2_lib.baseboard_fab2(sch_1):page57_i172@chpset_lib.skx_ext_b(chips)!SKX_EXT_B_BGA1-IC,TBD!!!F129!DDR0_MA(14)!!!!
S!M_G_MA<15>!U2D1!K49!@baseboard_fab2_lib.baseboard_fab2(sch_1):page57_i172@chpset_lib.skx_ext_b(chips)!SKX_EXT_B_BGA1-IC,TBD!!!F129!DDR0_MA(15)!!!!
S!M_G_MA<16>!U2D1!D51!@baseboard_fab2_lib.baseboard_fab2(sch_1):page57_i172@chpset_lib.skx_ext_b(chips)!SKX_EXT_B_BGA1-IC,TBD!!!F129!DDR0_MA(16)!!!!
S!M_G_MA<17>!U2D1!K47!@baseboard_fab2_lib.baseboard_fab2(sch_1):page57_i172@chpset_lib.skx_ext_b(chips)!SKX_EXT_B_BGA1-IC,TBD!!!F129!DDR0_MA(17)!!!!
S!M_G_MA<1>!U2D1!F57!@baseboard_fab2_lib.baseboard_fab2(sch_1):page57_i172@chpset_lib.skx_ext_b(chips)!SKX_EXT_B_BGA1-IC,TBD!!!F129!DDR0_MA(1)!!!!
S!M_G_MA<2>!U2D1!D57!@baseboard_fab2_lib.baseboard_fab2(sch_1):page57_i172@chpset_lib.skx_ext_b(chips)!SKX_EXT_B_BGA1-IC,TBD!!!F129!DDR0_MA(2)!!!!
S!M_G_MA<3>!U2D1!C58!@baseboard_fab2_lib.baseboard_fab2(sch_1):page57_i172@chpset_lib.skx_ext_b(chips)!SKX_EXT_B_BGA1-IC,TBD!!!F129!DDR0_MA(3)!!!!
S!M_G_MA<4>!U2D1!G58!@baseboard_fab2_lib.baseboard_fab2(sch_1):page57_i172@chpset_lib.skx_ext_b(chips)!SKX_EXT_B_BGA1-IC,TBD!!!F129!DDR0_MA(4)!!!!
S!M_G_MA<5>!U2D1!F59!@baseboard_fab2_lib.baseboard_fab2(sch_1):page57_i172@chpset_lib.skx_ext_b(chips)!SKX_EXT_B_BGA1-IC,TBD!!!F129!DDR0_MA(5)!!!!
S!M_G_MA<6>!U2D1!D59!@baseboard_fab2_lib.baseboard_fab2(sch_1):page57_i172@chpset_lib.skx_ext_b(chips)!SKX_EXT_B_BGA1-IC,TBD!!!F129!DDR0_MA(6)!!!!
S!M_G_MA<7>!U2D1!G60!@baseboard_fab2_lib.baseboard_fab2(sch_1):page57_i172@chpset_lib.skx_ext_b(chips)!SKX_EXT_B_BGA1-IC,TBD!!!F129!DDR0_MA(7)!!!!
S!M_G_MA<8>!U2D1!C60!@baseboard_fab2_lib.baseboard_fab2(sch_1):page57_i172@chpset_lib.skx_ext_b(chips)!SKX_EXT_B_BGA1-IC,TBD!!!F129!DDR0_MA(8)!!!!
S!M_G_MA<9>!U2D1!F61!@baseboard_fab2_lib.baseboard_fab2(sch_1):page57_i172@chpset_lib.skx_ext_b(chips)!SKX_EXT_B_BGA1-IC,TBD!!!F129!DDR0_MA(9)!!!!
S!M_G_ODT<0>!U2D1!C50!@baseboard_fab2_lib.baseboard_fab2(sch_1):page57_i172@chpset_lib.skx_ext_b(chips)!SKX_EXT_B_BGA1-IC,TBD!!!F129!DDR0_ODT(0)!!!!
S!M_G_ODT<1>!U2D1!C48!@baseboard_fab2_lib.baseboard_fab2(sch_1):page57_i172@chpset_lib.skx_ext_b(chips)!SKX_EXT_B_BGA1-IC,TBD!!!F129!DDR0_ODT(1)!!!!
S!M_G_ODT<2>!U2D1!G50!@baseboard_fab2_lib.baseboard_fab2(sch_1):page57_i172@chpset_lib.skx_ext_b(chips)!SKX_EXT_B_BGA1-IC,TBD!!!F129!DDR0_ODT(2)!!!!
S!M_G_ODT<3>!U2D1!G48!@baseboard_fab2_lib.baseboard_fab2(sch_1):page57_i172@chpset_lib.skx_ext_b(chips)!SKX_EXT_B_BGA1-IC,TBD!!!F129!DDR0_ODT(3)!!!!
S!M_G_PAR!U2D1!D53!@baseboard_fab2_lib.baseboard_fab2(sch_1):page57_i172@chpset_lib.skx_ext_b(chips)!SKX_EXT_B_BGA1-IC,TBD!!!F129!DDR0_PAR!!!!
S!M_H_ACT_N!U2D1!T63!@baseboard_fab2_lib.baseboard_fab2(sch_1):page58_i172@chpset_lib.skx_ext_b(chips)!SKX_EXT_B_BGA1-IC,TBD!!!F128!DDR1_ACT_N!!!!
S!M_H_ALERT_N!U2D1!W62!@baseboard_fab2_lib.baseboard_fab2(sch_1):page58_i172@chpset_lib.skx_ext_b(chips)!SKX_EXT_B_BGA1-IC,TBD!!!F128!DDR1_ALERT_N!!!!
S!M_H_BA<0>!U2D1!T53!@baseboard_fab2_lib.baseboard_fab2(sch_1):page58_i172@chpset_lib.skx_ext_b(chips)!SKX_EXT_B_BGA1-IC,TBD!!!F128!DDR1_BA(0)!!!!
S!M_H_BA<1>!U2D1!K55!@baseboard_fab2_lib.baseboard_fab2(sch_1):page58_i172@chpset_lib.skx_ext_b(chips)!SKX_EXT_B_BGA1-IC,TBD!!!F128!DDR1_BA(1)!!!!
S!M_H_BG<0>!U2D1!M61!@baseboard_fab2_lib.baseboard_fab2(sch_1):page58_i172@chpset_lib.skx_ext_b(chips)!SKX_EXT_B_BGA1-IC,TBD!!!F128!DDR1_BG(0)!!!!
S!M_H_BG<1>!U2D1!N60!@baseboard_fab2_lib.baseboard_fab2(sch_1):page58_i172@chpset_lib.skx_ext_b(chips)!SKX_EXT_B_BGA1-IC,TBD!!!F128!DDR1_BG(1)!!!!
S!M_H_C<2>!U2D1!M47!@baseboard_fab2_lib.baseboard_fab2(sch_1):page58_i172@chpset_lib.skx_ext_b(chips)!SKX_EXT_B_BGA1-IC,TBD!!!F128!DDR1_CID(2)!!!!
S!M_H_CKE<0>!U2D1!N62!@baseboard_fab2_lib.baseboard_fab2(sch_1):page58_i172@chpset_lib.skx_ext_b(chips)!SKX_EXT_B_BGA1-IC,TBD!!!F128!DDR1_CKE(0)!!!!
S!M_H_CKE<1>!U2D1!R64!@baseboard_fab2_lib.baseboard_fab2(sch_1):page58_i172@chpset_lib.skx_ext_b(chips)!SKX_EXT_B_BGA1-IC,TBD!!!F128!DDR1_CKE(1)!!!!
S!M_H_CKE<2>!U2D1!K63!@baseboard_fab2_lib.baseboard_fab2(sch_1):page58_i172@chpset_lib.skx_ext_b(chips)!SKX_EXT_B_BGA1-IC,TBD!!!F128!DDR1_CKE(2)!!!!
S!M_H_CKE<3>!U2D1!L64!@baseboard_fab2_lib.baseboard_fab2(sch_1):page58_i172@chpset_lib.skx_ext_b(chips)!SKX_EXT_B_BGA1-IC,TBD!!!F128!DDR1_CKE(3)!!!!
S!M_H_CLK_DN<0>!U2D1!M53!@baseboard_fab2_lib.baseboard_fab2(sch_1):page58_i172@chpset_lib.skx_ext_b(chips)!SKX_EXT_B_BGA1-IC,TBD!!!F128!DDR1_CLK_DN(0)!!!!
S!M_H_CLK_DN<2>!U2D1!N56!@baseboard_fab2_lib.baseboard_fab2(sch_1):page58_i172@chpset_lib.skx_ext_b(chips)!SKX_EXT_B_BGA1-IC,TBD!!!F128!DDR1_CLK_DN(2)!!!!
S!M_H_CLK_DN<1>!U2D1!R54!@baseboard_fab2_lib.baseboard_fab2(sch_1):page58_i172@chpset_lib.skx_ext_b(chips)!SKX_EXT_B_BGA1-IC,TBD!!!F128!DDR1_CLK_DN(1)!!!!
S!M_H_CLK_DN<3>!U2D1!R56!@baseboard_fab2_lib.baseboard_fab2(sch_1):page58_i172@chpset_lib.skx_ext_b(chips)!SKX_EXT_B_BGA1-IC,TBD!!!F128!DDR1_CLK_DN(3)!!!!
S!M_H_CLK_DP<0>!U2D1!N54!@baseboard_fab2_lib.baseboard_fab2(sch_1):page58_i172@chpset_lib.skx_ext_b(chips)!SKX_EXT_B_BGA1-IC,TBD!!!F128!DDR1_CLK_DP(0)!!!!
S!M_H_CLK_DP<2>!U2D1!M57!@baseboard_fab2_lib.baseboard_fab2(sch_1):page58_i172@chpset_lib.skx_ext_b(chips)!SKX_EXT_B_BGA1-IC,TBD!!!F128!DDR1_CLK_DP(2)!!!!
S!M_H_CLK_DP<1>!U2D1!T55!@baseboard_fab2_lib.baseboard_fab2(sch_1):page58_i172@chpset_lib.skx_ext_b(chips)!SKX_EXT_B_BGA1-IC,TBD!!!F128!DDR1_CLK_DP(1)!!!!
S!M_H_CLK_DP<3>!U2D1!T57!@baseboard_fab2_lib.baseboard_fab2(sch_1):page58_i172@chpset_lib.skx_ext_b(chips)!SKX_EXT_B_BGA1-IC,TBD!!!F128!DDR1_CLK_DP(3)!!!!
S!M_H_CS_N<0>!U2D1!K51!@baseboard_fab2_lib.baseboard_fab2(sch_1):page58_i172@chpset_lib.skx_ext_b(chips)!SKX_EXT_B_BGA1-IC,TBD!!!F128!DDR1_CS_N(0)!!!!
S!M_H_CS_N<1>!U2D1!R50!@baseboard_fab2_lib.baseboard_fab2(sch_1):page58_i172@chpset_lib.skx_ext_b(chips)!SKX_EXT_B_BGA1-IC,TBD!!!F128!DDR1_CS_N(1)!!!!
S!M_H_CS_N<2>!U2D1!N46!@baseboard_fab2_lib.baseboard_fab2(sch_1):page58_i172@chpset_lib.skx_ext_b(chips)!SKX_EXT_B_BGA1-IC,TBD!!!F128!DDR1_CS_N(2)!!!!
S!M_H_CS_N<3>!U2D1!V47!@baseboard_fab2_lib.baseboard_fab2(sch_1):page58_i172@chpset_lib.skx_ext_b(chips)!SKX_EXT_B_BGA1-IC,TBD!!!F128!DDR1_CS_N(3)!!!!
S!M_H_CS_N<4>!U2D1!J50!@baseboard_fab2_lib.baseboard_fab2(sch_1):page58_i172@chpset_lib.skx_ext_b(chips)!SKX_EXT_B_BGA1-IC,TBD!!!F128!DDR1_CS_N(4)!!!!
S!M_H_CS_N<5>!U2D1!T49!@baseboard_fab2_lib.baseboard_fab2(sch_1):page58_i172@chpset_lib.skx_ext_b(chips)!SKX_EXT_B_BGA1-IC,TBD!!!F128!DDR1_CS_N(5)!!!!
S!M_H_CS_N<6>!U2D1!M45!@baseboard_fab2_lib.baseboard_fab2(sch_1):page58_i172@chpset_lib.skx_ext_b(chips)!SKX_EXT_B_BGA1-IC,TBD!!!F128!DDR1_CS_N(6)!!!!
S!M_H_CS_N<7>!U2D1!R46!@baseboard_fab2_lib.baseboard_fab2(sch_1):page58_i172@chpset_lib.skx_ext_b(chips)!SKX_EXT_B_BGA1-IC,TBD!!!F128!DDR1_CS_N(7)!!!!
S!M_H_DQ<0>!U2D1!AV81!@baseboard_fab2_lib.baseboard_fab2(sch_1):page58_i172@chpset_lib.skx_ext_b(chips)!SKX_EXT_B_BGA1-IC,TBD!!!F128!DDR1_DQ(0)!!!!
S!M_H_DQ<10>!U2D1!AC82!@baseboard_fab2_lib.baseboard_fab2(sch_1):page58_i172@chpset_lib.skx_ext_b(chips)!SKX_EXT_B_BGA1-IC,TBD!!!F128!DDR1_DQ(10)!!!!
S!M_H_DQ<11>!U2D1!AB81!@baseboard_fab2_lib.baseboard_fab2(sch_1):page58_i172@chpset_lib.skx_ext_b(chips)!SKX_EXT_B_BGA1-IC,TBD!!!F128!DDR1_DQ(11)!!!!
S!M_H_DQ<12>!U2D1!AJ80!@baseboard_fab2_lib.baseboard_fab2(sch_1):page58_i172@chpset_lib.skx_ext_b(chips)!SKX_EXT_B_BGA1-IC,TBD!!!F128!DDR1_DQ(12)!!!!
S!M_H_DQ<13>!U2D1!AH79!@baseboard_fab2_lib.baseboard_fab2(sch_1):page58_i172@chpset_lib.skx_ext_b(chips)!SKX_EXT_B_BGA1-IC,TBD!!!F128!DDR1_DQ(13)!!!!
S!M_H_DQ<14>!U2D1!AE82!@baseboard_fab2_lib.baseboard_fab2(sch_1):page58_i172@chpset_lib.skx_ext_b(chips)!SKX_EXT_B_BGA1-IC,TBD!!!F128!DDR1_DQ(14)!!!!
S!M_H_DQ<15>!U2D1!AC80!@baseboard_fab2_lib.baseboard_fab2(sch_1):page58_i172@chpset_lib.skx_ext_b(chips)!SKX_EXT_B_BGA1-IC,TBD!!!F128!DDR1_DQ(15)!!!!
S!M_H_DQ<16>!U2D1!E80!@baseboard_fab2_lib.baseboard_fab2(sch_1):page58_i172@chpset_lib.skx_ext_b(chips)!SKX_EXT_B_BGA1-IC,TBD!!!F128!DDR1_DQ(16)!!!!
S!M_H_DQ<17>!U2D1!J80!@baseboard_fab2_lib.baseboard_fab2(sch_1):page58_i172@chpset_lib.skx_ext_b(chips)!SKX_EXT_B_BGA1-IC,TBD!!!F128!DDR1_DQ(17)!!!!
S!M_H_DQ<18>!U2D1!F77!@baseboard_fab2_lib.baseboard_fab2(sch_1):page58_i172@chpset_lib.skx_ext_b(chips)!SKX_EXT_B_BGA1-IC,TBD!!!F128!DDR1_DQ(18)!!!!
S!M_H_DQ<19>!U2D1!H77!@baseboard_fab2_lib.baseboard_fab2(sch_1):page58_i172@chpset_lib.skx_ext_b(chips)!SKX_EXT_B_BGA1-IC,TBD!!!F128!DDR1_DQ(19)!!!!
S!M_H_DQ<1>!U2D1!AT79!@baseboard_fab2_lib.baseboard_fab2(sch_1):page58_i172@chpset_lib.skx_ext_b(chips)!SKX_EXT_B_BGA1-IC,TBD!!!F128!DDR1_DQ(1)!!!!
S!M_H_DQ<20>!U2D1!F81!@baseboard_fab2_lib.baseboard_fab2(sch_1):page58_i172@chpset_lib.skx_ext_b(chips)!SKX_EXT_B_BGA1-IC,TBD!!!F128!DDR1_DQ(20)!!!!
S!M_H_DQ<21>!U2D1!H81!@baseboard_fab2_lib.baseboard_fab2(sch_1):page58_i172@chpset_lib.skx_ext_b(chips)!SKX_EXT_B_BGA1-IC,TBD!!!F128!DDR1_DQ(21)!!!!
S!M_H_DQ<22>!U2D1!E78!@baseboard_fab2_lib.baseboard_fab2(sch_1):page58_i172@chpset_lib.skx_ext_b(chips)!SKX_EXT_B_BGA1-IC,TBD!!!F128!DDR1_DQ(22)!!!!
S!M_H_DQ<23>!U2D1!J78!@baseboard_fab2_lib.baseboard_fab2(sch_1):page58_i172@chpset_lib.skx_ext_b(chips)!SKX_EXT_B_BGA1-IC,TBD!!!F128!DDR1_DQ(23)!!!!
S!M_H_DQ<24>!U2D1!D75!@baseboard_fab2_lib.baseboard_fab2(sch_1):page58_i172@chpset_lib.skx_ext_b(chips)!SKX_EXT_B_BGA1-IC,TBD!!!F128!DDR1_DQ(24)!!!!
S!M_H_DQ<25>!U2D1!C74!@baseboard_fab2_lib.baseboard_fab2(sch_1):page58_i172@chpset_lib.skx_ext_b(chips)!SKX_EXT_B_BGA1-IC,TBD!!!F128!DDR1_DQ(25)!!!!
S!M_H_DQ<26>!U2D1!D71!@baseboard_fab2_lib.baseboard_fab2(sch_1):page58_i172@chpset_lib.skx_ext_b(chips)!SKX_EXT_B_BGA1-IC,TBD!!!F128!DDR1_DQ(26)!!!!
S!M_H_DQ<27>!U2D1!F71!@baseboard_fab2_lib.baseboard_fab2(sch_1):page58_i172@chpset_lib.skx_ext_b(chips)!SKX_EXT_B_BGA1-IC,TBD!!!F128!DDR1_DQ(27)!!!!
S!M_H_DQ<28>!U2D1!F75!@baseboard_fab2_lib.baseboard_fab2(sch_1):page58_i172@chpset_lib.skx_ext_b(chips)!SKX_EXT_B_BGA1-IC,TBD!!!F128!DDR1_DQ(28)!!!!
S!M_H_DQ<29>!U2D1!G74!@baseboard_fab2_lib.baseboard_fab2(sch_1):page58_i172@chpset_lib.skx_ext_b(chips)!SKX_EXT_B_BGA1-IC,TBD!!!F128!DDR1_DQ(29)!!!!
S!M_H_DQ<2>!U2D1!AN82!@baseboard_fab2_lib.baseboard_fab2(sch_1):page58_i172@chpset_lib.skx_ext_b(chips)!SKX_EXT_B_BGA1-IC,TBD!!!F128!DDR1_DQ(2)!!!!
S!M_H_DQ<30>!U2D1!C72!@baseboard_fab2_lib.baseboard_fab2(sch_1):page58_i172@chpset_lib.skx_ext_b(chips)!SKX_EXT_B_BGA1-IC,TBD!!!F128!DDR1_DQ(30)!!!!
S!M_H_DQ<31>!U2D1!G72!@baseboard_fab2_lib.baseboard_fab2(sch_1):page58_i172@chpset_lib.skx_ext_b(chips)!SKX_EXT_B_BGA1-IC,TBD!!!F128!DDR1_DQ(31)!!!!
S!M_H_DQ<32>!U2D1!K43!@baseboard_fab2_lib.baseboard_fab2(sch_1):page58_i172@chpset_lib.skx_ext_b(chips)!SKX_EXT_B_BGA1-IC,TBD!!!F128!DDR1_DQ(32)!!!!
S!M_H_DQ<33>!U2D1!H43!@baseboard_fab2_lib.baseboard_fab2(sch_1):page58_i172@chpset_lib.skx_ext_b(chips)!SKX_EXT_B_BGA1-IC,TBD!!!F128!DDR1_DQ(33)!!!!
S!M_H_DQ<34>!U2D1!L40!@baseboard_fab2_lib.baseboard_fab2(sch_1):page58_i172@chpset_lib.skx_ext_b(chips)!SKX_EXT_B_BGA1-IC,TBD!!!F128!DDR1_DQ(34)!!!!
S!M_H_DQ<35>!U2D1!N40!@baseboard_fab2_lib.baseboard_fab2(sch_1):page58_i172@chpset_lib.skx_ext_b(chips)!SKX_EXT_B_BGA1-IC,TBD!!!F128!DDR1_DQ(35)!!!!
S!M_H_DQ<36>!U2D1!P43!@baseboard_fab2_lib.baseboard_fab2(sch_1):page58_i172@chpset_lib.skx_ext_b(chips)!SKX_EXT_B_BGA1-IC,TBD!!!F128!DDR1_DQ(36)!!!!
S!M_H_DQ<37>!U2D1!T43!@baseboard_fab2_lib.baseboard_fab2(sch_1):page58_i172@chpset_lib.skx_ext_b(chips)!SKX_EXT_B_BGA1-IC,TBD!!!F128!DDR1_DQ(37)!!!!
S!M_H_DQ<38>!U2D1!K41!@baseboard_fab2_lib.baseboard_fab2(sch_1):page58_i172@chpset_lib.skx_ext_b(chips)!SKX_EXT_B_BGA1-IC,TBD!!!F128!DDR1_DQ(38)!!!!
S!M_H_DQ<39>!U2D1!P41!@baseboard_fab2_lib.baseboard_fab2(sch_1):page58_i172@chpset_lib.skx_ext_b(chips)!SKX_EXT_B_BGA1-IC,TBD!!!F128!DDR1_DQ(39)!!!!
S!M_H_DQ<3>!U2D1!AM81!@baseboard_fab2_lib.baseboard_fab2(sch_1):page58_i172@chpset_lib.skx_ext_b(chips)!SKX_EXT_B_BGA1-IC,TBD!!!F128!DDR1_DQ(3)!!!!
S!M_H_DQ<40>!U2D1!C36!@baseboard_fab2_lib.baseboard_fab2(sch_1):page58_i172@chpset_lib.skx_ext_b(chips)!SKX_EXT_B_BGA1-IC,TBD!!!F128!DDR1_DQ(40)!!!!
S!M_H_DQ<41>!U2D1!B35!@baseboard_fab2_lib.baseboard_fab2(sch_1):page58_i172@chpset_lib.skx_ext_b(chips)!SKX_EXT_B_BGA1-IC,TBD!!!F128!DDR1_DQ(41)!!!!
S!M_H_DQ<42>!U2D1!C32!@baseboard_fab2_lib.baseboard_fab2(sch_1):page58_i172@chpset_lib.skx_ext_b(chips)!SKX_EXT_B_BGA1-IC,TBD!!!F128!DDR1_DQ(42)!!!!
S!M_H_DQ<43>!U2D1!E32!@baseboard_fab2_lib.baseboard_fab2(sch_1):page58_i172@chpset_lib.skx_ext_b(chips)!SKX_EXT_B_BGA1-IC,TBD!!!F128!DDR1_DQ(43)!!!!
S!M_H_DQ<44>!U2D1!E36!@baseboard_fab2_lib.baseboard_fab2(sch_1):page58_i172@chpset_lib.skx_ext_b(chips)!SKX_EXT_B_BGA1-IC,TBD!!!F128!DDR1_DQ(44)!!!!
S!M_H_DQ<45>!U2D1!F35!@baseboard_fab2_lib.baseboard_fab2(sch_1):page58_i172@chpset_lib.skx_ext_b(chips)!SKX_EXT_B_BGA1-IC,TBD!!!F128!DDR1_DQ(45)!!!!
S!M_H_DQ<46>!U2D1!B33!@baseboard_fab2_lib.baseboard_fab2(sch_1):page58_i172@chpset_lib.skx_ext_b(chips)!SKX_EXT_B_BGA1-IC,TBD!!!F128!DDR1_DQ(46)!!!!
S!M_H_DQ<47>!U2D1!F33!@baseboard_fab2_lib.baseboard_fab2(sch_1):page58_i172@chpset_lib.skx_ext_b(chips)!SKX_EXT_B_BGA1-IC,TBD!!!F128!DDR1_DQ(47)!!!!
S!M_H_DQ<48>!U2D1!C30!@baseboard_fab2_lib.baseboard_fab2(sch_1):page58_i172@chpset_lib.skx_ext_b(chips)!SKX_EXT_B_BGA1-IC,TBD!!!F128!DDR1_DQ(48)!!!!
S!M_H_DQ<49>!U2D1!B29!@baseboard_fab2_lib.baseboard_fab2(sch_1):page58_i172@chpset_lib.skx_ext_b(chips)!SKX_EXT_B_BGA1-IC,TBD!!!F128!DDR1_DQ(49)!!!!
S!M_H_DQ<4>!U2D1!AW80!@baseboard_fab2_lib.baseboard_fab2(sch_1):page58_i172@chpset_lib.skx_ext_b(chips)!SKX_EXT_B_BGA1-IC,TBD!!!F128!DDR1_DQ(4)!!!!
S!M_H_DQ<50>!U2D1!C26!@baseboard_fab2_lib.baseboard_fab2(sch_1):page58_i172@chpset_lib.skx_ext_b(chips)!SKX_EXT_B_BGA1-IC,TBD!!!F128!DDR1_DQ(50)!!!!
S!M_H_DQ<51>!U2D1!E26!@baseboard_fab2_lib.baseboard_fab2(sch_1):page58_i172@chpset_lib.skx_ext_b(chips)!SKX_EXT_B_BGA1-IC,TBD!!!F128!DDR1_DQ(51)!!!!
S!M_H_DQ<52>!U2D1!E30!@baseboard_fab2_lib.baseboard_fab2(sch_1):page58_i172@chpset_lib.skx_ext_b(chips)!SKX_EXT_B_BGA1-IC,TBD!!!F128!DDR1_DQ(52)!!!!
S!M_H_DQ<53>!U2D1!F29!@baseboard_fab2_lib.baseboard_fab2(sch_1):page58_i172@chpset_lib.skx_ext_b(chips)!SKX_EXT_B_BGA1-IC,TBD!!!F128!DDR1_DQ(53)!!!!
S!M_H_DQ<54>!U2D1!B27!@baseboard_fab2_lib.baseboard_fab2(sch_1):page58_i172@chpset_lib.skx_ext_b(chips)!SKX_EXT_B_BGA1-IC,TBD!!!F128!DDR1_DQ(54)!!!!
S!M_H_DQ<55>!U2D1!F27!@baseboard_fab2_lib.baseboard_fab2(sch_1):page58_i172@chpset_lib.skx_ext_b(chips)!SKX_EXT_B_BGA1-IC,TBD!!!F128!DDR1_DQ(55)!!!!
S!M_H_DQ<56>!U2D1!U28!@baseboard_fab2_lib.baseboard_fab2(sch_1):page58_i172@chpset_lib.skx_ext_b(chips)!SKX_EXT_B_BGA1-IC,TBD!!!F128!DDR1_DQ(56)!!!!
S!M_H_DQ<57>!U2D1!AA28!@baseboard_fab2_lib.baseboard_fab2(sch_1):page58_i172@chpset_lib.skx_ext_b(chips)!SKX_EXT_B_BGA1-IC,TBD!!!F128!DDR1_DQ(57)!!!!
S!M_H_DQ<58>!U2D1!V25!@baseboard_fab2_lib.baseboard_fab2(sch_1):page58_i172@chpset_lib.skx_ext_b(chips)!SKX_EXT_B_BGA1-IC,TBD!!!F128!DDR1_DQ(58)!!!!
S!M_H_DQ<59>!U2D1!Y25!@baseboard_fab2_lib.baseboard_fab2(sch_1):page58_i172@chpset_lib.skx_ext_b(chips)!SKX_EXT_B_BGA1-IC,TBD!!!F128!DDR1_DQ(59)!!!!
S!M_H_DQ<5>!U2D1!AV79!@baseboard_fab2_lib.baseboard_fab2(sch_1):page58_i172@chpset_lib.skx_ext_b(chips)!SKX_EXT_B_BGA1-IC,TBD!!!F128!DDR1_DQ(5)!!!!
S!M_H_DQ<60>!U2D1!V29!@baseboard_fab2_lib.baseboard_fab2(sch_1):page58_i172@chpset_lib.skx_ext_b(chips)!SKX_EXT_B_BGA1-IC,TBD!!!F128!DDR1_DQ(60)!!!!
S!M_H_DQ<61>!U2D1!Y29!@baseboard_fab2_lib.baseboard_fab2(sch_1):page58_i172@chpset_lib.skx_ext_b(chips)!SKX_EXT_B_BGA1-IC,TBD!!!F128!DDR1_DQ(61)!!!!
S!M_H_DQ<62>!U2D1!U26!@baseboard_fab2_lib.baseboard_fab2(sch_1):page58_i172@chpset_lib.skx_ext_b(chips)!SKX_EXT_B_BGA1-IC,TBD!!!F128!DDR1_DQ(62)!!!!
S!M_H_DQ<63>!U2D1!AA26!@baseboard_fab2_lib.baseboard_fab2(sch_1):page58_i172@chpset_lib.skx_ext_b(chips)!SKX_EXT_B_BGA1-IC,TBD!!!F128!DDR1_DQ(63)!!!!
S!M_H_DQ<6>!U2D1!AR82!@baseboard_fab2_lib.baseboard_fab2(sch_1):page58_i172@chpset_lib.skx_ext_b(chips)!SKX_EXT_B_BGA1-IC,TBD!!!F128!DDR1_DQ(6)!!!!
S!M_H_DQ<7>!U2D1!AN80!@baseboard_fab2_lib.baseboard_fab2(sch_1):page58_i172@chpset_lib.skx_ext_b(chips)!SKX_EXT_B_BGA1-IC,TBD!!!F128!DDR1_DQ(7)!!!!
S!M_H_DQ<8>!U2D1!AH81!@baseboard_fab2_lib.baseboard_fab2(sch_1):page58_i172@chpset_lib.skx_ext_b(chips)!SKX_EXT_B_BGA1-IC,TBD!!!F128!DDR1_DQ(8)!!!!
S!M_H_DQ<9>!U2D1!AF79!@baseboard_fab2_lib.baseboard_fab2(sch_1):page58_i172@chpset_lib.skx_ext_b(chips)!SKX_EXT_B_BGA1-IC,TBD!!!F128!DDR1_DQ(9)!!!!
S!M_H_DQS_DN<0>!U2D1!AP79!@baseboard_fab2_lib.baseboard_fab2(sch_1):page58_i172@chpset_lib.skx_ext_b(chips)!SKX_EXT_B_BGA1-IC,TBD!!!F128!DDR1_DQS_DN(0)!!!!
S!M_H_DQS_DN<10>!U2D1!AG82!@baseboard_fab2_lib.baseboard_fab2(sch_1):page58_i172@chpset_lib.skx_ext_b(chips)!SKX_EXT_B_BGA1-IC,TBD!!!F128!DDR1_DQS_DN(10)!!!!
S!M_H_DQS_DN<11>!U2D1!D79!@baseboard_fab2_lib.baseboard_fab2(sch_1):page58_i172@chpset_lib.skx_ext_b(chips)!SKX_EXT_B_BGA1-IC,TBD!!!F128!DDR1_DQS_DN(11)!!!!
S!M_H_DQS_DN<12>!U2D1!B73!@baseboard_fab2_lib.baseboard_fab2(sch_1):page58_i172@chpset_lib.skx_ext_b(chips)!SKX_EXT_B_BGA1-IC,TBD!!!F128!DDR1_DQS_DN(12)!!!!
S!M_H_DQS_DN<13>!U2D1!J42!@baseboard_fab2_lib.baseboard_fab2(sch_1):page58_i172@chpset_lib.skx_ext_b(chips)!SKX_EXT_B_BGA1-IC,TBD!!!F128!DDR1_DQS_DN(13)!!!!
S!M_H_DQS_DN<14>!U2D1!A34!@baseboard_fab2_lib.baseboard_fab2(sch_1):page58_i172@chpset_lib.skx_ext_b(chips)!SKX_EXT_B_BGA1-IC,TBD!!!F128!DDR1_DQS_DN(14)!!!!
S!M_H_DQS_DN<15>!U2D1!A28!@baseboard_fab2_lib.baseboard_fab2(sch_1):page58_i172@chpset_lib.skx_ext_b(chips)!SKX_EXT_B_BGA1-IC,TBD!!!F128!DDR1_DQS_DN(15)!!!!
S!M_H_DQS_DN<16>!U2D1!T27!@baseboard_fab2_lib.baseboard_fab2(sch_1):page58_i172@chpset_lib.skx_ext_b(chips)!SKX_EXT_B_BGA1-IC,TBD!!!F128!DDR1_DQS_DN(16)!!!!
S!M_H_DQS_DN<17>!U2D1!G68!@baseboard_fab2_lib.baseboard_fab2(sch_1):page58_i172@chpset_lib.skx_ext_b(chips)!SKX_EXT_B_BGA1-IC,TBD!!!F128!DDR1_DQS_DN(17)!!!!
S!M_H_DQS_DN<1>!U2D1!AD79!@baseboard_fab2_lib.baseboard_fab2(sch_1):page58_i172@chpset_lib.skx_ext_b(chips)!SKX_EXT_B_BGA1-IC,TBD!!!F128!DDR1_DQS_DN(1)!!!!
S!M_H_DQS_DN<2>!U2D1!K79!@baseboard_fab2_lib.baseboard_fab2(sch_1):page58_i172@chpset_lib.skx_ext_b(chips)!SKX_EXT_B_BGA1-IC,TBD!!!F128!DDR1_DQS_DN(2)!!!!
S!M_H_DQS_DN<3>!U2D1!H73!@baseboard_fab2_lib.baseboard_fab2(sch_1):page58_i172@chpset_lib.skx_ext_b(chips)!SKX_EXT_B_BGA1-IC,TBD!!!F128!DDR1_DQS_DN(3)!!!!
S!M_H_DQS_DN<4>!U2D1!N42!@baseboard_fab2_lib.baseboard_fab2(sch_1):page58_i172@chpset_lib.skx_ext_b(chips)!SKX_EXT_B_BGA1-IC,TBD!!!F128!DDR1_DQS_DN(4)!!!!
S!M_H_DQS_DN<5>!U2D1!G34!@baseboard_fab2_lib.baseboard_fab2(sch_1):page58_i172@chpset_lib.skx_ext_b(chips)!SKX_EXT_B_BGA1-IC,TBD!!!F128!DDR1_DQS_DN(5)!!!!
S!M_H_DQS_DN<6>!U2D1!G28!@baseboard_fab2_lib.baseboard_fab2(sch_1):page58_i172@chpset_lib.skx_ext_b(chips)!SKX_EXT_B_BGA1-IC,TBD!!!F128!DDR1_DQS_DN(6)!!!!
S!M_H_DQS_DN<7>!U2D1!AB27!@baseboard_fab2_lib.baseboard_fab2(sch_1):page58_i172@chpset_lib.skx_ext_b(chips)!SKX_EXT_B_BGA1-IC,TBD!!!F128!DDR1_DQS_DN(7)!!!!
S!M_H_DQS_DN<8>!U2D1!N68!@baseboard_fab2_lib.baseboard_fab2(sch_1):page58_i172@chpset_lib.skx_ext_b(chips)!SKX_EXT_B_BGA1-IC,TBD!!!F128!DDR1_DQS_DN(8)!!!!
S!M_H_DQS_DN<9>!U2D1!AU82!@baseboard_fab2_lib.baseboard_fab2(sch_1):page58_i172@chpset_lib.skx_ext_b(chips)!SKX_EXT_B_BGA1-IC,TBD!!!F128!DDR1_DQS_DN(9)!!!!
S!M_H_DQS_DP<0>!U2D1!AR80!@baseboard_fab2_lib.baseboard_fab2(sch_1):page58_i172@chpset_lib.skx_ext_b(chips)!SKX_EXT_B_BGA1-IC,TBD!!!F128!DDR1_DQS_DP(0)!!!!
S!M_H_DQS_DP<10>!U2D1!AF81!@baseboard_fab2_lib.baseboard_fab2(sch_1):page58_i172@chpset_lib.skx_ext_b(chips)!SKX_EXT_B_BGA1-IC,TBD!!!F128!DDR1_DQS_DP(10)!!!!
S!M_H_DQS_DP<11>!U2D1!F79!@baseboard_fab2_lib.baseboard_fab2(sch_1):page58_i172@chpset_lib.skx_ext_b(chips)!SKX_EXT_B_BGA1-IC,TBD!!!F128!DDR1_DQS_DP(11)!!!!
S!M_H_DQS_DP<12>!U2D1!D73!@baseboard_fab2_lib.baseboard_fab2(sch_1):page58_i172@chpset_lib.skx_ext_b(chips)!SKX_EXT_B_BGA1-IC,TBD!!!F128!DDR1_DQS_DP(12)!!!!
S!M_H_DQS_DP<13>!U2D1!L42!@baseboard_fab2_lib.baseboard_fab2(sch_1):page58_i172@chpset_lib.skx_ext_b(chips)!SKX_EXT_B_BGA1-IC,TBD!!!F128!DDR1_DQS_DP(13)!!!!
S!M_H_DQS_DP<14>!U2D1!C34!@baseboard_fab2_lib.baseboard_fab2(sch_1):page58_i172@chpset_lib.skx_ext_b(chips)!SKX_EXT_B_BGA1-IC,TBD!!!F128!DDR1_DQS_DP(14)!!!!
S!M_H_DQS_DP<15>!U2D1!C28!@baseboard_fab2_lib.baseboard_fab2(sch_1):page58_i172@chpset_lib.skx_ext_b(chips)!SKX_EXT_B_BGA1-IC,TBD!!!F128!DDR1_DQS_DP(15)!!!!
S!M_H_DQS_DP<16>!U2D1!V27!@baseboard_fab2_lib.baseboard_fab2(sch_1):page58_i172@chpset_lib.skx_ext_b(chips)!SKX_EXT_B_BGA1-IC,TBD!!!F128!DDR1_DQS_DP(16)!!!!
S!M_H_DQS_DP<17>!U2D1!J68!@baseboard_fab2_lib.baseboard_fab2(sch_1):page58_i172@chpset_lib.skx_ext_b(chips)!SKX_EXT_B_BGA1-IC,TBD!!!F128!DDR1_DQS_DP(17)!!!!
S!M_H_DQS_DP<1>!U2D1!AE80!@baseboard_fab2_lib.baseboard_fab2(sch_1):page58_i172@chpset_lib.skx_ext_b(chips)!SKX_EXT_B_BGA1-IC,TBD!!!F128!DDR1_DQS_DP(1)!!!!
S!M_H_DQS_DP<2>!U2D1!H79!@baseboard_fab2_lib.baseboard_fab2(sch_1):page58_i172@chpset_lib.skx_ext_b(chips)!SKX_EXT_B_BGA1-IC,TBD!!!F128!DDR1_DQS_DP(2)!!!!
S!M_H_DQS_DP<3>!U2D1!F73!@baseboard_fab2_lib.baseboard_fab2(sch_1):page58_i172@chpset_lib.skx_ext_b(chips)!SKX_EXT_B_BGA1-IC,TBD!!!F128!DDR1_DQS_DP(3)!!!!
S!M_H_DQS_DP<4>!U2D1!R42!@baseboard_fab2_lib.baseboard_fab2(sch_1):page58_i172@chpset_lib.skx_ext_b(chips)!SKX_EXT_B_BGA1-IC,TBD!!!F128!DDR1_DQS_DP(4)!!!!
S!M_H_DQS_DP<5>!U2D1!E34!@baseboard_fab2_lib.baseboard_fab2(sch_1):page58_i172@chpset_lib.skx_ext_b(chips)!SKX_EXT_B_BGA1-IC,TBD!!!F128!DDR1_DQS_DP(5)!!!!
S!M_H_DQS_DP<6>!U2D1!E28!@baseboard_fab2_lib.baseboard_fab2(sch_1):page58_i172@chpset_lib.skx_ext_b(chips)!SKX_EXT_B_BGA1-IC,TBD!!!F128!DDR1_DQS_DP(6)!!!!
S!M_H_DQS_DP<7>!U2D1!Y27!@baseboard_fab2_lib.baseboard_fab2(sch_1):page58_i172@chpset_lib.skx_ext_b(chips)!SKX_EXT_B_BGA1-IC,TBD!!!F128!DDR1_DQS_DP(7)!!!!
S!M_H_DQS_DP<8>!U2D1!L68!@baseboard_fab2_lib.baseboard_fab2(sch_1):page58_i172@chpset_lib.skx_ext_b(chips)!SKX_EXT_B_BGA1-IC,TBD!!!F128!DDR1_DQS_DP(8)!!!!
S!M_H_DQS_DP<9>!U2D1!AT81!@baseboard_fab2_lib.baseboard_fab2(sch_1):page58_i172@chpset_lib.skx_ext_b(chips)!SKX_EXT_B_BGA1-IC,TBD!!!F128!DDR1_DQS_DP(9)!!!!
S!M_H_ECC<0>!U2D1!J70!@baseboard_fab2_lib.baseboard_fab2(sch_1):page58_i172@chpset_lib.skx_ext_b(chips)!SKX_EXT_B_BGA1-IC,TBD!!!F128!DDR1_ECC(0)!!!!
S!M_H_ECC<1>!U2D1!H69!@baseboard_fab2_lib.baseboard_fab2(sch_1):page58_i172@chpset_lib.skx_ext_b(chips)!SKX_EXT_B_BGA1-IC,TBD!!!F128!DDR1_ECC(1)!!!!
S!M_H_ECC<2>!U2D1!J66!@baseboard_fab2_lib.baseboard_fab2(sch_1):page58_i172@chpset_lib.skx_ext_b(chips)!SKX_EXT_B_BGA1-IC,TBD!!!F128!DDR1_ECC(2)!!!!
S!M_H_ECC<3>!U2D1!L66!@baseboard_fab2_lib.baseboard_fab2(sch_1):page58_i172@chpset_lib.skx_ext_b(chips)!SKX_EXT_B_BGA1-IC,TBD!!!F128!DDR1_ECC(3)!!!!
S!M_H_ECC<4>!U2D1!L70!@baseboard_fab2_lib.baseboard_fab2(sch_1):page58_i172@chpset_lib.skx_ext_b(chips)!SKX_EXT_B_BGA1-IC,TBD!!!F128!DDR1_ECC(4)!!!!
S!M_H_ECC<5>!U2D1!M69!@baseboard_fab2_lib.baseboard_fab2(sch_1):page58_i172@chpset_lib.skx_ext_b(chips)!SKX_EXT_B_BGA1-IC,TBD!!!F128!DDR1_ECC(5)!!!!
S!M_H_ECC<6>!U2D1!H67!@baseboard_fab2_lib.baseboard_fab2(sch_1):page58_i172@chpset_lib.skx_ext_b(chips)!SKX_EXT_B_BGA1-IC,TBD!!!F128!DDR1_ECC(6)!!!!
S!M_H_ECC<7>!U2D1!M67!@baseboard_fab2_lib.baseboard_fab2(sch_1):page58_i172@chpset_lib.skx_ext_b(chips)!SKX_EXT_B_BGA1-IC,TBD!!!F128!DDR1_ECC(7)!!!!
S!M_H_MA<0>!U2D1!J52!@baseboard_fab2_lib.baseboard_fab2(sch_1):page58_i172@chpset_lib.skx_ext_b(chips)!SKX_EXT_B_BGA1-IC,TBD!!!F128!DDR1_MA(0)!!!!
S!M_H_MA<10>!U2D1!M55!@baseboard_fab2_lib.baseboard_fab2(sch_1):page58_i172@chpset_lib.skx_ext_b(chips)!SKX_EXT_B_BGA1-IC,TBD!!!F128!DDR1_MA(10)!!!!
S!M_H_MA<11>!U2D1!R60!@baseboard_fab2_lib.baseboard_fab2(sch_1):page58_i172@chpset_lib.skx_ext_b(chips)!SKX_EXT_B_BGA1-IC,TBD!!!F128!DDR1_MA(11)!!!!
S!M_H_MA<12>!U2D1!T61!@baseboard_fab2_lib.baseboard_fab2(sch_1):page58_i172@chpset_lib.skx_ext_b(chips)!SKX_EXT_B_BGA1-IC,TBD!!!F128!DDR1_MA(12)!!!!
S!M_H_MA<13>!U2D1!M51!@baseboard_fab2_lib.baseboard_fab2(sch_1):page58_i172@chpset_lib.skx_ext_b(chips)!SKX_EXT_B_BGA1-IC,TBD!!!F128!DDR1_MA(13)!!!!
S!M_H_MA<14>!U2D1!T51!@baseboard_fab2_lib.baseboard_fab2(sch_1):page58_i172@chpset_lib.skx_ext_b(chips)!SKX_EXT_B_BGA1-IC,TBD!!!F128!DDR1_MA(14)!!!!
S!M_H_MA<15>!U2D1!N52!@baseboard_fab2_lib.baseboard_fab2(sch_1):page58_i172@chpset_lib.skx_ext_b(chips)!SKX_EXT_B_BGA1-IC,TBD!!!F128!DDR1_MA(15)!!!!
S!M_H_MA<16>!U2D1!R52!@baseboard_fab2_lib.baseboard_fab2(sch_1):page58_i172@chpset_lib.skx_ext_b(chips)!SKX_EXT_B_BGA1-IC,TBD!!!F128!DDR1_MA(16)!!!!
S!M_H_MA<17>!U2D1!N48!@baseboard_fab2_lib.baseboard_fab2(sch_1):page58_i172@chpset_lib.skx_ext_b(chips)!SKX_EXT_B_BGA1-IC,TBD!!!F128!DDR1_MA(17)!!!!
S!M_H_MA<1>!U2D1!J58!@baseboard_fab2_lib.baseboard_fab2(sch_1):page58_i172@chpset_lib.skx_ext_b(chips)!SKX_EXT_B_BGA1-IC,TBD!!!F128!DDR1_MA(1)!!!!
S!M_H_MA<2>!U2D1!K57!@baseboard_fab2_lib.baseboard_fab2(sch_1):page58_i172@chpset_lib.skx_ext_b(chips)!SKX_EXT_B_BGA1-IC,TBD!!!F128!DDR1_MA(2)!!!!
S!M_H_MA<3>!U2D1!N58!@baseboard_fab2_lib.baseboard_fab2(sch_1):page58_i172@chpset_lib.skx_ext_b(chips)!SKX_EXT_B_BGA1-IC,TBD!!!F128!DDR1_MA(3)!!!!
S!M_H_MA<4>!U2D1!M59!@baseboard_fab2_lib.baseboard_fab2(sch_1):page58_i172@chpset_lib.skx_ext_b(chips)!SKX_EXT_B_BGA1-IC,TBD!!!F128!DDR1_MA(4)!!!!
S!M_H_MA<5>!U2D1!R58!@baseboard_fab2_lib.baseboard_fab2(sch_1):page58_i172@chpset_lib.skx_ext_b(chips)!SKX_EXT_B_BGA1-IC,TBD!!!F128!DDR1_MA(5)!!!!
S!M_H_MA<6>!U2D1!T59!@baseboard_fab2_lib.baseboard_fab2(sch_1):page58_i172@chpset_lib.skx_ext_b(chips)!SKX_EXT_B_BGA1-IC,TBD!!!F128!DDR1_MA(6)!!!!
S!M_H_MA<7>!U2D1!V61!@baseboard_fab2_lib.baseboard_fab2(sch_1):page58_i172@chpset_lib.skx_ext_b(chips)!SKX_EXT_B_BGA1-IC,TBD!!!F128!DDR1_MA(7)!!!!
S!M_H_MA<8>!U2D1!W60!@baseboard_fab2_lib.baseboard_fab2(sch_1):page58_i172@chpset_lib.skx_ext_b(chips)!SKX_EXT_B_BGA1-IC,TBD!!!F128!DDR1_MA(8)!!!!
S!M_H_MA<9>!U2D1!K59!@baseboard_fab2_lib.baseboard_fab2(sch_1):page58_i172@chpset_lib.skx_ext_b(chips)!SKX_EXT_B_BGA1-IC,TBD!!!F128!DDR1_MA(9)!!!!
S!M_H_ODT<0>!U2D1!N50!@baseboard_fab2_lib.baseboard_fab2(sch_1):page58_i172@chpset_lib.skx_ext_b(chips)!SKX_EXT_B_BGA1-IC,TBD!!!F128!DDR1_ODT(0)!!!!
S!M_H_ODT<1>!U2D1!R48!@baseboard_fab2_lib.baseboard_fab2(sch_1):page58_i172@chpset_lib.skx_ext_b(chips)!SKX_EXT_B_BGA1-IC,TBD!!!F128!DDR1_ODT(1)!!!!
S!M_H_ODT<2>!U2D1!M49!@baseboard_fab2_lib.baseboard_fab2(sch_1):page58_i172@chpset_lib.skx_ext_b(chips)!SKX_EXT_B_BGA1-IC,TBD!!!F128!DDR1_ODT(2)!!!!
S!M_H_ODT<3>!U2D1!T47!@baseboard_fab2_lib.baseboard_fab2(sch_1):page58_i172@chpset_lib.skx_ext_b(chips)!SKX_EXT_B_BGA1-IC,TBD!!!F128!DDR1_ODT(3)!!!!
S!M_H_PAR!U2D1!K53!@baseboard_fab2_lib.baseboard_fab2(sch_1):page58_i172@chpset_lib.skx_ext_b(chips)!SKX_EXT_B_BGA1-IC,TBD!!!F128!DDR1_PAR!!!!
S!M_J_ACT_N!U2D1!AB61!@baseboard_fab2_lib.baseboard_fab2(sch_1):page59_i172@chpset_lib.skx_ext_b(chips)!SKX_EXT_B_BGA1-IC,TBD!!!F127!DDR2_ACT_N!!!!
S!M_J_ALERT_N!U2D1!AD61!@baseboard_fab2_lib.baseboard_fab2(sch_1):page59_i172@chpset_lib.skx_ext_b(chips)!SKX_EXT_B_BGA1-IC,TBD!!!F127!DDR2_ALERT_N!!!!
S!M_J_BA<0>!U2D1!W52!@baseboard_fab2_lib.baseboard_fab2(sch_1):page59_i172@chpset_lib.skx_ext_b(chips)!SKX_EXT_B_BGA1-IC,TBD!!!F127!DDR2_BA(0)!!!!
S!M_J_BA<1>!U2D1!AE56!@baseboard_fab2_lib.baseboard_fab2(sch_1):page59_i172@chpset_lib.skx_ext_b(chips)!SKX_EXT_B_BGA1-IC,TBD!!!F127!DDR2_BA(1)!!!!
S!M_J_BG<0>!U2D1!AA60!@baseboard_fab2_lib.baseboard_fab2(sch_1):page59_i172@chpset_lib.skx_ext_b(chips)!SKX_EXT_B_BGA1-IC,TBD!!!F127!DDR2_BG(0)!!!!
S!M_J_BG<1>!U2D1!AE62!@baseboard_fab2_lib.baseboard_fab2(sch_1):page59_i172@chpset_lib.skx_ext_b(chips)!SKX_EXT_B_BGA1-IC,TBD!!!F127!DDR2_BG(1)!!!!
S!M_J_C<2>!U2D1!AB45!@baseboard_fab2_lib.baseboard_fab2(sch_1):page59_i172@chpset_lib.skx_ext_b(chips)!SKX_EXT_B_BGA1-IC,TBD!!!F127!DDR2_CID(2)!!!!
S!M_J_CKE<0>!U2D1!AA62!@baseboard_fab2_lib.baseboard_fab2(sch_1):page59_i172@chpset_lib.skx_ext_b(chips)!SKX_EXT_B_BGA1-IC,TBD!!!F127!DDR2_CKE(0)!!!!
S!M_J_CKE<1>!U2D1!AD63!@baseboard_fab2_lib.baseboard_fab2(sch_1):page59_i172@chpset_lib.skx_ext_b(chips)!SKX_EXT_B_BGA1-IC,TBD!!!F127!DDR2_CKE(1)!!!!
S!M_J_CKE<2>!U2D1!V63!@baseboard_fab2_lib.baseboard_fab2(sch_1):page59_i172@chpset_lib.skx_ext_b(chips)!SKX_EXT_B_BGA1-IC,TBD!!!F127!DDR2_CKE(2)!!!!
S!M_J_CKE<3>!U2D1!AB63!@baseboard_fab2_lib.baseboard_fab2(sch_1):page59_i172@chpset_lib.skx_ext_b(chips)!SKX_EXT_B_BGA1-IC,TBD!!!F127!DDR2_CKE(3)!!!!
S!M_J_CLK_DN<0>!U2D1!AA54!@baseboard_fab2_lib.baseboard_fab2(sch_1):page59_i172@chpset_lib.skx_ext_b(chips)!SKX_EXT_B_BGA1-IC,TBD!!!F127!DDR2_CLK_DN(0)!!!!
S!M_J_CLK_DN<2>!U2D1!AA56!@baseboard_fab2_lib.baseboard_fab2(sch_1):page59_i172@chpset_lib.skx_ext_b(chips)!SKX_EXT_B_BGA1-IC,TBD!!!F127!DDR2_CLK_DN(2)!!!!
S!M_J_CLK_DN<1>!U2D1!W54!@baseboard_fab2_lib.baseboard_fab2(sch_1):page59_i172@chpset_lib.skx_ext_b(chips)!SKX_EXT_B_BGA1-IC,TBD!!!F127!DDR2_CLK_DN(1)!!!!
S!M_J_CLK_DN<3>!U2D1!W56!@baseboard_fab2_lib.baseboard_fab2(sch_1):page59_i172@chpset_lib.skx_ext_b(chips)!SKX_EXT_B_BGA1-IC,TBD!!!F127!DDR2_CLK_DN(3)!!!!
S!M_J_CLK_DP<0>!U2D1!AB55!@baseboard_fab2_lib.baseboard_fab2(sch_1):page59_i172@chpset_lib.skx_ext_b(chips)!SKX_EXT_B_BGA1-IC,TBD!!!F127!DDR2_CLK_DP(0)!!!!
S!M_J_CLK_DP<2>!U2D1!AB57!@baseboard_fab2_lib.baseboard_fab2(sch_1):page59_i172@chpset_lib.skx_ext_b(chips)!SKX_EXT_B_BGA1-IC,TBD!!!F127!DDR2_CLK_DP(2)!!!!
S!M_J_CLK_DP<1>!U2D1!V55!@baseboard_fab2_lib.baseboard_fab2(sch_1):page59_i172@chpset_lib.skx_ext_b(chips)!SKX_EXT_B_BGA1-IC,TBD!!!F127!DDR2_CLK_DP(1)!!!!
S!M_J_CLK_DP<3>!U2D1!V57!@baseboard_fab2_lib.baseboard_fab2(sch_1):page59_i172@chpset_lib.skx_ext_b(chips)!SKX_EXT_B_BGA1-IC,TBD!!!F127!DDR2_CLK_DP(3)!!!!
S!M_J_CS_N<0>!U2D1!V51!@baseboard_fab2_lib.baseboard_fab2(sch_1):page59_i172@chpset_lib.skx_ext_b(chips)!SKX_EXT_B_BGA1-IC,TBD!!!F127!DDR2_CS_N(0)!!!!
S!M_J_CS_N<1>!U2D1!AB49!@baseboard_fab2_lib.baseboard_fab2(sch_1):page59_i172@chpset_lib.skx_ext_b(chips)!SKX_EXT_B_BGA1-IC,TBD!!!F127!DDR2_CS_N(1)!!!!
S!M_J_CS_N<2>!U2D1!W46!@baseboard_fab2_lib.baseboard_fab2(sch_1):page59_i172@chpset_lib.skx_ext_b(chips)!SKX_EXT_B_BGA1-IC,TBD!!!F127!DDR2_CS_N(2)!!!!
S!M_J_CS_N<3>!U2D1!AA46!@baseboard_fab2_lib.baseboard_fab2(sch_1):page59_i172@chpset_lib.skx_ext_b(chips)!SKX_EXT_B_BGA1-IC,TBD!!!F127!DDR2_CS_N(3)!!!!
S!M_J_CS_N<4>!U2D1!AB51!@baseboard_fab2_lib.baseboard_fab2(sch_1):page59_i172@chpset_lib.skx_ext_b(chips)!SKX_EXT_B_BGA1-IC,TBD!!!F127!DDR2_CS_N(4)!!!!
S!M_J_CS_N<5>!U2D1!W48!@baseboard_fab2_lib.baseboard_fab2(sch_1):page59_i172@chpset_lib.skx_ext_b(chips)!SKX_EXT_B_BGA1-IC,TBD!!!F127!DDR2_CS_N(5)!!!!
S!M_J_CS_N<6>!U2D1!T45!@baseboard_fab2_lib.baseboard_fab2(sch_1):page59_i172@chpset_lib.skx_ext_b(chips)!SKX_EXT_B_BGA1-IC,TBD!!!F127!DDR2_CS_N(6)!!!!
S!M_J_CS_N<7>!U2D1!V45!@baseboard_fab2_lib.baseboard_fab2(sch_1):page59_i172@chpset_lib.skx_ext_b(chips)!SKX_EXT_B_BGA1-IC,TBD!!!F127!DDR2_CS_N(7)!!!!
S!M_J_DQ<0>!U2D1!AR76!@baseboard_fab2_lib.baseboard_fab2(sch_1):page59_i172@chpset_lib.skx_ext_b(chips)!SKX_EXT_B_BGA1-IC,TBD!!!F127!DDR2_DQ(0)!!!!
S!M_J_DQ<10>!U2D1!Y77!@baseboard_fab2_lib.baseboard_fab2(sch_1):page59_i172@chpset_lib.skx_ext_b(chips)!SKX_EXT_B_BGA1-IC,TBD!!!F127!DDR2_DQ(10)!!!!
S!M_J_DQ<11>!U2D1!W76!@baseboard_fab2_lib.baseboard_fab2(sch_1):page59_i172@chpset_lib.skx_ext_b(chips)!SKX_EXT_B_BGA1-IC,TBD!!!F127!DDR2_DQ(11)!!!!
S!M_J_DQ<12>!U2D1!AF75!@baseboard_fab2_lib.baseboard_fab2(sch_1):page59_i172@chpset_lib.skx_ext_b(chips)!SKX_EXT_B_BGA1-IC,TBD!!!F127!DDR2_DQ(12)!!!!
S!M_J_DQ<13>!U2D1!AE74!@baseboard_fab2_lib.baseboard_fab2(sch_1):page59_i172@chpset_lib.skx_ext_b(chips)!SKX_EXT_B_BGA1-IC,TBD!!!F127!DDR2_DQ(13)!!!!
S!M_J_DQ<14>!U2D1!AB77!@baseboard_fab2_lib.baseboard_fab2(sch_1):page59_i172@chpset_lib.skx_ext_b(chips)!SKX_EXT_B_BGA1-IC,TBD!!!F127!DDR2_DQ(14)!!!!
S!M_J_DQ<15>!U2D1!Y75!@baseboard_fab2_lib.baseboard_fab2(sch_1):page59_i172@chpset_lib.skx_ext_b(chips)!SKX_EXT_B_BGA1-IC,TBD!!!F127!DDR2_DQ(15)!!!!
S!M_J_DQ<16>!U2D1!W72!@baseboard_fab2_lib.baseboard_fab2(sch_1):page59_i172@chpset_lib.skx_ext_b(chips)!SKX_EXT_B_BGA1-IC,TBD!!!F127!DDR2_DQ(16)!!!!
S!M_J_DQ<17>!U2D1!AA70!@baseboard_fab2_lib.baseboard_fab2(sch_1):page59_i172@chpset_lib.skx_ext_b(chips)!SKX_EXT_B_BGA1-IC,TBD!!!F127!DDR2_DQ(17)!!!!
S!M_J_DQ<18>!U2D1!R70!@baseboard_fab2_lib.baseboard_fab2(sch_1):page59_i172@chpset_lib.skx_ext_b(chips)!SKX_EXT_B_BGA1-IC,TBD!!!F127!DDR2_DQ(18)!!!!
S!M_J_DQ<19>!U2D1!T69!@baseboard_fab2_lib.baseboard_fab2(sch_1):page59_i172@chpset_lib.skx_ext_b(chips)!SKX_EXT_B_BGA1-IC,TBD!!!F127!DDR2_DQ(19)!!!!
S!M_J_DQ<1>!U2D1!AN74!@baseboard_fab2_lib.baseboard_fab2(sch_1):page59_i172@chpset_lib.skx_ext_b(chips)!SKX_EXT_B_BGA1-IC,TBD!!!F127!DDR2_DQ(1)!!!!
S!M_J_DQ<20>!U2D1!AA72!@baseboard_fab2_lib.baseboard_fab2(sch_1):page59_i172@chpset_lib.skx_ext_b(chips)!SKX_EXT_B_BGA1-IC,TBD!!!F127!DDR2_DQ(20)!!!!
S!M_J_DQ<21>!U2D1!AB71!@baseboard_fab2_lib.baseboard_fab2(sch_1):page59_i172@chpset_lib.skx_ext_b(chips)!SKX_EXT_B_BGA1-IC,TBD!!!F127!DDR2_DQ(21)!!!!
S!M_J_DQ<22>!U2D1!T71!@baseboard_fab2_lib.baseboard_fab2(sch_1):page59_i172@chpset_lib.skx_ext_b(chips)!SKX_EXT_B_BGA1-IC,TBD!!!F127!DDR2_DQ(22)!!!!
S!M_J_DQ<23>!U2D1!V69!@baseboard_fab2_lib.baseboard_fab2(sch_1):page59_i172@chpset_lib.skx_ext_b(chips)!SKX_EXT_B_BGA1-IC,TBD!!!F127!DDR2_DQ(23)!!!!
S!M_J_DQ<24>!U2D1!AM67!@baseboard_fab2_lib.baseboard_fab2(sch_1):page59_i172@chpset_lib.skx_ext_b(chips)!SKX_EXT_B_BGA1-IC,TBD!!!F127!DDR2_DQ(24)!!!!
S!M_J_DQ<25>!U2D1!AT67!@baseboard_fab2_lib.baseboard_fab2(sch_1):page59_i172@chpset_lib.skx_ext_b(chips)!SKX_EXT_B_BGA1-IC,TBD!!!F127!DDR2_DQ(25)!!!!
S!M_J_DQ<26>!U2D1!AN64!@baseboard_fab2_lib.baseboard_fab2(sch_1):page59_i172@chpset_lib.skx_ext_b(chips)!SKX_EXT_B_BGA1-IC,TBD!!!F127!DDR2_DQ(26)!!!!
S!M_J_DQ<27>!U2D1!AR64!@baseboard_fab2_lib.baseboard_fab2(sch_1):page59_i172@chpset_lib.skx_ext_b(chips)!SKX_EXT_B_BGA1-IC,TBD!!!F127!DDR2_DQ(27)!!!!
S!M_J_DQ<28>!U2D1!AN68!@baseboard_fab2_lib.baseboard_fab2(sch_1):page59_i172@chpset_lib.skx_ext_b(chips)!SKX_EXT_B_BGA1-IC,TBD!!!F127!DDR2_DQ(28)!!!!
S!M_J_DQ<29>!U2D1!AR68!@baseboard_fab2_lib.baseboard_fab2(sch_1):page59_i172@chpset_lib.skx_ext_b(chips)!SKX_EXT_B_BGA1-IC,TBD!!!F127!DDR2_DQ(29)!!!!
S!M_J_DQ<2>!U2D1!AK77!@baseboard_fab2_lib.baseboard_fab2(sch_1):page59_i172@chpset_lib.skx_ext_b(chips)!SKX_EXT_B_BGA1-IC,TBD!!!F127!DDR2_DQ(2)!!!!
S!M_J_DQ<30>!U2D1!AM65!@baseboard_fab2_lib.baseboard_fab2(sch_1):page59_i172@chpset_lib.skx_ext_b(chips)!SKX_EXT_B_BGA1-IC,TBD!!!F127!DDR2_DQ(30)!!!!
S!M_J_DQ<31>!U2D1!AT65!@baseboard_fab2_lib.baseboard_fab2(sch_1):page59_i172@chpset_lib.skx_ext_b(chips)!SKX_EXT_B_BGA1-IC,TBD!!!F127!DDR2_DQ(31)!!!!
S!M_J_DQ<32>!U2D1!U40!@baseboard_fab2_lib.baseboard_fab2(sch_1):page59_i172@chpset_lib.skx_ext_b(chips)!SKX_EXT_B_BGA1-IC,TBD!!!F127!DDR2_DQ(32)!!!!
S!M_J_DQ<33>!U2D1!AA40!@baseboard_fab2_lib.baseboard_fab2(sch_1):page59_i172@chpset_lib.skx_ext_b(chips)!SKX_EXT_B_BGA1-IC,TBD!!!F127!DDR2_DQ(33)!!!!
S!M_J_DQ<34>!U2D1!V37!@baseboard_fab2_lib.baseboard_fab2(sch_1):page59_i172@chpset_lib.skx_ext_b(chips)!SKX_EXT_B_BGA1-IC,TBD!!!F127!DDR2_DQ(34)!!!!
S!M_J_DQ<35>!U2D1!Y37!@baseboard_fab2_lib.baseboard_fab2(sch_1):page59_i172@chpset_lib.skx_ext_b(chips)!SKX_EXT_B_BGA1-IC,TBD!!!F127!DDR2_DQ(35)!!!!
S!M_J_DQ<36>!U2D1!V41!@baseboard_fab2_lib.baseboard_fab2(sch_1):page59_i172@chpset_lib.skx_ext_b(chips)!SKX_EXT_B_BGA1-IC,TBD!!!F127!DDR2_DQ(36)!!!!
S!M_J_DQ<37>!U2D1!Y41!@baseboard_fab2_lib.baseboard_fab2(sch_1):page59_i172@chpset_lib.skx_ext_b(chips)!SKX_EXT_B_BGA1-IC,TBD!!!F127!DDR2_DQ(37)!!!!
S!M_J_DQ<38>!U2D1!U38!@baseboard_fab2_lib.baseboard_fab2(sch_1):page59_i172@chpset_lib.skx_ext_b(chips)!SKX_EXT_B_BGA1-IC,TBD!!!F127!DDR2_DQ(38)!!!!
S!M_J_DQ<39>!U2D1!AA38!@baseboard_fab2_lib.baseboard_fab2(sch_1):page59_i172@chpset_lib.skx_ext_b(chips)!SKX_EXT_B_BGA1-IC,TBD!!!F127!DDR2_DQ(39)!!!!
S!M_J_DQ<3>!U2D1!AJ76!@baseboard_fab2_lib.baseboard_fab2(sch_1):page59_i172@chpset_lib.skx_ext_b(chips)!SKX_EXT_B_BGA1-IC,TBD!!!F127!DDR2_DQ(3)!!!!
S!M_J_DQ<40>!U2D1!U34!@baseboard_fab2_lib.baseboard_fab2(sch_1):page59_i172@chpset_lib.skx_ext_b(chips)!SKX_EXT_B_BGA1-IC,TBD!!!F127!DDR2_DQ(40)!!!!
S!M_J_DQ<41>!U2D1!AA34!@baseboard_fab2_lib.baseboard_fab2(sch_1):page59_i172@chpset_lib.skx_ext_b(chips)!SKX_EXT_B_BGA1-IC,TBD!!!F127!DDR2_DQ(41)!!!!
S!M_J_DQ<42>!U2D1!V31!@baseboard_fab2_lib.baseboard_fab2(sch_1):page59_i172@chpset_lib.skx_ext_b(chips)!SKX_EXT_B_BGA1-IC,TBD!!!F127!DDR2_DQ(42)!!!!
S!M_J_DQ<43>!U2D1!Y31!@baseboard_fab2_lib.baseboard_fab2(sch_1):page59_i172@chpset_lib.skx_ext_b(chips)!SKX_EXT_B_BGA1-IC,TBD!!!F127!DDR2_DQ(43)!!!!
S!M_J_DQ<44>!U2D1!V35!@baseboard_fab2_lib.baseboard_fab2(sch_1):page59_i172@chpset_lib.skx_ext_b(chips)!SKX_EXT_B_BGA1-IC,TBD!!!F127!DDR2_DQ(44)!!!!
S!M_J_DQ<45>!U2D1!Y35!@baseboard_fab2_lib.baseboard_fab2(sch_1):page59_i172@chpset_lib.skx_ext_b(chips)!SKX_EXT_B_BGA1-IC,TBD!!!F127!DDR2_DQ(45)!!!!
S!M_J_DQ<46>!U2D1!U32!@baseboard_fab2_lib.baseboard_fab2(sch_1):page59_i172@chpset_lib.skx_ext_b(chips)!SKX_EXT_B_BGA1-IC,TBD!!!F127!DDR2_DQ(46)!!!!
S!M_J_DQ<47>!U2D1!AA32!@baseboard_fab2_lib.baseboard_fab2(sch_1):page59_i172@chpset_lib.skx_ext_b(chips)!SKX_EXT_B_BGA1-IC,TBD!!!F127!DDR2_DQ(47)!!!!
S!M_J_DQ<48>!U2D1!AD31!@baseboard_fab2_lib.baseboard_fab2(sch_1):page59_i172@chpset_lib.skx_ext_b(chips)!SKX_EXT_B_BGA1-IC,TBD!!!F127!DDR2_DQ(48)!!!!
S!M_J_DQ<49>!U2D1!AH31!@baseboard_fab2_lib.baseboard_fab2(sch_1):page59_i172@chpset_lib.skx_ext_b(chips)!SKX_EXT_B_BGA1-IC,TBD!!!F127!DDR2_DQ(49)!!!!
S!M_J_DQ<4>!U2D1!AT75!@baseboard_fab2_lib.baseboard_fab2(sch_1):page59_i172@chpset_lib.skx_ext_b(chips)!SKX_EXT_B_BGA1-IC,TBD!!!F127!DDR2_DQ(4)!!!!
S!M_J_DQ<50>!U2D1!AE28!@baseboard_fab2_lib.baseboard_fab2(sch_1):page59_i172@chpset_lib.skx_ext_b(chips)!SKX_EXT_B_BGA1-IC,TBD!!!F127!DDR2_DQ(50)!!!!
S!M_J_DQ<51>!U2D1!AG28!@baseboard_fab2_lib.baseboard_fab2(sch_1):page59_i172@chpset_lib.skx_ext_b(chips)!SKX_EXT_B_BGA1-IC,TBD!!!F127!DDR2_DQ(51)!!!!
S!M_J_DQ<52>!U2D1!AE32!@baseboard_fab2_lib.baseboard_fab2(sch_1):page59_i172@chpset_lib.skx_ext_b(chips)!SKX_EXT_B_BGA1-IC,TBD!!!F127!DDR2_DQ(52)!!!!
S!M_J_DQ<53>!U2D1!AG32!@baseboard_fab2_lib.baseboard_fab2(sch_1):page59_i172@chpset_lib.skx_ext_b(chips)!SKX_EXT_B_BGA1-IC,TBD!!!F127!DDR2_DQ(53)!!!!
S!M_J_DQ<54>!U2D1!AD29!@baseboard_fab2_lib.baseboard_fab2(sch_1):page59_i172@chpset_lib.skx_ext_b(chips)!SKX_EXT_B_BGA1-IC,TBD!!!F127!DDR2_DQ(54)!!!!
S!M_J_DQ<55>!U2D1!AH29!@baseboard_fab2_lib.baseboard_fab2(sch_1):page59_i172@chpset_lib.skx_ext_b(chips)!SKX_EXT_B_BGA1-IC,TBD!!!F127!DDR2_DQ(55)!!!!
S!M_J_DQ<56>!U2D1!AD25!@baseboard_fab2_lib.baseboard_fab2(sch_1):page59_i172@chpset_lib.skx_ext_b(chips)!SKX_EXT_B_BGA1-IC,TBD!!!F127!DDR2_DQ(56)!!!!
S!M_J_DQ<57>!U2D1!AH25!@baseboard_fab2_lib.baseboard_fab2(sch_1):page59_i172@chpset_lib.skx_ext_b(chips)!SKX_EXT_B_BGA1-IC,TBD!!!F127!DDR2_DQ(57)!!!!
S!M_J_DQ<58>!U2D1!AE22!@baseboard_fab2_lib.baseboard_fab2(sch_1):page59_i172@chpset_lib.skx_ext_b(chips)!SKX_EXT_B_BGA1-IC,TBD!!!F127!DDR2_DQ(58)!!!!
S!M_J_DQ<59>!U2D1!AG22!@baseboard_fab2_lib.baseboard_fab2(sch_1):page59_i172@chpset_lib.skx_ext_b(chips)!SKX_EXT_B_BGA1-IC,TBD!!!F127!DDR2_DQ(59)!!!!
S!M_J_DQ<5>!U2D1!AR74!@baseboard_fab2_lib.baseboard_fab2(sch_1):page59_i172@chpset_lib.skx_ext_b(chips)!SKX_EXT_B_BGA1-IC,TBD!!!F127!DDR2_DQ(5)!!!!
S!M_J_DQ<60>!U2D1!AE26!@baseboard_fab2_lib.baseboard_fab2(sch_1):page59_i172@chpset_lib.skx_ext_b(chips)!SKX_EXT_B_BGA1-IC,TBD!!!F127!DDR2_DQ(60)!!!!
S!M_J_DQ<61>!U2D1!AG26!@baseboard_fab2_lib.baseboard_fab2(sch_1):page59_i172@chpset_lib.skx_ext_b(chips)!SKX_EXT_B_BGA1-IC,TBD!!!F127!DDR2_DQ(61)!!!!
S!M_J_DQ<62>!U2D1!AD23!@baseboard_fab2_lib.baseboard_fab2(sch_1):page59_i172@chpset_lib.skx_ext_b(chips)!SKX_EXT_B_BGA1-IC,TBD!!!F127!DDR2_DQ(62)!!!!
S!M_J_DQ<63>!U2D1!AH23!@baseboard_fab2_lib.baseboard_fab2(sch_1):page59_i172@chpset_lib.skx_ext_b(chips)!SKX_EXT_B_BGA1-IC,TBD!!!F127!DDR2_DQ(63)!!!!
S!M_J_DQ<6>!U2D1!AM77!@baseboard_fab2_lib.baseboard_fab2(sch_1):page59_i172@chpset_lib.skx_ext_b(chips)!SKX_EXT_B_BGA1-IC,TBD!!!F127!DDR2_DQ(6)!!!!
S!M_J_DQ<7>!U2D1!AK75!@baseboard_fab2_lib.baseboard_fab2(sch_1):page59_i172@chpset_lib.skx_ext_b(chips)!SKX_EXT_B_BGA1-IC,TBD!!!F127!DDR2_DQ(7)!!!!
S!M_J_DQ<8>!U2D1!AE76!@baseboard_fab2_lib.baseboard_fab2(sch_1):page59_i172@chpset_lib.skx_ext_b(chips)!SKX_EXT_B_BGA1-IC,TBD!!!F127!DDR2_DQ(8)!!!!
S!M_J_DQ<9>!U2D1!AC74!@baseboard_fab2_lib.baseboard_fab2(sch_1):page59_i172@chpset_lib.skx_ext_b(chips)!SKX_EXT_B_BGA1-IC,TBD!!!F127!DDR2_DQ(9)!!!!
S!M_J_DQS_DN<0>!U2D1!AL74!@baseboard_fab2_lib.baseboard_fab2(sch_1):page59_i172@chpset_lib.skx_ext_b(chips)!SKX_EXT_B_BGA1-IC,TBD!!!F127!DDR2_DQS_DN(0)!!!!
S!M_J_DQS_DN<10>!U2D1!AD77!@baseboard_fab2_lib.baseboard_fab2(sch_1):page59_i172@chpset_lib.skx_ext_b(chips)!SKX_EXT_B_BGA1-IC,TBD!!!F127!DDR2_DQS_DN(10)!!!!
S!M_J_DQS_DN<11>!U2D1!U72!@baseboard_fab2_lib.baseboard_fab2(sch_1):page59_i172@chpset_lib.skx_ext_b(chips)!SKX_EXT_B_BGA1-IC,TBD!!!F127!DDR2_DQS_DN(11)!!!!
S!M_J_DQS_DN<12>!U2D1!AL66!@baseboard_fab2_lib.baseboard_fab2(sch_1):page59_i172@chpset_lib.skx_ext_b(chips)!SKX_EXT_B_BGA1-IC,TBD!!!F127!DDR2_DQS_DN(12)!!!!
S!M_J_DQS_DN<13>!U2D1!T39!@baseboard_fab2_lib.baseboard_fab2(sch_1):page59_i172@chpset_lib.skx_ext_b(chips)!SKX_EXT_B_BGA1-IC,TBD!!!F127!DDR2_DQS_DN(13)!!!!
S!M_J_DQS_DN<14>!U2D1!T33!@baseboard_fab2_lib.baseboard_fab2(sch_1):page59_i172@chpset_lib.skx_ext_b(chips)!SKX_EXT_B_BGA1-IC,TBD!!!F127!DDR2_DQS_DN(14)!!!!
S!M_J_DQS_DN<15>!U2D1!AC30!@baseboard_fab2_lib.baseboard_fab2(sch_1):page59_i172@chpset_lib.skx_ext_b(chips)!SKX_EXT_B_BGA1-IC,TBD!!!F127!DDR2_DQS_DN(15)!!!!
S!M_J_DQS_DN<16>!U2D1!AC24!@baseboard_fab2_lib.baseboard_fab2(sch_1):page59_i172@chpset_lib.skx_ext_b(chips)!SKX_EXT_B_BGA1-IC,TBD!!!F127!DDR2_DQS_DN(16)!!!!
S!M_J_DQS_DN<17>!U2D1!AT71!@baseboard_fab2_lib.baseboard_fab2(sch_1):page59_i172@chpset_lib.skx_ext_b(chips)!SKX_EXT_B_BGA1-IC,TBD!!!F127!DDR2_DQS_DN(17)!!!!
S!M_J_DQS_DN<1>!U2D1!AA74!@baseboard_fab2_lib.baseboard_fab2(sch_1):page59_i172@chpset_lib.skx_ext_b(chips)!SKX_EXT_B_BGA1-IC,TBD!!!F127!DDR2_DQS_DN(1)!!!!
S!M_J_DQS_DN<2>!U2D1!Y69!@baseboard_fab2_lib.baseboard_fab2(sch_1):page59_i172@chpset_lib.skx_ext_b(chips)!SKX_EXT_B_BGA1-IC,TBD!!!F127!DDR2_DQS_DN(2)!!!!
S!M_J_DQS_DN<3>!U2D1!AU66!@baseboard_fab2_lib.baseboard_fab2(sch_1):page59_i172@chpset_lib.skx_ext_b(chips)!SKX_EXT_B_BGA1-IC,TBD!!!F127!DDR2_DQS_DN(3)!!!!
S!M_J_DQS_DN<4>!U2D1!AB39!@baseboard_fab2_lib.baseboard_fab2(sch_1):page59_i172@chpset_lib.skx_ext_b(chips)!SKX_EXT_B_BGA1-IC,TBD!!!F127!DDR2_DQS_DN(4)!!!!
S!M_J_DQS_DN<5>!U2D1!AB33!@baseboard_fab2_lib.baseboard_fab2(sch_1):page59_i172@chpset_lib.skx_ext_b(chips)!SKX_EXT_B_BGA1-IC,TBD!!!F127!DDR2_DQS_DN(5)!!!!
S!M_J_DQS_DN<6>!U2D1!AJ30!@baseboard_fab2_lib.baseboard_fab2(sch_1):page59_i172@chpset_lib.skx_ext_b(chips)!SKX_EXT_B_BGA1-IC,TBD!!!F127!DDR2_DQS_DN(6)!!!!
S!M_J_DQS_DN<7>!U2D1!AJ24!@baseboard_fab2_lib.baseboard_fab2(sch_1):page59_i172@chpset_lib.skx_ext_b(chips)!SKX_EXT_B_BGA1-IC,TBD!!!F127!DDR2_DQS_DN(7)!!!!
S!M_J_DQS_DN<8>!U2D1!BB71!@baseboard_fab2_lib.baseboard_fab2(sch_1):page59_i172@chpset_lib.skx_ext_b(chips)!SKX_EXT_B_BGA1-IC,TBD!!!F127!DDR2_DQS_DN(8)!!!!
S!M_J_DQS_DN<9>!U2D1!AP77!@baseboard_fab2_lib.baseboard_fab2(sch_1):page59_i172@chpset_lib.skx_ext_b(chips)!SKX_EXT_B_BGA1-IC,TBD!!!F127!DDR2_DQS_DN(9)!!!!
S!M_J_DQS_DP<0>!U2D1!AM75!@baseboard_fab2_lib.baseboard_fab2(sch_1):page59_i172@chpset_lib.skx_ext_b(chips)!SKX_EXT_B_BGA1-IC,TBD!!!F127!DDR2_DQS_DP(0)!!!!
S!M_J_DQS_DP<10>!U2D1!AC76!@baseboard_fab2_lib.baseboard_fab2(sch_1):page59_i172@chpset_lib.skx_ext_b(chips)!SKX_EXT_B_BGA1-IC,TBD!!!F127!DDR2_DQS_DP(10)!!!!
S!M_J_DQS_DP<11>!U2D1!V71!@baseboard_fab2_lib.baseboard_fab2(sch_1):page59_i172@chpset_lib.skx_ext_b(chips)!SKX_EXT_B_BGA1-IC,TBD!!!F127!DDR2_DQS_DP(11)!!!!
S!M_J_DQS_DP<12>!U2D1!AN66!@baseboard_fab2_lib.baseboard_fab2(sch_1):page59_i172@chpset_lib.skx_ext_b(chips)!SKX_EXT_B_BGA1-IC,TBD!!!F127!DDR2_DQS_DP(12)!!!!
S!M_J_DQS_DP<13>!U2D1!V39!@baseboard_fab2_lib.baseboard_fab2(sch_1):page59_i172@chpset_lib.skx_ext_b(chips)!SKX_EXT_B_BGA1-IC,TBD!!!F127!DDR2_DQS_DP(13)!!!!
S!M_J_DQS_DP<14>!U2D1!V33!@baseboard_fab2_lib.baseboard_fab2(sch_1):page59_i172@chpset_lib.skx_ext_b(chips)!SKX_EXT_B_BGA1-IC,TBD!!!F127!DDR2_DQS_DP(14)!!!!
S!M_J_DQS_DP<15>!U2D1!AE30!@baseboard_fab2_lib.baseboard_fab2(sch_1):page59_i172@chpset_lib.skx_ext_b(chips)!SKX_EXT_B_BGA1-IC,TBD!!!F127!DDR2_DQS_DP(15)!!!!
S!M_J_DQS_DP<16>!U2D1!AE24!@baseboard_fab2_lib.baseboard_fab2(sch_1):page59_i172@chpset_lib.skx_ext_b(chips)!SKX_EXT_B_BGA1-IC,TBD!!!F127!DDR2_DQS_DP(16)!!!!
S!M_J_DQS_DP<17>!U2D1!AV71!@baseboard_fab2_lib.baseboard_fab2(sch_1):page59_i172@chpset_lib.skx_ext_b(chips)!SKX_EXT_B_BGA1-IC,TBD!!!F127!DDR2_DQS_DP(17)!!!!
S!M_J_DQS_DP<1>!U2D1!AB75!@baseboard_fab2_lib.baseboard_fab2(sch_1):page59_i172@chpset_lib.skx_ext_b(chips)!SKX_EXT_B_BGA1-IC,TBD!!!F127!DDR2_DQS_DP(1)!!!!
S!M_J_DQS_DP<2>!U2D1!W70!@baseboard_fab2_lib.baseboard_fab2(sch_1):page59_i172@chpset_lib.skx_ext_b(chips)!SKX_EXT_B_BGA1-IC,TBD!!!F127!DDR2_DQS_DP(2)!!!!
S!M_J_DQS_DP<3>!U2D1!AR66!@baseboard_fab2_lib.baseboard_fab2(sch_1):page59_i172@chpset_lib.skx_ext_b(chips)!SKX_EXT_B_BGA1-IC,TBD!!!F127!DDR2_DQS_DP(3)!!!!
S!M_J_DQS_DP<4>!U2D1!Y39!@baseboard_fab2_lib.baseboard_fab2(sch_1):page59_i172@chpset_lib.skx_ext_b(chips)!SKX_EXT_B_BGA1-IC,TBD!!!F127!DDR2_DQS_DP(4)!!!!
S!M_J_DQS_DP<5>!U2D1!Y33!@baseboard_fab2_lib.baseboard_fab2(sch_1):page59_i172@chpset_lib.skx_ext_b(chips)!SKX_EXT_B_BGA1-IC,TBD!!!F127!DDR2_DQS_DP(5)!!!!
S!M_J_DQS_DP<6>!U2D1!AG30!@baseboard_fab2_lib.baseboard_fab2(sch_1):page59_i172@chpset_lib.skx_ext_b(chips)!SKX_EXT_B_BGA1-IC,TBD!!!F127!DDR2_DQS_DP(6)!!!!
S!M_J_DQS_DP<7>!U2D1!AG24!@baseboard_fab2_lib.baseboard_fab2(sch_1):page59_i172@chpset_lib.skx_ext_b(chips)!SKX_EXT_B_BGA1-IC,TBD!!!F127!DDR2_DQS_DP(7)!!!!
S!M_J_DQS_DP<8>!U2D1!AY71!@baseboard_fab2_lib.baseboard_fab2(sch_1):page59_i172@chpset_lib.skx_ext_b(chips)!SKX_EXT_B_BGA1-IC,TBD!!!F127!DDR2_DQS_DP(8)!!!!
S!M_J_DQS_DP<9>!U2D1!AN76!@baseboard_fab2_lib.baseboard_fab2(sch_1):page59_i172@chpset_lib.skx_ext_b(chips)!SKX_EXT_B_BGA1-IC,TBD!!!F127!DDR2_DQS_DP(9)!!!!
S!M_J_ECC<0>!U2D1!AU72!@baseboard_fab2_lib.baseboard_fab2(sch_1):page59_i172@chpset_lib.skx_ext_b(chips)!SKX_EXT_B_BGA1-IC,TBD!!!F127!DDR2_ECC(0)!!!!
S!M_J_ECC<1>!U2D1!BA72!@baseboard_fab2_lib.baseboard_fab2(sch_1):page59_i172@chpset_lib.skx_ext_b(chips)!SKX_EXT_B_BGA1-IC,TBD!!!F127!DDR2_ECC(1)!!!!
S!M_J_ECC<2>!U2D1!AV69!@baseboard_fab2_lib.baseboard_fab2(sch_1):page59_i172@chpset_lib.skx_ext_b(chips)!SKX_EXT_B_BGA1-IC,TBD!!!F127!DDR2_ECC(2)!!!!
S!M_J_ECC<3>!U2D1!AY69!@baseboard_fab2_lib.baseboard_fab2(sch_1):page59_i172@chpset_lib.skx_ext_b(chips)!SKX_EXT_B_BGA1-IC,TBD!!!F127!DDR2_ECC(3)!!!!
S!M_J_ECC<4>!U2D1!AV73!@baseboard_fab2_lib.baseboard_fab2(sch_1):page59_i172@chpset_lib.skx_ext_b(chips)!SKX_EXT_B_BGA1-IC,TBD!!!F127!DDR2_ECC(4)!!!!
S!M_J_ECC<5>!U2D1!AY73!@baseboard_fab2_lib.baseboard_fab2(sch_1):page59_i172@chpset_lib.skx_ext_b(chips)!SKX_EXT_B_BGA1-IC,TBD!!!F127!DDR2_ECC(5)!!!!
S!M_J_ECC<6>!U2D1!AU70!@baseboard_fab2_lib.baseboard_fab2(sch_1):page59_i172@chpset_lib.skx_ext_b(chips)!SKX_EXT_B_BGA1-IC,TBD!!!F127!DDR2_ECC(6)!!!!
S!M_J_ECC<7>!U2D1!BA70!@baseboard_fab2_lib.baseboard_fab2(sch_1):page59_i172@chpset_lib.skx_ext_b(chips)!SKX_EXT_B_BGA1-IC,TBD!!!F127!DDR2_ECC(7)!!!!
S!M_J_MA<0>!U2D1!AB53!@baseboard_fab2_lib.baseboard_fab2(sch_1):page59_i172@chpset_lib.skx_ext_b(chips)!SKX_EXT_B_BGA1-IC,TBD!!!F127!DDR2_MA(0)!!!!
S!M_J_MA<10>!U2D1!AD55!@baseboard_fab2_lib.baseboard_fab2(sch_1):page59_i172@chpset_lib.skx_ext_b(chips)!SKX_EXT_B_BGA1-IC,TBD!!!F127!DDR2_MA(10)!!!!
S!M_J_MA<11>!U2D1!AG60!@baseboard_fab2_lib.baseboard_fab2(sch_1):page59_i172@chpset_lib.skx_ext_b(chips)!SKX_EXT_B_BGA1-IC,TBD!!!F127!DDR2_MA(11)!!!!
S!M_J_MA<12>!U2D1!AG62!@baseboard_fab2_lib.baseboard_fab2(sch_1):page59_i172@chpset_lib.skx_ext_b(chips)!SKX_EXT_B_BGA1-IC,TBD!!!F127!DDR2_MA(12)!!!!
S!M_J_MA<13>!U2D1!AD53!@baseboard_fab2_lib.baseboard_fab2(sch_1):page59_i172@chpset_lib.skx_ext_b(chips)!SKX_EXT_B_BGA1-IC,TBD!!!F127!DDR2_MA(13)!!!!
S!M_J_MA<14>!U2D1!W50!@baseboard_fab2_lib.baseboard_fab2(sch_1):page59_i172@chpset_lib.skx_ext_b(chips)!SKX_EXT_B_BGA1-IC,TBD!!!F127!DDR2_MA(14)!!!!
S!M_J_MA<15>!U2D1!AE54!@baseboard_fab2_lib.baseboard_fab2(sch_1):page59_i172@chpset_lib.skx_ext_b(chips)!SKX_EXT_B_BGA1-IC,TBD!!!F127!DDR2_MA(15)!!!!
S!M_J_MA<16>!U2D1!AA52!@baseboard_fab2_lib.baseboard_fab2(sch_1):page59_i172@chpset_lib.skx_ext_b(chips)!SKX_EXT_B_BGA1-IC,TBD!!!F127!DDR2_MA(16)!!!!
S!M_J_MA<17>!U2D1!AC46!@baseboard_fab2_lib.baseboard_fab2(sch_1):page59_i172@chpset_lib.skx_ext_b(chips)!SKX_EXT_B_BGA1-IC,TBD!!!F127!DDR2_MA(17)!!!!
S!M_J_MA<1>!U2D1!AE58!@baseboard_fab2_lib.baseboard_fab2(sch_1):page59_i172@chpset_lib.skx_ext_b(chips)!SKX_EXT_B_BGA1-IC,TBD!!!F127!DDR2_MA(1)!!!!
S!M_J_MA<2>!U2D1!AD57!@baseboard_fab2_lib.baseboard_fab2(sch_1):page59_i172@chpset_lib.skx_ext_b(chips)!SKX_EXT_B_BGA1-IC,TBD!!!F127!DDR2_MA(2)!!!!
S!M_J_MA<3>!U2D1!W58!@baseboard_fab2_lib.baseboard_fab2(sch_1):page59_i172@chpset_lib.skx_ext_b(chips)!SKX_EXT_B_BGA1-IC,TBD!!!F127!DDR2_MA(3)!!!!
S!M_J_MA<4>!U2D1!AA58!@baseboard_fab2_lib.baseboard_fab2(sch_1):page59_i172@chpset_lib.skx_ext_b(chips)!SKX_EXT_B_BGA1-IC,TBD!!!F127!DDR2_MA(4)!!!!
S!M_J_MA<5>!U2D1!V59!@baseboard_fab2_lib.baseboard_fab2(sch_1):page59_i172@chpset_lib.skx_ext_b(chips)!SKX_EXT_B_BGA1-IC,TBD!!!F127!DDR2_MA(5)!!!!
S!M_J_MA<6>!U2D1!AB59!@baseboard_fab2_lib.baseboard_fab2(sch_1):page59_i172@chpset_lib.skx_ext_b(chips)!SKX_EXT_B_BGA1-IC,TBD!!!F127!DDR2_MA(6)!!!!
S!M_J_MA<7>!U2D1!AE60!@baseboard_fab2_lib.baseboard_fab2(sch_1):page59_i172@chpset_lib.skx_ext_b(chips)!SKX_EXT_B_BGA1-IC,TBD!!!F127!DDR2_MA(7)!!!!
S!M_J_MA<8>!U2D1!AD59!@baseboard_fab2_lib.baseboard_fab2(sch_1):page59_i172@chpset_lib.skx_ext_b(chips)!SKX_EXT_B_BGA1-IC,TBD!!!F127!DDR2_MA(8)!!!!
S!M_J_MA<9>!U2D1!AG58!@baseboard_fab2_lib.baseboard_fab2(sch_1):page59_i172@chpset_lib.skx_ext_b(chips)!SKX_EXT_B_BGA1-IC,TBD!!!F127!DDR2_MA(9)!!!!
S!M_J_ODT<0>!U2D1!AA50!@baseboard_fab2_lib.baseboard_fab2(sch_1):page59_i172@chpset_lib.skx_ext_b(chips)!SKX_EXT_B_BGA1-IC,TBD!!!F127!DDR2_ODT(0)!!!!
S!M_J_ODT<1>!U2D1!AA48!@baseboard_fab2_lib.baseboard_fab2(sch_1):page59_i172@chpset_lib.skx_ext_b(chips)!SKX_EXT_B_BGA1-IC,TBD!!!F127!DDR2_ODT(1)!!!!
S!M_J_ODT<2>!U2D1!V49!@baseboard_fab2_lib.baseboard_fab2(sch_1):page59_i172@chpset_lib.skx_ext_b(chips)!SKX_EXT_B_BGA1-IC,TBD!!!F127!DDR2_ODT(2)!!!!
S!M_J_ODT<3>!U2D1!AB47!@baseboard_fab2_lib.baseboard_fab2(sch_1):page59_i172@chpset_lib.skx_ext_b(chips)!SKX_EXT_B_BGA1-IC,TBD!!!F127!DDR2_ODT(3)!!!!
S!M_J_PAR!U2D1!V53!@baseboard_fab2_lib.baseboard_fab2(sch_1):page59_i172@chpset_lib.skx_ext_b(chips)!SKX_EXT_B_BGA1-IC,TBD!!!F127!DDR2_PAR!!!!
S!M_K_ACT_N!U2D1!DW60!@baseboard_fab2_lib.baseboard_fab2(sch_1):page60_i172@chpset_lib.skx_ext_b(chips)!SKX_EXT_B_BGA1-IC,TBD!!!F126!DDR3_ACT_N!!!!
S!M_K_ALERT_N!U2D1!ED63!@baseboard_fab2_lib.baseboard_fab2(sch_1):page60_i172@chpset_lib.skx_ext_b(chips)!SKX_EXT_B_BGA1-IC,TBD!!!F126!DDR3_ALERT_N!!!!
S!M_K_BA<0>!U2D1!EE52!@baseboard_fab2_lib.baseboard_fab2(sch_1):page60_i172@chpset_lib.skx_ext_b(chips)!SKX_EXT_B_BGA1-IC,TBD!!!F126!DDR3_BA(0)!!!!
S!M_K_BA<1>!U2D1!EA54!@baseboard_fab2_lib.baseboard_fab2(sch_1):page60_i172@chpset_lib.skx_ext_b(chips)!SKX_EXT_B_BGA1-IC,TBD!!!F126!DDR3_BA(1)!!!!
S!M_K_BG<0>!U2D1!ED61!@baseboard_fab2_lib.baseboard_fab2(sch_1):page60_i172@chpset_lib.skx_ext_b(chips)!SKX_EXT_B_BGA1-IC,TBD!!!F126!DDR3_BG(0)!!!!
S!M_K_BG<1>!U2D1!DW62!@baseboard_fab2_lib.baseboard_fab2(sch_1):page60_i172@chpset_lib.skx_ext_b(chips)!SKX_EXT_B_BGA1-IC,TBD!!!F126!DDR3_BG(1)!!!!
S!M_K_C<2>!U2D1!DV47!@baseboard_fab2_lib.baseboard_fab2(sch_1):page60_i172@chpset_lib.skx_ext_b(chips)!SKX_EXT_B_BGA1-IC,TBD!!!F126!DDR3_CID(2)!!!!
S!M_K_CKE<0>!U2D1!EE62!@baseboard_fab2_lib.baseboard_fab2(sch_1):page60_i172@chpset_lib.skx_ext_b(chips)!SKX_EXT_B_BGA1-IC,TBD!!!F126!DDR3_CKE(0)!!!!
S!M_K_CKE<1>!U2D1!EF63!@baseboard_fab2_lib.baseboard_fab2(sch_1):page60_i172@chpset_lib.skx_ext_b(chips)!SKX_EXT_B_BGA1-IC,TBD!!!F126!DDR3_CKE(1)!!!!
S!M_K_CKE<2>!U2D1!EA62!@baseboard_fab2_lib.baseboard_fab2(sch_1):page60_i172@chpset_lib.skx_ext_b(chips)!SKX_EXT_B_BGA1-IC,TBD!!!F126!DDR3_CKE(2)!!!!
S!M_K_CKE<3>!U2D1!EB63!@baseboard_fab2_lib.baseboard_fab2(sch_1):page60_i172@chpset_lib.skx_ext_b(chips)!SKX_EXT_B_BGA1-IC,TBD!!!F126!DDR3_CKE(3)!!!!
S!M_K_CLK_DN<0>!U2D1!ED55!@baseboard_fab2_lib.baseboard_fab2(sch_1):page60_i172@chpset_lib.skx_ext_b(chips)!SKX_EXT_B_BGA1-IC,TBD!!!F126!DDR3_CLK_DN(0)!!!!
S!M_K_CLK_DN<2>!U2D1!DW56!@baseboard_fab2_lib.baseboard_fab2(sch_1):page60_i172@chpset_lib.skx_ext_b(chips)!SKX_EXT_B_BGA1-IC,TBD!!!F126!DDR3_CLK_DN(2)!!!!
S!M_K_CLK_DN<1>!U2D1!EF55!@baseboard_fab2_lib.baseboard_fab2(sch_1):page60_i172@chpset_lib.skx_ext_b(chips)!SKX_EXT_B_BGA1-IC,TBD!!!F126!DDR3_CLK_DN(1)!!!!
S!M_K_CLK_DN<3>!U2D1!EF57!@baseboard_fab2_lib.baseboard_fab2(sch_1):page60_i172@chpset_lib.skx_ext_b(chips)!SKX_EXT_B_BGA1-IC,TBD!!!F126!DDR3_CLK_DN(3)!!!!
S!M_K_CLK_DP<0>!U2D1!EB55!@baseboard_fab2_lib.baseboard_fab2(sch_1):page60_i172@chpset_lib.skx_ext_b(chips)!SKX_EXT_B_BGA1-IC,TBD!!!F126!DDR3_CLK_DP(0)!!!!
S!M_K_CLK_DP<2>!U2D1!EA56!@baseboard_fab2_lib.baseboard_fab2(sch_1):page60_i172@chpset_lib.skx_ext_b(chips)!SKX_EXT_B_BGA1-IC,TBD!!!F126!DDR3_CLK_DP(2)!!!!
S!M_K_CLK_DP<1>!U2D1!EE54!@baseboard_fab2_lib.baseboard_fab2(sch_1):page60_i172@chpset_lib.skx_ext_b(chips)!SKX_EXT_B_BGA1-IC,TBD!!!F126!DDR3_CLK_DP(1)!!!!
S!M_K_CLK_DP<3>!U2D1!EE56!@baseboard_fab2_lib.baseboard_fab2(sch_1):page60_i172@chpset_lib.skx_ext_b(chips)!SKX_EXT_B_BGA1-IC,TBD!!!F126!DDR3_CLK_DP(3)!!!!
S!M_K_CS_N<0>!U2D1!EF51!@baseboard_fab2_lib.baseboard_fab2(sch_1):page60_i172@chpset_lib.skx_ext_b(chips)!SKX_EXT_B_BGA1-IC,TBD!!!F126!DDR3_CS_N(0)!!!!
S!M_K_CS_N<1>!U2D1!ED49!@baseboard_fab2_lib.baseboard_fab2(sch_1):page60_i172@chpset_lib.skx_ext_b(chips)!SKX_EXT_B_BGA1-IC,TBD!!!F126!DDR3_CS_N(1)!!!!
S!M_K_CS_N<2>!U2D1!ED47!@baseboard_fab2_lib.baseboard_fab2(sch_1):page60_i172@chpset_lib.skx_ext_b(chips)!SKX_EXT_B_BGA1-IC,TBD!!!F126!DDR3_CS_N(2)!!!!
S!M_K_CS_N<3>!U2D1!EB47!@baseboard_fab2_lib.baseboard_fab2(sch_1):page60_i172@chpset_lib.skx_ext_b(chips)!SKX_EXT_B_BGA1-IC,TBD!!!F126!DDR3_CS_N(3)!!!!
S!M_K_CS_N<4>!U2D1!EB51!@baseboard_fab2_lib.baseboard_fab2(sch_1):page60_i172@chpset_lib.skx_ext_b(chips)!SKX_EXT_B_BGA1-IC,TBD!!!F126!DDR3_CS_N(4)!!!!
S!M_K_CS_N<5>!U2D1!EB49!@baseboard_fab2_lib.baseboard_fab2(sch_1):page60_i172@chpset_lib.skx_ext_b(chips)!SKX_EXT_B_BGA1-IC,TBD!!!F126!DDR3_CS_N(5)!!!!
S!M_K_CS_N<6>!U2D1!DV45!@baseboard_fab2_lib.baseboard_fab2(sch_1):page60_i172@chpset_lib.skx_ext_b(chips)!SKX_EXT_B_BGA1-IC,TBD!!!F126!DDR3_CS_N(6)!!!!
S!M_K_CS_N<7>!U2D1!EB45!@baseboard_fab2_lib.baseboard_fab2(sch_1):page60_i172@chpset_lib.skx_ext_b(chips)!SKX_EXT_B_BGA1-IC,TBD!!!F126!DDR3_CS_N(7)!!!!
S!M_K_DQ<0>!U2D1!CN84!@baseboard_fab2_lib.baseboard_fab2(sch_1):page60_i172@chpset_lib.skx_ext_b(chips)!SKX_EXT_B_BGA1-IC,TBD!!!F126!DDR3_DQ(0)!!!!
S!M_K_DQ<10>!U2D1!DV83!@baseboard_fab2_lib.baseboard_fab2(sch_1):page60_i172@chpset_lib.skx_ext_b(chips)!SKX_EXT_B_BGA1-IC,TBD!!!F126!DDR3_DQ(10)!!!!
S!M_K_DQ<11>!U2D1!DY83!@baseboard_fab2_lib.baseboard_fab2(sch_1):page60_i172@chpset_lib.skx_ext_b(chips)!SKX_EXT_B_BGA1-IC,TBD!!!F126!DDR3_DQ(11)!!!!
S!M_K_DQ<12>!U2D1!DD85!@baseboard_fab2_lib.baseboard_fab2(sch_1):page60_i172@chpset_lib.skx_ext_b(chips)!SKX_EXT_B_BGA1-IC,TBD!!!F126!DDR3_DQ(12)!!!!
S!M_K_DQ<13>!U2D1!DE84!@baseboard_fab2_lib.baseboard_fab2(sch_1):page60_i172@chpset_lib.skx_ext_b(chips)!SKX_EXT_B_BGA1-IC,TBD!!!F126!DDR3_DQ(13)!!!!
S!M_K_DQ<14>!U2D1!DR84!@baseboard_fab2_lib.baseboard_fab2(sch_1):page60_i172@chpset_lib.skx_ext_b(chips)!SKX_EXT_B_BGA1-IC,TBD!!!F126!DDR3_DQ(14)!!!!
S!M_K_DQ<15>!U2D1!DV85!@baseboard_fab2_lib.baseboard_fab2(sch_1):page60_i172@chpset_lib.skx_ext_b(chips)!SKX_EXT_B_BGA1-IC,TBD!!!F126!DDR3_DQ(15)!!!!
S!M_K_DQ<16>!U2D1!DM79!@baseboard_fab2_lib.baseboard_fab2(sch_1):page60_i172@chpset_lib.skx_ext_b(chips)!SKX_EXT_B_BGA1-IC,TBD!!!F126!DDR3_DQ(16)!!!!
S!M_K_DQ<17>!U2D1!DK81!@baseboard_fab2_lib.baseboard_fab2(sch_1):page60_i172@chpset_lib.skx_ext_b(chips)!SKX_EXT_B_BGA1-IC,TBD!!!F126!DDR3_DQ(17)!!!!
S!M_K_DQ<18>!U2D1!DT81!@baseboard_fab2_lib.baseboard_fab2(sch_1):page60_i172@chpset_lib.skx_ext_b(chips)!SKX_EXT_B_BGA1-IC,TBD!!!F126!DDR3_DQ(18)!!!!
S!M_K_DQ<19>!U2D1!DR82!@baseboard_fab2_lib.baseboard_fab2(sch_1):page60_i172@chpset_lib.skx_ext_b(chips)!SKX_EXT_B_BGA1-IC,TBD!!!F126!DDR3_DQ(19)!!!!
S!M_K_DQ<1>!U2D1!CN86!@baseboard_fab2_lib.baseboard_fab2(sch_1):page60_i172@chpset_lib.skx_ext_b(chips)!SKX_EXT_B_BGA1-IC,TBD!!!F126!DDR3_DQ(1)!!!!
S!M_K_DQ<20>!U2D1!DK79!@baseboard_fab2_lib.baseboard_fab2(sch_1):page60_i172@chpset_lib.skx_ext_b(chips)!SKX_EXT_B_BGA1-IC,TBD!!!F126!DDR3_DQ(20)!!!!
S!M_K_DQ<21>!U2D1!DJ80!@baseboard_fab2_lib.baseboard_fab2(sch_1):page60_i172@chpset_lib.skx_ext_b(chips)!SKX_EXT_B_BGA1-IC,TBD!!!F126!DDR3_DQ(21)!!!!
S!M_K_DQ<22>!U2D1!DR80!@baseboard_fab2_lib.baseboard_fab2(sch_1):page60_i172@chpset_lib.skx_ext_b(chips)!SKX_EXT_B_BGA1-IC,TBD!!!F126!DDR3_DQ(22)!!!!
S!M_K_DQ<23>!U2D1!DN82!@baseboard_fab2_lib.baseboard_fab2(sch_1):page60_i172@chpset_lib.skx_ext_b(chips)!SKX_EXT_B_BGA1-IC,TBD!!!F126!DDR3_DQ(23)!!!!
S!M_K_DQ<24>!U2D1!DN76!@baseboard_fab2_lib.baseboard_fab2(sch_1):page60_i172@chpset_lib.skx_ext_b(chips)!SKX_EXT_B_BGA1-IC,TBD!!!F126!DDR3_DQ(24)!!!!
S!M_K_DQ<25>!U2D1!DU76!@baseboard_fab2_lib.baseboard_fab2(sch_1):page60_i172@chpset_lib.skx_ext_b(chips)!SKX_EXT_B_BGA1-IC,TBD!!!F126!DDR3_DQ(25)!!!!
S!M_K_DQ<26>!U2D1!DP73!@baseboard_fab2_lib.baseboard_fab2(sch_1):page60_i172@chpset_lib.skx_ext_b(chips)!SKX_EXT_B_BGA1-IC,TBD!!!F126!DDR3_DQ(26)!!!!
S!M_K_DQ<27>!U2D1!DT73!@baseboard_fab2_lib.baseboard_fab2(sch_1):page60_i172@chpset_lib.skx_ext_b(chips)!SKX_EXT_B_BGA1-IC,TBD!!!F126!DDR3_DQ(27)!!!!
S!M_K_DQ<28>!U2D1!DP77!@baseboard_fab2_lib.baseboard_fab2(sch_1):page60_i172@chpset_lib.skx_ext_b(chips)!SKX_EXT_B_BGA1-IC,TBD!!!F126!DDR3_DQ(28)!!!!
S!M_K_DQ<29>!U2D1!DT77!@baseboard_fab2_lib.baseboard_fab2(sch_1):page60_i172@chpset_lib.skx_ext_b(chips)!SKX_EXT_B_BGA1-IC,TBD!!!F126!DDR3_DQ(29)!!!!
S!M_K_DQ<2>!U2D1!DA86!@baseboard_fab2_lib.baseboard_fab2(sch_1):page60_i172@chpset_lib.skx_ext_b(chips)!SKX_EXT_B_BGA1-IC,TBD!!!F126!DDR3_DQ(2)!!!!
S!M_K_DQ<30>!U2D1!DN74!@baseboard_fab2_lib.baseboard_fab2(sch_1):page60_i172@chpset_lib.skx_ext_b(chips)!SKX_EXT_B_BGA1-IC,TBD!!!F126!DDR3_DQ(30)!!!!
S!M_K_DQ<31>!U2D1!DU74!@baseboard_fab2_lib.baseboard_fab2(sch_1):page60_i172@chpset_lib.skx_ext_b(chips)!SKX_EXT_B_BGA1-IC,TBD!!!F126!DDR3_DQ(31)!!!!
S!M_K_DQ<32>!U2D1!EC40!@baseboard_fab2_lib.baseboard_fab2(sch_1):page60_i172@chpset_lib.skx_ext_b(chips)!SKX_EXT_B_BGA1-IC,TBD!!!F126!DDR3_DQ(32)!!!!
S!M_K_DQ<33>!U2D1!ED39!@baseboard_fab2_lib.baseboard_fab2(sch_1):page60_i172@chpset_lib.skx_ext_b(chips)!SKX_EXT_B_BGA1-IC,TBD!!!F126!DDR3_DQ(33)!!!!
S!M_K_DQ<34>!U2D1!EA36!@baseboard_fab2_lib.baseboard_fab2(sch_1):page60_i172@chpset_lib.skx_ext_b(chips)!SKX_EXT_B_BGA1-IC,TBD!!!F126!DDR3_DQ(34)!!!!
S!M_K_DQ<35>!U2D1!EC36!@baseboard_fab2_lib.baseboard_fab2(sch_1):page60_i172@chpset_lib.skx_ext_b(chips)!SKX_EXT_B_BGA1-IC,TBD!!!F126!DDR3_DQ(35)!!!!
S!M_K_DQ<36>!U2D1!DY39!@baseboard_fab2_lib.baseboard_fab2(sch_1):page60_i172@chpset_lib.skx_ext_b(chips)!SKX_EXT_B_BGA1-IC,TBD!!!F126!DDR3_DQ(36)!!!!
S!M_K_DQ<37>!U2D1!EA40!@baseboard_fab2_lib.baseboard_fab2(sch_1):page60_i172@chpset_lib.skx_ext_b(chips)!SKX_EXT_B_BGA1-IC,TBD!!!F126!DDR3_DQ(37)!!!!
S!M_K_DQ<38>!U2D1!DY37!@baseboard_fab2_lib.baseboard_fab2(sch_1):page60_i172@chpset_lib.skx_ext_b(chips)!SKX_EXT_B_BGA1-IC,TBD!!!F126!DDR3_DQ(38)!!!!
S!M_K_DQ<39>!U2D1!ED37!@baseboard_fab2_lib.baseboard_fab2(sch_1):page60_i172@chpset_lib.skx_ext_b(chips)!SKX_EXT_B_BGA1-IC,TBD!!!F126!DDR3_DQ(39)!!!!
S!M_K_DQ<3>!U2D1!DA84!@baseboard_fab2_lib.baseboard_fab2(sch_1):page60_i172@chpset_lib.skx_ext_b(chips)!SKX_EXT_B_BGA1-IC,TBD!!!F126!DDR3_DQ(3)!!!!
S!M_K_DQ<40>!U2D1!DN36!@baseboard_fab2_lib.baseboard_fab2(sch_1):page60_i172@chpset_lib.skx_ext_b(chips)!SKX_EXT_B_BGA1-IC,TBD!!!F126!DDR3_DQ(40)!!!!
S!M_K_DQ<41>!U2D1!DU36!@baseboard_fab2_lib.baseboard_fab2(sch_1):page60_i172@chpset_lib.skx_ext_b(chips)!SKX_EXT_B_BGA1-IC,TBD!!!F126!DDR3_DQ(41)!!!!
S!M_K_DQ<42>!U2D1!DP33!@baseboard_fab2_lib.baseboard_fab2(sch_1):page60_i172@chpset_lib.skx_ext_b(chips)!SKX_EXT_B_BGA1-IC,TBD!!!F126!DDR3_DQ(42)!!!!
S!M_K_DQ<43>!U2D1!DT33!@baseboard_fab2_lib.baseboard_fab2(sch_1):page60_i172@chpset_lib.skx_ext_b(chips)!SKX_EXT_B_BGA1-IC,TBD!!!F126!DDR3_DQ(43)!!!!
S!M_K_DQ<44>!U2D1!DP37!@baseboard_fab2_lib.baseboard_fab2(sch_1):page60_i172@chpset_lib.skx_ext_b(chips)!SKX_EXT_B_BGA1-IC,TBD!!!F126!DDR3_DQ(44)!!!!
S!M_K_DQ<45>!U2D1!DT37!@baseboard_fab2_lib.baseboard_fab2(sch_1):page60_i172@chpset_lib.skx_ext_b(chips)!SKX_EXT_B_BGA1-IC,TBD!!!F126!DDR3_DQ(45)!!!!
S!M_K_DQ<46>!U2D1!DN34!@baseboard_fab2_lib.baseboard_fab2(sch_1):page60_i172@chpset_lib.skx_ext_b(chips)!SKX_EXT_B_BGA1-IC,TBD!!!F126!DDR3_DQ(46)!!!!
S!M_K_DQ<47>!U2D1!DU34!@baseboard_fab2_lib.baseboard_fab2(sch_1):page60_i172@chpset_lib.skx_ext_b(chips)!SKX_EXT_B_BGA1-IC,TBD!!!F126!DDR3_DQ(47)!!!!
S!M_K_DQ<48>!U2D1!DN30!@baseboard_fab2_lib.baseboard_fab2(sch_1):page60_i172@chpset_lib.skx_ext_b(chips)!SKX_EXT_B_BGA1-IC,TBD!!!F126!DDR3_DQ(48)!!!!
S!M_K_DQ<49>!U2D1!DU30!@baseboard_fab2_lib.baseboard_fab2(sch_1):page60_i172@chpset_lib.skx_ext_b(chips)!SKX_EXT_B_BGA1-IC,TBD!!!F126!DDR3_DQ(49)!!!!
S!M_K_DQ<4>!U2D1!CL84!@baseboard_fab2_lib.baseboard_fab2(sch_1):page60_i172@chpset_lib.skx_ext_b(chips)!SKX_EXT_B_BGA1-IC,TBD!!!F126!DDR3_DQ(4)!!!!
S!M_K_DQ<50>!U2D1!DP27!@baseboard_fab2_lib.baseboard_fab2(sch_1):page60_i172@chpset_lib.skx_ext_b(chips)!SKX_EXT_B_BGA1-IC,TBD!!!F126!DDR3_DQ(50)!!!!
S!M_K_DQ<51>!U2D1!DT27!@baseboard_fab2_lib.baseboard_fab2(sch_1):page60_i172@chpset_lib.skx_ext_b(chips)!SKX_EXT_B_BGA1-IC,TBD!!!F126!DDR3_DQ(51)!!!!
S!M_K_DQ<52>!U2D1!DP31!@baseboard_fab2_lib.baseboard_fab2(sch_1):page60_i172@chpset_lib.skx_ext_b(chips)!SKX_EXT_B_BGA1-IC,TBD!!!F126!DDR3_DQ(52)!!!!
S!M_K_DQ<53>!U2D1!DT31!@baseboard_fab2_lib.baseboard_fab2(sch_1):page60_i172@chpset_lib.skx_ext_b(chips)!SKX_EXT_B_BGA1-IC,TBD!!!F126!DDR3_DQ(53)!!!!
S!M_K_DQ<54>!U2D1!DN28!@baseboard_fab2_lib.baseboard_fab2(sch_1):page60_i172@chpset_lib.skx_ext_b(chips)!SKX_EXT_B_BGA1-IC,TBD!!!F126!DDR3_DQ(54)!!!!
S!M_K_DQ<55>!U2D1!DU28!@baseboard_fab2_lib.baseboard_fab2(sch_1):page60_i172@chpset_lib.skx_ext_b(chips)!SKX_EXT_B_BGA1-IC,TBD!!!F126!DDR3_DQ(55)!!!!
S!M_K_DQ<56>!U2D1!DN24!@baseboard_fab2_lib.baseboard_fab2(sch_1):page60_i172@chpset_lib.skx_ext_b(chips)!SKX_EXT_B_BGA1-IC,TBD!!!F126!DDR3_DQ(56)!!!!
S!M_K_DQ<57>!U2D1!DU24!@baseboard_fab2_lib.baseboard_fab2(sch_1):page60_i172@chpset_lib.skx_ext_b(chips)!SKX_EXT_B_BGA1-IC,TBD!!!F126!DDR3_DQ(57)!!!!
S!M_K_DQ<59>!U2D1!EB21!@baseboard_fab2_lib.baseboard_fab2(sch_1):page60_i172@chpset_lib.skx_ext_b(chips)!SKX_EXT_B_BGA1-IC,TBD!!!F126!DDR3_DQ(59)!!!!
S!M_K_DQ<58>!U2D1!DY21!@baseboard_fab2_lib.baseboard_fab2(sch_1):page60_i172@chpset_lib.skx_ext_b(chips)!SKX_EXT_B_BGA1-IC,TBD!!!F126!DDR3_DQ(58)!!!!
S!M_K_DQ<5>!U2D1!CL86!@baseboard_fab2_lib.baseboard_fab2(sch_1):page60_i172@chpset_lib.skx_ext_b(chips)!SKX_EXT_B_BGA1-IC,TBD!!!F126!DDR3_DQ(5)!!!!
S!M_K_DQ<60>!U2D1!DP25!@baseboard_fab2_lib.baseboard_fab2(sch_1):page60_i172@chpset_lib.skx_ext_b(chips)!SKX_EXT_B_BGA1-IC,TBD!!!F126!DDR3_DQ(60)!!!!
S!M_K_DQ<61>!U2D1!DT25!@baseboard_fab2_lib.baseboard_fab2(sch_1):page60_i172@chpset_lib.skx_ext_b(chips)!SKX_EXT_B_BGA1-IC,TBD!!!F126!DDR3_DQ(61)!!!!
S!M_K_DQ<62>!U2D1!EC22!@baseboard_fab2_lib.baseboard_fab2(sch_1):page60_i172@chpset_lib.skx_ext_b(chips)!SKX_EXT_B_BGA1-IC,TBD!!!F126!DDR3_DQ(62)!!!!
S!M_K_DQ<63>!U2D1!DW22!@baseboard_fab2_lib.baseboard_fab2(sch_1):page60_i172@chpset_lib.skx_ext_b(chips)!SKX_EXT_B_BGA1-IC,TBD!!!F126!DDR3_DQ(63)!!!!
S!M_K_DQ<6>!U2D1!CW86!@baseboard_fab2_lib.baseboard_fab2(sch_1):page60_i172@chpset_lib.skx_ext_b(chips)!SKX_EXT_B_BGA1-IC,TBD!!!F126!DDR3_DQ(6)!!!!
S!M_K_DQ<7>!U2D1!CW84!@baseboard_fab2_lib.baseboard_fab2(sch_1):page60_i172@chpset_lib.skx_ext_b(chips)!SKX_EXT_B_BGA1-IC,TBD!!!F126!DDR3_DQ(7)!!!!
S!M_K_DQ<8>!U2D1!DG84!@baseboard_fab2_lib.baseboard_fab2(sch_1):page60_i172@chpset_lib.skx_ext_b(chips)!SKX_EXT_B_BGA1-IC,TBD!!!F126!DDR3_DQ(8)!!!!
S!M_K_DQ<9>!U2D1!DH85!@baseboard_fab2_lib.baseboard_fab2(sch_1):page60_i172@chpset_lib.skx_ext_b(chips)!SKX_EXT_B_BGA1-IC,TBD!!!F126!DDR3_DQ(9)!!!!
S!M_K_DQS_DN<0>!U2D1!CU84!@baseboard_fab2_lib.baseboard_fab2(sch_1):page60_i172@chpset_lib.skx_ext_b(chips)!SKX_EXT_B_BGA1-IC,TBD!!!F126!DDR3_DQS_DN(0)!!!!
S!M_K_DQS_DN<10>!U2D1!DM85!@baseboard_fab2_lib.baseboard_fab2(sch_1):page60_i172@chpset_lib.skx_ext_b(chips)!SKX_EXT_B_BGA1-IC,TBD!!!F126!DDR3_DQS_DN(10)!!!!
S!M_K_DQS_DN<11>!U2D1!DN80!@baseboard_fab2_lib.baseboard_fab2(sch_1):page60_i172@chpset_lib.skx_ext_b(chips)!SKX_EXT_B_BGA1-IC,TBD!!!F126!DDR3_DQS_DN(11)!!!!
S!M_K_DQS_DN<12>!U2D1!DP75!@baseboard_fab2_lib.baseboard_fab2(sch_1):page60_i172@chpset_lib.skx_ext_b(chips)!SKX_EXT_B_BGA1-IC,TBD!!!F126!DDR3_DQS_DN(12)!!!!
S!M_K_DQS_DN<13>!U2D1!EA38!@baseboard_fab2_lib.baseboard_fab2(sch_1):page60_i172@chpset_lib.skx_ext_b(chips)!SKX_EXT_B_BGA1-IC,TBD!!!F126!DDR3_DQS_DN(13)!!!!
S!M_K_DQS_DN<14>!U2D1!DP35!@baseboard_fab2_lib.baseboard_fab2(sch_1):page60_i172@chpset_lib.skx_ext_b(chips)!SKX_EXT_B_BGA1-IC,TBD!!!F126!DDR3_DQS_DN(14)!!!!
S!M_K_DQS_DN<15>!U2D1!DM29!@baseboard_fab2_lib.baseboard_fab2(sch_1):page60_i172@chpset_lib.skx_ext_b(chips)!SKX_EXT_B_BGA1-IC,TBD!!!F126!DDR3_DQS_DN(15)!!!!
S!M_K_DQS_DN<16>!U2D1!DM23!@baseboard_fab2_lib.baseboard_fab2(sch_1):page60_i172@chpset_lib.skx_ext_b(chips)!SKX_EXT_B_BGA1-IC,TBD!!!F126!DDR3_DQS_DN(16)!!!!
S!M_K_DQS_DN<17>!U2D1!DB67!@baseboard_fab2_lib.baseboard_fab2(sch_1):page60_i172@chpset_lib.skx_ext_b(chips)!SKX_EXT_B_BGA1-IC,TBD!!!F126!DDR3_DQS_DN(17)!!!!
S!M_K_DQS_DN<1>!U2D1!DN84!@baseboard_fab2_lib.baseboard_fab2(sch_1):page60_i172@chpset_lib.skx_ext_b(chips)!SKX_EXT_B_BGA1-IC,TBD!!!F126!DDR3_DQS_DN(1)!!!!
S!M_K_DQS_DN<2>!U2D1!DL82!@baseboard_fab2_lib.baseboard_fab2(sch_1):page60_i172@chpset_lib.skx_ext_b(chips)!SKX_EXT_B_BGA1-IC,TBD!!!F126!DDR3_DQS_DN(2)!!!!
S!M_K_DQS_DN<3>!U2D1!DV75!@baseboard_fab2_lib.baseboard_fab2(sch_1):page60_i172@chpset_lib.skx_ext_b(chips)!SKX_EXT_B_BGA1-IC,TBD!!!F126!DDR3_DQS_DN(3)!!!!
S!M_K_DQS_DN<4>!U2D1!EE38!@baseboard_fab2_lib.baseboard_fab2(sch_1):page60_i172@chpset_lib.skx_ext_b(chips)!SKX_EXT_B_BGA1-IC,TBD!!!F126!DDR3_DQS_DN(4)!!!!
S!M_K_DQS_DN<5>!U2D1!DV35!@baseboard_fab2_lib.baseboard_fab2(sch_1):page60_i172@chpset_lib.skx_ext_b(chips)!SKX_EXT_B_BGA1-IC,TBD!!!F126!DDR3_DQS_DN(5)!!!!
S!M_K_DQS_DN<6>!U2D1!DV29!@baseboard_fab2_lib.baseboard_fab2(sch_1):page60_i172@chpset_lib.skx_ext_b(chips)!SKX_EXT_B_BGA1-IC,TBD!!!F126!DDR3_DQS_DN(6)!!!!
S!M_K_DQS_DN<7>!U2D1!DV23!@baseboard_fab2_lib.baseboard_fab2(sch_1):page60_i172@chpset_lib.skx_ext_b(chips)!SKX_EXT_B_BGA1-IC,TBD!!!F126!DDR3_DQS_DN(7)!!!!
S!M_K_DQS_DN<8>!U2D1!DF67!@baseboard_fab2_lib.baseboard_fab2(sch_1):page60_i172@chpset_lib.skx_ext_b(chips)!SKX_EXT_B_BGA1-IC,TBD!!!F126!DDR3_DQS_DN(8)!!!!
S!M_K_DQS_DN<9>!U2D1!CR84!@baseboard_fab2_lib.baseboard_fab2(sch_1):page60_i172@chpset_lib.skx_ext_b(chips)!SKX_EXT_B_BGA1-IC,TBD!!!F126!DDR3_DQS_DN(9)!!!!
S!M_K_DQS_DP<0>!U2D1!CV85!@baseboard_fab2_lib.baseboard_fab2(sch_1):page60_i172@chpset_lib.skx_ext_b(chips)!SKX_EXT_B_BGA1-IC,TBD!!!F126!DDR3_DQS_DP(0)!!!!
S!M_K_DQS_DP<10>!U2D1!DL84!@baseboard_fab2_lib.baseboard_fab2(sch_1):page60_i172@chpset_lib.skx_ext_b(chips)!SKX_EXT_B_BGA1-IC,TBD!!!F126!DDR3_DQS_DP(10)!!!!
S!M_K_DQS_DP<11>!U2D1!DP79!@baseboard_fab2_lib.baseboard_fab2(sch_1):page60_i172@chpset_lib.skx_ext_b(chips)!SKX_EXT_B_BGA1-IC,TBD!!!F126!DDR3_DQS_DP(11)!!!!
S!M_K_DQS_DP<12>!U2D1!DM75!@baseboard_fab2_lib.baseboard_fab2(sch_1):page60_i172@chpset_lib.skx_ext_b(chips)!SKX_EXT_B_BGA1-IC,TBD!!!F126!DDR3_DQS_DP(12)!!!!
S!M_K_DQS_DP<13>!U2D1!DW38!@baseboard_fab2_lib.baseboard_fab2(sch_1):page60_i172@chpset_lib.skx_ext_b(chips)!SKX_EXT_B_BGA1-IC,TBD!!!F126!DDR3_DQS_DP(13)!!!!
S!M_K_DQS_DP<14>!U2D1!DM35!@baseboard_fab2_lib.baseboard_fab2(sch_1):page60_i172@chpset_lib.skx_ext_b(chips)!SKX_EXT_B_BGA1-IC,TBD!!!F126!DDR3_DQS_DP(14)!!!!
S!M_K_DQS_DP<15>!U2D1!DP29!@baseboard_fab2_lib.baseboard_fab2(sch_1):page60_i172@chpset_lib.skx_ext_b(chips)!SKX_EXT_B_BGA1-IC,TBD!!!F126!DDR3_DQS_DP(15)!!!!
S!M_K_DQS_DP<16>!U2D1!DP23!@baseboard_fab2_lib.baseboard_fab2(sch_1):page60_i172@chpset_lib.skx_ext_b(chips)!SKX_EXT_B_BGA1-IC,TBD!!!F126!DDR3_DQS_DP(16)!!!!
S!M_K_DQS_DP<17>!U2D1!CY67!@baseboard_fab2_lib.baseboard_fab2(sch_1):page60_i172@chpset_lib.skx_ext_b(chips)!SKX_EXT_B_BGA1-IC,TBD!!!F126!DDR3_DQS_DP(17)!!!!
S!M_K_DQS_DP<1>!U2D1!DP85!@baseboard_fab2_lib.baseboard_fab2(sch_1):page60_i172@chpset_lib.skx_ext_b(chips)!SKX_EXT_B_BGA1-IC,TBD!!!F126!DDR3_DQS_DP(1)!!!!
S!M_K_DQS_DP<2>!U2D1!DM81!@baseboard_fab2_lib.baseboard_fab2(sch_1):page60_i172@chpset_lib.skx_ext_b(chips)!SKX_EXT_B_BGA1-IC,TBD!!!F126!DDR3_DQS_DP(2)!!!!
S!M_K_DQS_DP<3>!U2D1!DT75!@baseboard_fab2_lib.baseboard_fab2(sch_1):page60_i172@chpset_lib.skx_ext_b(chips)!SKX_EXT_B_BGA1-IC,TBD!!!F126!DDR3_DQS_DP(3)!!!!
S!M_K_DQS_DP<4>!U2D1!EC38!@baseboard_fab2_lib.baseboard_fab2(sch_1):page60_i172@chpset_lib.skx_ext_b(chips)!SKX_EXT_B_BGA1-IC,TBD!!!F126!DDR3_DQS_DP(4)!!!!
S!M_K_DQS_DP<5>!U2D1!DT35!@baseboard_fab2_lib.baseboard_fab2(sch_1):page60_i172@chpset_lib.skx_ext_b(chips)!SKX_EXT_B_BGA1-IC,TBD!!!F126!DDR3_DQS_DP(5)!!!!
S!M_K_DQS_DP<6>!U2D1!DT29!@baseboard_fab2_lib.baseboard_fab2(sch_1):page60_i172@chpset_lib.skx_ext_b(chips)!SKX_EXT_B_BGA1-IC,TBD!!!F126!DDR3_DQS_DP(6)!!!!
S!M_K_DQS_DP<7>!U2D1!DT23!@baseboard_fab2_lib.baseboard_fab2(sch_1):page60_i172@chpset_lib.skx_ext_b(chips)!SKX_EXT_B_BGA1-IC,TBD!!!F126!DDR3_DQS_DP(7)!!!!
S!M_K_DQS_DP<8>!U2D1!DD67!@baseboard_fab2_lib.baseboard_fab2(sch_1):page60_i172@chpset_lib.skx_ext_b(chips)!SKX_EXT_B_BGA1-IC,TBD!!!F126!DDR3_DQS_DP(8)!!!!
S!M_K_DQS_DP<9>!U2D1!CP85!@baseboard_fab2_lib.baseboard_fab2(sch_1):page60_i172@chpset_lib.skx_ext_b(chips)!SKX_EXT_B_BGA1-IC,TBD!!!F126!DDR3_DQS_DP(9)!!!!
S!M_K_ECC<0>!U2D1!DA68!@baseboard_fab2_lib.baseboard_fab2(sch_1):page60_i172@chpset_lib.skx_ext_b(chips)!SKX_EXT_B_BGA1-IC,TBD!!!F126!DDR3_ECC(0)!!!!
S!M_K_ECC<1>!U2D1!DE68!@baseboard_fab2_lib.baseboard_fab2(sch_1):page60_i172@chpset_lib.skx_ext_b(chips)!SKX_EXT_B_BGA1-IC,TBD!!!F126!DDR3_ECC(1)!!!!
S!M_K_ECC<2>!U2D1!DB65!@baseboard_fab2_lib.baseboard_fab2(sch_1):page60_i172@chpset_lib.skx_ext_b(chips)!SKX_EXT_B_BGA1-IC,TBD!!!F126!DDR3_ECC(2)!!!!
S!M_K_ECC<3>!U2D1!DD65!@baseboard_fab2_lib.baseboard_fab2(sch_1):page60_i172@chpset_lib.skx_ext_b(chips)!SKX_EXT_B_BGA1-IC,TBD!!!F126!DDR3_ECC(3)!!!!
S!M_K_ECC<4>!U2D1!DB69!@baseboard_fab2_lib.baseboard_fab2(sch_1):page60_i172@chpset_lib.skx_ext_b(chips)!SKX_EXT_B_BGA1-IC,TBD!!!F126!DDR3_ECC(4)!!!!
S!M_K_ECC<5>!U2D1!DD69!@baseboard_fab2_lib.baseboard_fab2(sch_1):page60_i172@chpset_lib.skx_ext_b(chips)!SKX_EXT_B_BGA1-IC,TBD!!!F126!DDR3_ECC(5)!!!!
S!M_K_ECC<6>!U2D1!DA66!@baseboard_fab2_lib.baseboard_fab2(sch_1):page60_i172@chpset_lib.skx_ext_b(chips)!SKX_EXT_B_BGA1-IC,TBD!!!F126!DDR3_ECC(6)!!!!
S!M_K_ECC<7>!U2D1!DE66!@baseboard_fab2_lib.baseboard_fab2(sch_1):page60_i172@chpset_lib.skx_ext_b(chips)!SKX_EXT_B_BGA1-IC,TBD!!!F126!DDR3_ECC(7)!!!!
S!M_K_MA<0>!U2D1!EB53!@baseboard_fab2_lib.baseboard_fab2(sch_1):page60_i172@chpset_lib.skx_ext_b(chips)!SKX_EXT_B_BGA1-IC,TBD!!!F126!DDR3_MA(0)!!!!
S!M_K_MA<10>!U2D1!DW54!@baseboard_fab2_lib.baseboard_fab2(sch_1):page60_i172@chpset_lib.skx_ext_b(chips)!SKX_EXT_B_BGA1-IC,TBD!!!F126!DDR3_MA(10)!!!!
S!M_K_MA<11>!U2D1!EB61!@baseboard_fab2_lib.baseboard_fab2(sch_1):page60_i172@chpset_lib.skx_ext_b(chips)!SKX_EXT_B_BGA1-IC,TBD!!!F126!DDR3_MA(11)!!!!
S!M_K_MA<12>!U2D1!DT63!@baseboard_fab2_lib.baseboard_fab2(sch_1):page60_i172@chpset_lib.skx_ext_b(chips)!SKX_EXT_B_BGA1-IC,TBD!!!F126!DDR3_MA(12)!!!!
S!M_K_MA<13>!U2D1!DW48!@baseboard_fab2_lib.baseboard_fab2(sch_1):page60_i172@chpset_lib.skx_ext_b(chips)!SKX_EXT_B_BGA1-IC,TBD!!!F126!DDR3_MA(13)!!!!
S!M_K_MA<14>!U2D1!ED51!@baseboard_fab2_lib.baseboard_fab2(sch_1):page60_i172@chpset_lib.skx_ext_b(chips)!SKX_EXT_B_BGA1-IC,TBD!!!F126!DDR3_MA(14)!!!!
S!M_K_MA<15>!U2D1!DV49!@baseboard_fab2_lib.baseboard_fab2(sch_1):page60_i172@chpset_lib.skx_ext_b(chips)!SKX_EXT_B_BGA1-IC,TBD!!!F126!DDR3_MA(15)!!!!
S!M_K_MA<16>!U2D1!EA52!@baseboard_fab2_lib.baseboard_fab2(sch_1):page60_i172@chpset_lib.skx_ext_b(chips)!SKX_EXT_B_BGA1-IC,TBD!!!F126!DDR3_MA(16)!!!!
S!M_K_MA<17>!U2D1!EA46!@baseboard_fab2_lib.baseboard_fab2(sch_1):page60_i172@chpset_lib.skx_ext_b(chips)!SKX_EXT_B_BGA1-IC,TBD!!!F126!DDR3_MA(17)!!!!
S!M_K_MA<1>!U2D1!ED57!@baseboard_fab2_lib.baseboard_fab2(sch_1):page60_i172@chpset_lib.skx_ext_b(chips)!SKX_EXT_B_BGA1-IC,TBD!!!F126!DDR3_MA(1)!!!!
S!M_K_MA<2>!U2D1!EE58!@baseboard_fab2_lib.baseboard_fab2(sch_1):page60_i172@chpset_lib.skx_ext_b(chips)!SKX_EXT_B_BGA1-IC,TBD!!!F126!DDR3_MA(2)!!!!
S!M_K_MA<3>!U2D1!EB57!@baseboard_fab2_lib.baseboard_fab2(sch_1):page60_i172@chpset_lib.skx_ext_b(chips)!SKX_EXT_B_BGA1-IC,TBD!!!F126!DDR3_MA(3)!!!!
S!M_K_MA<4>!U2D1!ED59!@baseboard_fab2_lib.baseboard_fab2(sch_1):page60_i172@chpset_lib.skx_ext_b(chips)!SKX_EXT_B_BGA1-IC,TBD!!!F126!DDR3_MA(4)!!!!
S!M_K_MA<5>!U2D1!EA58!@baseboard_fab2_lib.baseboard_fab2(sch_1):page60_i172@chpset_lib.skx_ext_b(chips)!SKX_EXT_B_BGA1-IC,TBD!!!F126!DDR3_MA(5)!!!!
S!M_K_MA<6>!U2D1!EE60!@baseboard_fab2_lib.baseboard_fab2(sch_1):page60_i172@chpset_lib.skx_ext_b(chips)!SKX_EXT_B_BGA1-IC,TBD!!!F126!DDR3_MA(6)!!!!
S!M_K_MA<7>!U2D1!EA60!@baseboard_fab2_lib.baseboard_fab2(sch_1):page60_i172@chpset_lib.skx_ext_b(chips)!SKX_EXT_B_BGA1-IC,TBD!!!F126!DDR3_MA(7)!!!!
S!M_K_MA<8>!U2D1!EB59!@baseboard_fab2_lib.baseboard_fab2(sch_1):page60_i172@chpset_lib.skx_ext_b(chips)!SKX_EXT_B_BGA1-IC,TBD!!!F126!DDR3_MA(8)!!!!
S!M_K_MA<9>!U2D1!EF61!@baseboard_fab2_lib.baseboard_fab2(sch_1):page60_i172@chpset_lib.skx_ext_b(chips)!SKX_EXT_B_BGA1-IC,TBD!!!F126!DDR3_MA(9)!!!!
S!M_K_ODT<0>!U2D1!EE50!@baseboard_fab2_lib.baseboard_fab2(sch_1):page60_i172@chpset_lib.skx_ext_b(chips)!SKX_EXT_B_BGA1-IC,TBD!!!F126!DDR3_ODT(0)!!!!
S!M_K_ODT<1>!U2D1!EE48!@baseboard_fab2_lib.baseboard_fab2(sch_1):page60_i172@chpset_lib.skx_ext_b(chips)!SKX_EXT_B_BGA1-IC,TBD!!!F126!DDR3_ODT(1)!!!!
S!M_K_ODT<2>!U2D1!EA50!@baseboard_fab2_lib.baseboard_fab2(sch_1):page60_i172@chpset_lib.skx_ext_b(chips)!SKX_EXT_B_BGA1-IC,TBD!!!F126!DDR3_ODT(2)!!!!
S!M_K_ODT<3>!U2D1!EA48!@baseboard_fab2_lib.baseboard_fab2(sch_1):page60_i172@chpset_lib.skx_ext_b(chips)!SKX_EXT_B_BGA1-IC,TBD!!!F126!DDR3_ODT(3)!!!!
S!M_K_PAR!U2D1!ED53!@baseboard_fab2_lib.baseboard_fab2(sch_1):page60_i172@chpset_lib.skx_ext_b(chips)!SKX_EXT_B_BGA1-IC,TBD!!!F126!DDR3_PAR!!!!
S!M_L_ACT_N!U2D1!DR62!@baseboard_fab2_lib.baseboard_fab2(sch_1):page61_i172@chpset_lib.skx_ext_b(chips)!SKX_EXT_B_BGA1-IC,TBD!!!F125!DDR4_ACT_N!!!!
S!M_L_ALERT_N!U2D1!DT61!@baseboard_fab2_lib.baseboard_fab2(sch_1):page61_i172@chpset_lib.skx_ext_b(chips)!SKX_EXT_B_BGA1-IC,TBD!!!F125!DDR4_ALERT_N!!!!
S!M_L_BA<0>!U2D1!DM53!@baseboard_fab2_lib.baseboard_fab2(sch_1):page61_i172@chpset_lib.skx_ext_b(chips)!SKX_EXT_B_BGA1-IC,TBD!!!F125!DDR4_BA(0)!!!!
S!M_L_BA<1>!U2D1!DV55!@baseboard_fab2_lib.baseboard_fab2(sch_1):page61_i172@chpset_lib.skx_ext_b(chips)!SKX_EXT_B_BGA1-IC,TBD!!!F125!DDR4_BA(1)!!!!
S!M_L_BG<0>!U2D1!DJ62!@baseboard_fab2_lib.baseboard_fab2(sch_1):page61_i172@chpset_lib.skx_ext_b(chips)!SKX_EXT_B_BGA1-IC,TBD!!!F125!DDR4_BG(0)!!!!
S!M_L_BG<1>!U2D1!DM61!@baseboard_fab2_lib.baseboard_fab2(sch_1):page61_i172@chpset_lib.skx_ext_b(chips)!SKX_EXT_B_BGA1-IC,TBD!!!F125!DDR4_BG(1)!!!!
S!M_L_C<2>!U2D1!DT47!@baseboard_fab2_lib.baseboard_fab2(sch_1):page61_i172@chpset_lib.skx_ext_b(chips)!SKX_EXT_B_BGA1-IC,TBD!!!F125!DDR4_CID(2)!!!!
S!M_L_CKE<0>!U2D1!DM63!@baseboard_fab2_lib.baseboard_fab2(sch_1):page61_i172@chpset_lib.skx_ext_b(chips)!SKX_EXT_B_BGA1-IC,TBD!!!F125!DDR4_CKE(0)!!!!
S!M_L_CKE<1>!U2D1!DN64!@baseboard_fab2_lib.baseboard_fab2(sch_1):page61_i172@chpset_lib.skx_ext_b(chips)!SKX_EXT_B_BGA1-IC,TBD!!!F125!DDR4_CKE(1)!!!!
S!M_L_CKE<2>!U2D1!DL64!@baseboard_fab2_lib.baseboard_fab2(sch_1):page61_i172@chpset_lib.skx_ext_b(chips)!SKX_EXT_B_BGA1-IC,TBD!!!F125!DDR4_CKE(2)!!!!
S!M_L_CKE<3>!U2D1!DR64!@baseboard_fab2_lib.baseboard_fab2(sch_1):page61_i172@chpset_lib.skx_ext_b(chips)!SKX_EXT_B_BGA1-IC,TBD!!!F125!DDR4_CKE(3)!!!!
S!M_L_CLK_DN<0>!U2D1!DM55!@baseboard_fab2_lib.baseboard_fab2(sch_1):page61_i172@chpset_lib.skx_ext_b(chips)!SKX_EXT_B_BGA1-IC,TBD!!!F125!DDR4_CLK_DN(0)!!!!
S!M_L_CLK_DN<2>!U2D1!DM57!@baseboard_fab2_lib.baseboard_fab2(sch_1):page61_i172@chpset_lib.skx_ext_b(chips)!SKX_EXT_B_BGA1-IC,TBD!!!F125!DDR4_CLK_DN(2)!!!!
S!M_L_CLK_DN<1>!U2D1!DR54!@baseboard_fab2_lib.baseboard_fab2(sch_1):page61_i172@chpset_lib.skx_ext_b(chips)!SKX_EXT_B_BGA1-IC,TBD!!!F125!DDR4_CLK_DN(1)!!!!
S!M_L_CLK_DN<3>!U2D1!DT57!@baseboard_fab2_lib.baseboard_fab2(sch_1):page61_i172@chpset_lib.skx_ext_b(chips)!SKX_EXT_B_BGA1-IC,TBD!!!F125!DDR4_CLK_DN(3)!!!!
S!M_L_CLK_DP<0>!U2D1!DN54!@baseboard_fab2_lib.baseboard_fab2(sch_1):page61_i172@chpset_lib.skx_ext_b(chips)!SKX_EXT_B_BGA1-IC,TBD!!!F125!DDR4_CLK_DP(0)!!!!
S!M_L_CLK_DP<2>!U2D1!DN56!@baseboard_fab2_lib.baseboard_fab2(sch_1):page61_i172@chpset_lib.skx_ext_b(chips)!SKX_EXT_B_BGA1-IC,TBD!!!F125!DDR4_CLK_DP(2)!!!!
S!M_L_CLK_DP<1>!U2D1!DT53!@baseboard_fab2_lib.baseboard_fab2(sch_1):page61_i172@chpset_lib.skx_ext_b(chips)!SKX_EXT_B_BGA1-IC,TBD!!!F125!DDR4_CLK_DP(1)!!!!
S!M_L_CLK_DP<3>!U2D1!DR56!@baseboard_fab2_lib.baseboard_fab2(sch_1):page61_i172@chpset_lib.skx_ext_b(chips)!SKX_EXT_B_BGA1-IC,TBD!!!F125!DDR4_CLK_DP(3)!!!!
S!M_L_CS_N<0>!U2D1!DV51!@baseboard_fab2_lib.baseboard_fab2(sch_1):page61_i172@chpset_lib.skx_ext_b(chips)!SKX_EXT_B_BGA1-IC,TBD!!!F125!DDR4_CS_N(0)!!!!
S!M_L_CS_N<1>!U2D1!DN50!@baseboard_fab2_lib.baseboard_fab2(sch_1):page61_i172@chpset_lib.skx_ext_b(chips)!SKX_EXT_B_BGA1-IC,TBD!!!F125!DDR4_CS_N(1)!!!!
S!M_L_CS_N<2>!U2D1!DR46!@baseboard_fab2_lib.baseboard_fab2(sch_1):page61_i172@chpset_lib.skx_ext_b(chips)!SKX_EXT_B_BGA1-IC,TBD!!!F125!DDR4_CS_N(2)!!!!
S!M_L_CS_N<3>!U2D1!DK47!@baseboard_fab2_lib.baseboard_fab2(sch_1):page61_i172@chpset_lib.skx_ext_b(chips)!SKX_EXT_B_BGA1-IC,TBD!!!F125!DDR4_CS_N(3)!!!!
S!M_L_CS_N<4>!U2D1!DW50!@baseboard_fab2_lib.baseboard_fab2(sch_1):page61_i172@chpset_lib.skx_ext_b(chips)!SKX_EXT_B_BGA1-IC,TBD!!!F125!DDR4_CS_N(4)!!!!
S!M_L_CS_N<5>!U2D1!DM49!@baseboard_fab2_lib.baseboard_fab2(sch_1):page61_i172@chpset_lib.skx_ext_b(chips)!SKX_EXT_B_BGA1-IC,TBD!!!F125!DDR4_CS_N(5)!!!!
S!M_L_CS_N<6>!U2D1!DT45!@baseboard_fab2_lib.baseboard_fab2(sch_1):page61_i172@chpset_lib.skx_ext_b(chips)!SKX_EXT_B_BGA1-IC,TBD!!!F125!DDR4_CS_N(6)!!!!
S!M_L_CS_N<7>!U2D1!DN46!@baseboard_fab2_lib.baseboard_fab2(sch_1):page61_i172@chpset_lib.skx_ext_b(chips)!SKX_EXT_B_BGA1-IC,TBD!!!F125!DDR4_CS_N(7)!!!!
S!M_L_DQ<0>!U2D1!CM79!@baseboard_fab2_lib.baseboard_fab2(sch_1):page61_i172@chpset_lib.skx_ext_b(chips)!SKX_EXT_B_BGA1-IC,TBD!!!F125!DDR4_DQ(0)!!!!
S!M_L_DQ<10>!U2D1!DE80!@baseboard_fab2_lib.baseboard_fab2(sch_1):page61_i172@chpset_lib.skx_ext_b(chips)!SKX_EXT_B_BGA1-IC,TBD!!!F125!DDR4_DQ(10)!!!!
S!M_L_DQ<11>!U2D1!DF81!@baseboard_fab2_lib.baseboard_fab2(sch_1):page61_i172@chpset_lib.skx_ext_b(chips)!SKX_EXT_B_BGA1-IC,TBD!!!F125!DDR4_DQ(11)!!!!
S!M_L_DQ<12>!U2D1!CY79!@baseboard_fab2_lib.baseboard_fab2(sch_1):page61_i172@chpset_lib.skx_ext_b(chips)!SKX_EXT_B_BGA1-IC,TBD!!!F125!DDR4_DQ(12)!!!!
S!M_L_DQ<13>!U2D1!CW80!@baseboard_fab2_lib.baseboard_fab2(sch_1):page61_i172@chpset_lib.skx_ext_b(chips)!SKX_EXT_B_BGA1-IC,TBD!!!F125!DDR4_DQ(13)!!!!
S!M_L_DQ<14>!U2D1!DC82!@baseboard_fab2_lib.baseboard_fab2(sch_1):page61_i172@chpset_lib.skx_ext_b(chips)!SKX_EXT_B_BGA1-IC,TBD!!!F125!DDR4_DQ(14)!!!!
S!M_L_DQ<15>!U2D1!DE82!@baseboard_fab2_lib.baseboard_fab2(sch_1):page61_i172@chpset_lib.skx_ext_b(chips)!SKX_EXT_B_BGA1-IC,TBD!!!F125!DDR4_DQ(15)!!!!
S!M_L_DQ<16>!U2D1!DW80!@baseboard_fab2_lib.baseboard_fab2(sch_1):page61_i172@chpset_lib.skx_ext_b(chips)!SKX_EXT_B_BGA1-IC,TBD!!!F125!DDR4_DQ(16)!!!!
S!M_L_DQ<17>!U2D1!EC80!@baseboard_fab2_lib.baseboard_fab2(sch_1):page61_i172@chpset_lib.skx_ext_b(chips)!SKX_EXT_B_BGA1-IC,TBD!!!F125!DDR4_DQ(17)!!!!
S!M_L_DQ<18>!U2D1!DY77!@baseboard_fab2_lib.baseboard_fab2(sch_1):page61_i172@chpset_lib.skx_ext_b(chips)!SKX_EXT_B_BGA1-IC,TBD!!!F125!DDR4_DQ(18)!!!!
S!M_L_DQ<19>!U2D1!EB77!@baseboard_fab2_lib.baseboard_fab2(sch_1):page61_i172@chpset_lib.skx_ext_b(chips)!SKX_EXT_B_BGA1-IC,TBD!!!F125!DDR4_DQ(19)!!!!
S!M_L_DQ<1>!U2D1!CK81!@baseboard_fab2_lib.baseboard_fab2(sch_1):page61_i172@chpset_lib.skx_ext_b(chips)!SKX_EXT_B_BGA1-IC,TBD!!!F125!DDR4_DQ(1)!!!!
S!M_L_DQ<20>!U2D1!DY81!@baseboard_fab2_lib.baseboard_fab2(sch_1):page61_i172@chpset_lib.skx_ext_b(chips)!SKX_EXT_B_BGA1-IC,TBD!!!F125!DDR4_DQ(20)!!!!
S!M_L_DQ<21>!U2D1!EB81!@baseboard_fab2_lib.baseboard_fab2(sch_1):page61_i172@chpset_lib.skx_ext_b(chips)!SKX_EXT_B_BGA1-IC,TBD!!!F125!DDR4_DQ(21)!!!!
S!M_L_DQ<22>!U2D1!DW78!@baseboard_fab2_lib.baseboard_fab2(sch_1):page61_i172@chpset_lib.skx_ext_b(chips)!SKX_EXT_B_BGA1-IC,TBD!!!F125!DDR4_DQ(22)!!!!
S!M_L_DQ<23>!U2D1!EC78!@baseboard_fab2_lib.baseboard_fab2(sch_1):page61_i172@chpset_lib.skx_ext_b(chips)!SKX_EXT_B_BGA1-IC,TBD!!!F125!DDR4_DQ(23)!!!!
S!M_L_DQ<24>!U2D1!ED75!@baseboard_fab2_lib.baseboard_fab2(sch_1):page61_i172@chpset_lib.skx_ext_b(chips)!SKX_EXT_B_BGA1-IC,TBD!!!F125!DDR4_DQ(24)!!!!
S!M_L_DQ<25>!U2D1!EE74!@baseboard_fab2_lib.baseboard_fab2(sch_1):page61_i172@chpset_lib.skx_ext_b(chips)!SKX_EXT_B_BGA1-IC,TBD!!!F125!DDR4_DQ(25)!!!!
S!M_L_DQ<26>!U2D1!EB71!@baseboard_fab2_lib.baseboard_fab2(sch_1):page61_i172@chpset_lib.skx_ext_b(chips)!SKX_EXT_B_BGA1-IC,TBD!!!F125!DDR4_DQ(26)!!!!
S!M_L_DQ<27>!U2D1!ED71!@baseboard_fab2_lib.baseboard_fab2(sch_1):page61_i172@chpset_lib.skx_ext_b(chips)!SKX_EXT_B_BGA1-IC,TBD!!!F125!DDR4_DQ(27)!!!!
S!M_L_DQ<28>!U2D1!EA74!@baseboard_fab2_lib.baseboard_fab2(sch_1):page61_i172@chpset_lib.skx_ext_b(chips)!SKX_EXT_B_BGA1-IC,TBD!!!F125!DDR4_DQ(28)!!!!
S!M_L_DQ<29>!U2D1!EB75!@baseboard_fab2_lib.baseboard_fab2(sch_1):page61_i172@chpset_lib.skx_ext_b(chips)!SKX_EXT_B_BGA1-IC,TBD!!!F125!DDR4_DQ(29)!!!!
S!M_L_DQ<2>!U2D1!CT81!@baseboard_fab2_lib.baseboard_fab2(sch_1):page61_i172@chpset_lib.skx_ext_b(chips)!SKX_EXT_B_BGA1-IC,TBD!!!F125!DDR4_DQ(2)!!!!
S!M_L_DQ<30>!U2D1!EA72!@baseboard_fab2_lib.baseboard_fab2(sch_1):page61_i172@chpset_lib.skx_ext_b(chips)!SKX_EXT_B_BGA1-IC,TBD!!!F125!DDR4_DQ(30)!!!!
S!M_L_DQ<31>!U2D1!EE72!@baseboard_fab2_lib.baseboard_fab2(sch_1):page61_i172@chpset_lib.skx_ext_b(chips)!SKX_EXT_B_BGA1-IC,TBD!!!F125!DDR4_DQ(31)!!!!
S!M_L_DQ<37>!U2D1!DN42!@baseboard_fab2_lib.baseboard_fab2(sch_1):page61_i172@chpset_lib.skx_ext_b(chips)!SKX_EXT_B_BGA1-IC,TBD!!!F125!DDR4_DQ(37)!!!!
S!M_L_DQ<36>!U2D1!DL42!@baseboard_fab2_lib.baseboard_fab2(sch_1):page61_i172@chpset_lib.skx_ext_b(chips)!SKX_EXT_B_BGA1-IC,TBD!!!F125!DDR4_DQ(36)!!!!
S!M_L_DQ<34>!U2D1!DP39!@baseboard_fab2_lib.baseboard_fab2(sch_1):page61_i172@chpset_lib.skx_ext_b(chips)!SKX_EXT_B_BGA1-IC,TBD!!!F125!DDR4_DQ(34)!!!!
S!M_L_DQ<35>!U2D1!DT39!@baseboard_fab2_lib.baseboard_fab2(sch_1):page61_i172@chpset_lib.skx_ext_b(chips)!SKX_EXT_B_BGA1-IC,TBD!!!F125!DDR4_DQ(35)!!!!
S!M_L_DQ<33>!U2D1!DW42!@baseboard_fab2_lib.baseboard_fab2(sch_1):page61_i172@chpset_lib.skx_ext_b(chips)!SKX_EXT_B_BGA1-IC,TBD!!!F125!DDR4_DQ(33)!!!!
S!M_L_DQ<32>!U2D1!DU42!@baseboard_fab2_lib.baseboard_fab2(sch_1):page61_i172@chpset_lib.skx_ext_b(chips)!SKX_EXT_B_BGA1-IC,TBD!!!F125!DDR4_DQ(32)!!!!
S!M_L_DQ<38>!U2D1!DN40!@baseboard_fab2_lib.baseboard_fab2(sch_1):page61_i172@chpset_lib.skx_ext_b(chips)!SKX_EXT_B_BGA1-IC,TBD!!!F125!DDR4_DQ(38)!!!!
S!M_L_DQ<39>!U2D1!DU40!@baseboard_fab2_lib.baseboard_fab2(sch_1):page61_i172@chpset_lib.skx_ext_b(chips)!SKX_EXT_B_BGA1-IC,TBD!!!F125!DDR4_DQ(39)!!!!
S!M_L_DQ<3>!U2D1!CR82!@baseboard_fab2_lib.baseboard_fab2(sch_1):page61_i172@chpset_lib.skx_ext_b(chips)!SKX_EXT_B_BGA1-IC,TBD!!!F125!DDR4_DQ(3)!!!!
S!M_L_DQ<40>!U2D1!EC34!@baseboard_fab2_lib.baseboard_fab2(sch_1):page61_i172@chpset_lib.skx_ext_b(chips)!SKX_EXT_B_BGA1-IC,TBD!!!F125!DDR4_DQ(40)!!!!
S!M_L_DQ<41>!U2D1!ED33!@baseboard_fab2_lib.baseboard_fab2(sch_1):page61_i172@chpset_lib.skx_ext_b(chips)!SKX_EXT_B_BGA1-IC,TBD!!!F125!DDR4_DQ(41)!!!!
S!M_L_DQ<42>!U2D1!EA30!@baseboard_fab2_lib.baseboard_fab2(sch_1):page61_i172@chpset_lib.skx_ext_b(chips)!SKX_EXT_B_BGA1-IC,TBD!!!F125!DDR4_DQ(42)!!!!
S!M_L_DQ<43>!U2D1!EC30!@baseboard_fab2_lib.baseboard_fab2(sch_1):page61_i172@chpset_lib.skx_ext_b(chips)!SKX_EXT_B_BGA1-IC,TBD!!!F125!DDR4_DQ(43)!!!!
S!M_L_DQ<44>!U2D1!DY33!@baseboard_fab2_lib.baseboard_fab2(sch_1):page61_i172@chpset_lib.skx_ext_b(chips)!SKX_EXT_B_BGA1-IC,TBD!!!F125!DDR4_DQ(44)!!!!
S!M_L_DQ<45>!U2D1!EA34!@baseboard_fab2_lib.baseboard_fab2(sch_1):page61_i172@chpset_lib.skx_ext_b(chips)!SKX_EXT_B_BGA1-IC,TBD!!!F125!DDR4_DQ(45)!!!!
S!M_L_DQ<46>!U2D1!DY31!@baseboard_fab2_lib.baseboard_fab2(sch_1):page61_i172@chpset_lib.skx_ext_b(chips)!SKX_EXT_B_BGA1-IC,TBD!!!F125!DDR4_DQ(46)!!!!
S!M_L_DQ<47>!U2D1!ED31!@baseboard_fab2_lib.baseboard_fab2(sch_1):page61_i172@chpset_lib.skx_ext_b(chips)!SKX_EXT_B_BGA1-IC,TBD!!!F125!DDR4_DQ(47)!!!!
S!M_L_DQ<48>!U2D1!EC28!@baseboard_fab2_lib.baseboard_fab2(sch_1):page61_i172@chpset_lib.skx_ext_b(chips)!SKX_EXT_B_BGA1-IC,TBD!!!F125!DDR4_DQ(48)!!!!
S!M_L_DQ<49>!U2D1!ED27!@baseboard_fab2_lib.baseboard_fab2(sch_1):page61_i172@chpset_lib.skx_ext_b(chips)!SKX_EXT_B_BGA1-IC,TBD!!!F125!DDR4_DQ(49)!!!!
S!M_L_DQ<4>!U2D1!CK79!@baseboard_fab2_lib.baseboard_fab2(sch_1):page61_i172@chpset_lib.skx_ext_b(chips)!SKX_EXT_B_BGA1-IC,TBD!!!F125!DDR4_DQ(4)!!!!
S!M_L_DQ<50>!U2D1!EA24!@baseboard_fab2_lib.baseboard_fab2(sch_1):page61_i172@chpset_lib.skx_ext_b(chips)!SKX_EXT_B_BGA1-IC,TBD!!!F125!DDR4_DQ(50)!!!!
S!M_L_DQ<51>!U2D1!EC24!@baseboard_fab2_lib.baseboard_fab2(sch_1):page61_i172@chpset_lib.skx_ext_b(chips)!SKX_EXT_B_BGA1-IC,TBD!!!F125!DDR4_DQ(51)!!!!
S!M_L_DQ<52>!U2D1!DY27!@baseboard_fab2_lib.baseboard_fab2(sch_1):page61_i172@chpset_lib.skx_ext_b(chips)!SKX_EXT_B_BGA1-IC,TBD!!!F125!DDR4_DQ(52)!!!!
S!M_L_DQ<53>!U2D1!EA28!@baseboard_fab2_lib.baseboard_fab2(sch_1):page61_i172@chpset_lib.skx_ext_b(chips)!SKX_EXT_B_BGA1-IC,TBD!!!F125!DDR4_DQ(53)!!!!
S!M_L_DQ<54>!U2D1!DY25!@baseboard_fab2_lib.baseboard_fab2(sch_1):page61_i172@chpset_lib.skx_ext_b(chips)!SKX_EXT_B_BGA1-IC,TBD!!!F125!DDR4_DQ(54)!!!!
S!M_L_DQ<55>!U2D1!ED25!@baseboard_fab2_lib.baseboard_fab2(sch_1):page61_i172@chpset_lib.skx_ext_b(chips)!SKX_EXT_B_BGA1-IC,TBD!!!F125!DDR4_DQ(55)!!!!
S!M_L_DQ<56>!U2D1!DF27!@baseboard_fab2_lib.baseboard_fab2(sch_1):page61_i172@chpset_lib.skx_ext_b(chips)!SKX_EXT_B_BGA1-IC,TBD!!!F125!DDR4_DQ(56)!!!!
S!M_L_DQ<57>!U2D1!DK27!@baseboard_fab2_lib.baseboard_fab2(sch_1):page61_i172@chpset_lib.skx_ext_b(chips)!SKX_EXT_B_BGA1-IC,TBD!!!F125!DDR4_DQ(57)!!!!
S!M_L_DQ<58>!U2D1!DD25!@baseboard_fab2_lib.baseboard_fab2(sch_1):page61_i172@chpset_lib.skx_ext_b(chips)!SKX_EXT_B_BGA1-IC,TBD!!!F125!DDR4_DQ(58)!!!!
S!M_L_DQ<59>!U2D1!DJ24!@baseboard_fab2_lib.baseboard_fab2(sch_1):page61_i172@chpset_lib.skx_ext_b(chips)!SKX_EXT_B_BGA1-IC,TBD!!!F125!DDR4_DQ(59)!!!!
S!M_L_DQ<5>!U2D1!CJ80!@baseboard_fab2_lib.baseboard_fab2(sch_1):page61_i172@chpset_lib.skx_ext_b(chips)!SKX_EXT_B_BGA1-IC,TBD!!!F125!DDR4_DQ(5)!!!!
S!M_L_DQ<60>!U2D1!DG28!@baseboard_fab2_lib.baseboard_fab2(sch_1):page61_i172@chpset_lib.skx_ext_b(chips)!SKX_EXT_B_BGA1-IC,TBD!!!F125!DDR4_DQ(60)!!!!
S!M_L_DQ<61>!U2D1!DJ28!@baseboard_fab2_lib.baseboard_fab2(sch_1):page61_i172@chpset_lib.skx_ext_b(chips)!SKX_EXT_B_BGA1-IC,TBD!!!F125!DDR4_DQ(61)!!!!
S!M_L_DQ<62>!U2D1!DF25!@baseboard_fab2_lib.baseboard_fab2(sch_1):page61_i172@chpset_lib.skx_ext_b(chips)!SKX_EXT_B_BGA1-IC,TBD!!!F125!DDR4_DQ(62)!!!!
S!M_L_DQ<63>!U2D1!DK25!@baseboard_fab2_lib.baseboard_fab2(sch_1):page61_i172@chpset_lib.skx_ext_b(chips)!SKX_EXT_B_BGA1-IC,TBD!!!F125!DDR4_DQ(63)!!!!
S!M_L_DQ<6>!U2D1!CR80!@baseboard_fab2_lib.baseboard_fab2(sch_1):page61_i172@chpset_lib.skx_ext_b(chips)!SKX_EXT_B_BGA1-IC,TBD!!!F125!DDR4_DQ(6)!!!!
S!M_L_DQ<7>!U2D1!CN82!@baseboard_fab2_lib.baseboard_fab2(sch_1):page61_i172@chpset_lib.skx_ext_b(chips)!SKX_EXT_B_BGA1-IC,TBD!!!F125!DDR4_DQ(7)!!!!
S!M_L_DQ<8>!U2D1!DB79!@baseboard_fab2_lib.baseboard_fab2(sch_1):page61_i172@chpset_lib.skx_ext_b(chips)!SKX_EXT_B_BGA1-IC,TBD!!!F125!DDR4_DQ(8)!!!!
S!M_L_DQ<9>!U2D1!CY81!@baseboard_fab2_lib.baseboard_fab2(sch_1):page61_i172@chpset_lib.skx_ext_b(chips)!SKX_EXT_B_BGA1-IC,TBD!!!F125!DDR4_DQ(9)!!!!
S!M_L_DQS_DN<0>!U2D1!CL82!@baseboard_fab2_lib.baseboard_fab2(sch_1):page61_i172@chpset_lib.skx_ext_b(chips)!SKX_EXT_B_BGA1-IC,TBD!!!F125!DDR4_DQS_DN(0)!!!!
S!M_L_DQS_DN<10>!U2D1!DC80!@baseboard_fab2_lib.baseboard_fab2(sch_1):page61_i172@chpset_lib.skx_ext_b(chips)!SKX_EXT_B_BGA1-IC,TBD!!!F125!DDR4_DQS_DN(10)!!!!
S!M_L_DQS_DN<11>!U2D1!DY79!@baseboard_fab2_lib.baseboard_fab2(sch_1):page61_i172@chpset_lib.skx_ext_b(chips)!SKX_EXT_B_BGA1-IC,TBD!!!F125!DDR4_DQS_DN(11)!!!!
S!M_L_DQS_DN<12>!U2D1!EB73!@baseboard_fab2_lib.baseboard_fab2(sch_1):page61_i172@chpset_lib.skx_ext_b(chips)!SKX_EXT_B_BGA1-IC,TBD!!!F125!DDR4_DQS_DN(12)!!!!
S!M_L_DQS_DN<13>!U2D1!DP41!@baseboard_fab2_lib.baseboard_fab2(sch_1):page61_i172@chpset_lib.skx_ext_b(chips)!SKX_EXT_B_BGA1-IC,TBD!!!F125!DDR4_DQS_DN(13)!!!!
S!M_L_DQS_DN<14>!U2D1!EA32!@baseboard_fab2_lib.baseboard_fab2(sch_1):page61_i172@chpset_lib.skx_ext_b(chips)!SKX_EXT_B_BGA1-IC,TBD!!!F125!DDR4_DQS_DN(14)!!!!
S!M_L_DQS_DN<15>!U2D1!EA26!@baseboard_fab2_lib.baseboard_fab2(sch_1):page61_i172@chpset_lib.skx_ext_b(chips)!SKX_EXT_B_BGA1-IC,TBD!!!F125!DDR4_DQS_DN(15)!!!!
S!M_L_DQS_DN<16>!U2D1!DG26!@baseboard_fab2_lib.baseboard_fab2(sch_1):page61_i172@chpset_lib.skx_ext_b(chips)!SKX_EXT_B_BGA1-IC,TBD!!!F125!DDR4_DQS_DN(16)!!!!
S!M_L_DQS_DN<17>!U2D1!DV67!@baseboard_fab2_lib.baseboard_fab2(sch_1):page61_i172@chpset_lib.skx_ext_b(chips)!SKX_EXT_B_BGA1-IC,TBD!!!F125!DDR4_DQS_DN(17)!!!!
S!M_L_DQS_DN<1>!U2D1!DA82!@baseboard_fab2_lib.baseboard_fab2(sch_1):page61_i172@chpset_lib.skx_ext_b(chips)!SKX_EXT_B_BGA1-IC,TBD!!!F125!DDR4_DQS_DN(1)!!!!
S!M_L_DQS_DN<2>!U2D1!ED79!@baseboard_fab2_lib.baseboard_fab2(sch_1):page61_i172@chpset_lib.skx_ext_b(chips)!SKX_EXT_B_BGA1-IC,TBD!!!F125!DDR4_DQS_DN(2)!!!!
S!M_L_DQS_DN<3>!U2D1!EF73!@baseboard_fab2_lib.baseboard_fab2(sch_1):page61_i172@chpset_lib.skx_ext_b(chips)!SKX_EXT_B_BGA1-IC,TBD!!!F125!DDR4_DQS_DN(3)!!!!
S!M_L_DQS_DN<4>!U2D1!DV41!@baseboard_fab2_lib.baseboard_fab2(sch_1):page61_i172@chpset_lib.skx_ext_b(chips)!SKX_EXT_B_BGA1-IC,TBD!!!F125!DDR4_DQS_DN(4)!!!!
S!M_L_DQS_DN<5>!U2D1!EE32!@baseboard_fab2_lib.baseboard_fab2(sch_1):page61_i172@chpset_lib.skx_ext_b(chips)!SKX_EXT_B_BGA1-IC,TBD!!!F125!DDR4_DQS_DN(5)!!!!
S!M_L_DQS_DN<6>!U2D1!EE26!@baseboard_fab2_lib.baseboard_fab2(sch_1):page61_i172@chpset_lib.skx_ext_b(chips)!SKX_EXT_B_BGA1-IC,TBD!!!F125!DDR4_DQS_DN(6)!!!!
S!M_L_DQS_DN<7>!U2D1!DL26!@baseboard_fab2_lib.baseboard_fab2(sch_1):page61_i172@chpset_lib.skx_ext_b(chips)!SKX_EXT_B_BGA1-IC,TBD!!!F125!DDR4_DQS_DN(7)!!!!
S!M_L_DQS_DN<8>!U2D1!EB67!@baseboard_fab2_lib.baseboard_fab2(sch_1):page61_i172@chpset_lib.skx_ext_b(chips)!SKX_EXT_B_BGA1-IC,TBD!!!F125!DDR4_DQS_DN(8)!!!!
S!M_L_DQS_DN<9>!U2D1!CN80!@baseboard_fab2_lib.baseboard_fab2(sch_1):page61_i172@chpset_lib.skx_ext_b(chips)!SKX_EXT_B_BGA1-IC,TBD!!!F125!DDR4_DQS_DN(9)!!!!
S!M_L_DQS_DP<0>!U2D1!CM81!@baseboard_fab2_lib.baseboard_fab2(sch_1):page61_i172@chpset_lib.skx_ext_b(chips)!SKX_EXT_B_BGA1-IC,TBD!!!F125!DDR4_DQS_DP(0)!!!!
S!M_L_DQS_DP<10>!U2D1!DD79!@baseboard_fab2_lib.baseboard_fab2(sch_1):page61_i172@chpset_lib.skx_ext_b(chips)!SKX_EXT_B_BGA1-IC,TBD!!!F125!DDR4_DQS_DP(10)!!!!
S!M_L_DQS_DP<11>!U2D1!DV79!@baseboard_fab2_lib.baseboard_fab2(sch_1):page61_i172@chpset_lib.skx_ext_b(chips)!SKX_EXT_B_BGA1-IC,TBD!!!F125!DDR4_DQS_DP(11)!!!!
S!M_L_DQS_DP<12>!U2D1!DY73!@baseboard_fab2_lib.baseboard_fab2(sch_1):page61_i172@chpset_lib.skx_ext_b(chips)!SKX_EXT_B_BGA1-IC,TBD!!!F125!DDR4_DQS_DP(12)!!!!
S!M_L_DQS_DP<13>!U2D1!DM41!@baseboard_fab2_lib.baseboard_fab2(sch_1):page61_i172@chpset_lib.skx_ext_b(chips)!SKX_EXT_B_BGA1-IC,TBD!!!F125!DDR4_DQS_DP(13)!!!!
S!M_L_DQS_DP<14>!U2D1!DW32!@baseboard_fab2_lib.baseboard_fab2(sch_1):page61_i172@chpset_lib.skx_ext_b(chips)!SKX_EXT_B_BGA1-IC,TBD!!!F125!DDR4_DQS_DP(14)!!!!
S!M_L_DQS_DP<15>!U2D1!DW26!@baseboard_fab2_lib.baseboard_fab2(sch_1):page61_i172@chpset_lib.skx_ext_b(chips)!SKX_EXT_B_BGA1-IC,TBD!!!F125!DDR4_DQS_DP(15)!!!!
S!M_L_DQS_DP<16>!U2D1!DE26!@baseboard_fab2_lib.baseboard_fab2(sch_1):page61_i172@chpset_lib.skx_ext_b(chips)!SKX_EXT_B_BGA1-IC,TBD!!!F125!DDR4_DQS_DP(16)!!!!
S!M_L_DQS_DP<17>!U2D1!DT67!@baseboard_fab2_lib.baseboard_fab2(sch_1):page61_i172@chpset_lib.skx_ext_b(chips)!SKX_EXT_B_BGA1-IC,TBD!!!F125!DDR4_DQS_DP(17)!!!!
S!M_L_DQS_DP<1>!U2D1!DB81!@baseboard_fab2_lib.baseboard_fab2(sch_1):page61_i172@chpset_lib.skx_ext_b(chips)!SKX_EXT_B_BGA1-IC,TBD!!!F125!DDR4_DQS_DP(1)!!!!
S!M_L_DQS_DP<2>!U2D1!EB79!@baseboard_fab2_lib.baseboard_fab2(sch_1):page61_i172@chpset_lib.skx_ext_b(chips)!SKX_EXT_B_BGA1-IC,TBD!!!F125!DDR4_DQS_DP(2)!!!!
S!M_L_DQS_DP<3>!U2D1!ED73!@baseboard_fab2_lib.baseboard_fab2(sch_1):page61_i172@chpset_lib.skx_ext_b(chips)!SKX_EXT_B_BGA1-IC,TBD!!!F125!DDR4_DQS_DP(3)!!!!
S!M_L_DQS_DP<4>!U2D1!DT41!@baseboard_fab2_lib.baseboard_fab2(sch_1):page61_i172@chpset_lib.skx_ext_b(chips)!SKX_EXT_B_BGA1-IC,TBD!!!F125!DDR4_DQS_DP(4)!!!!
S!M_L_DQS_DP<5>!U2D1!EC32!@baseboard_fab2_lib.baseboard_fab2(sch_1):page61_i172@chpset_lib.skx_ext_b(chips)!SKX_EXT_B_BGA1-IC,TBD!!!F125!DDR4_DQS_DP(5)!!!!
S!M_L_DQS_DP<6>!U2D1!EC26!@baseboard_fab2_lib.baseboard_fab2(sch_1):page61_i172@chpset_lib.skx_ext_b(chips)!SKX_EXT_B_BGA1-IC,TBD!!!F125!DDR4_DQS_DP(6)!!!!
S!M_L_DQS_DP<7>!U2D1!DJ26!@baseboard_fab2_lib.baseboard_fab2(sch_1):page61_i172@chpset_lib.skx_ext_b(chips)!SKX_EXT_B_BGA1-IC,TBD!!!F125!DDR4_DQS_DP(7)!!!!
S!M_L_DQS_DP<8>!U2D1!DY67!@baseboard_fab2_lib.baseboard_fab2(sch_1):page61_i172@chpset_lib.skx_ext_b(chips)!SKX_EXT_B_BGA1-IC,TBD!!!F125!DDR4_DQS_DP(8)!!!!
S!M_L_DQS_DP<9>!U2D1!CP79!@baseboard_fab2_lib.baseboard_fab2(sch_1):page61_i172@chpset_lib.skx_ext_b(chips)!SKX_EXT_B_BGA1-IC,TBD!!!F125!DDR4_DQS_DP(9)!!!!
S!M_L_ECC<0>!U2D1!DY69!@baseboard_fab2_lib.baseboard_fab2(sch_1):page61_i172@chpset_lib.skx_ext_b(chips)!SKX_EXT_B_BGA1-IC,TBD!!!F125!DDR4_ECC(0)!!!!
S!M_L_ECC<1>!U2D1!EA68!@baseboard_fab2_lib.baseboard_fab2(sch_1):page61_i172@chpset_lib.skx_ext_b(chips)!SKX_EXT_B_BGA1-IC,TBD!!!F125!DDR4_ECC(1)!!!!
S!M_L_ECC<2>!U2D1!DV65!@baseboard_fab2_lib.baseboard_fab2(sch_1):page61_i172@chpset_lib.skx_ext_b(chips)!SKX_EXT_B_BGA1-IC,TBD!!!F125!DDR4_ECC(2)!!!!
S!M_L_ECC<3>!U2D1!DY65!@baseboard_fab2_lib.baseboard_fab2(sch_1):page61_i172@chpset_lib.skx_ext_b(chips)!SKX_EXT_B_BGA1-IC,TBD!!!F125!DDR4_ECC(3)!!!!
S!M_L_ECC<4>!U2D1!DU68!@baseboard_fab2_lib.baseboard_fab2(sch_1):page61_i172@chpset_lib.skx_ext_b(chips)!SKX_EXT_B_BGA1-IC,TBD!!!F125!DDR4_ECC(4)!!!!
S!M_L_ECC<5>!U2D1!DV69!@baseboard_fab2_lib.baseboard_fab2(sch_1):page61_i172@chpset_lib.skx_ext_b(chips)!SKX_EXT_B_BGA1-IC,TBD!!!F125!DDR4_ECC(5)!!!!
S!M_L_ECC<6>!U2D1!DU66!@baseboard_fab2_lib.baseboard_fab2(sch_1):page61_i172@chpset_lib.skx_ext_b(chips)!SKX_EXT_B_BGA1-IC,TBD!!!F125!DDR4_ECC(6)!!!!
S!M_L_ECC<7>!U2D1!EA66!@baseboard_fab2_lib.baseboard_fab2(sch_1):page61_i172@chpset_lib.skx_ext_b(chips)!SKX_EXT_B_BGA1-IC,TBD!!!F125!DDR4_ECC(7)!!!!
S!M_L_MA<0>!U2D1!DW52!@baseboard_fab2_lib.baseboard_fab2(sch_1):page61_i172@chpset_lib.skx_ext_b(chips)!SKX_EXT_B_BGA1-IC,TBD!!!F125!DDR4_MA(0)!!!!
S!M_L_MA<10>!U2D1!DT55!@baseboard_fab2_lib.baseboard_fab2(sch_1):page61_i172@chpset_lib.skx_ext_b(chips)!SKX_EXT_B_BGA1-IC,TBD!!!F125!DDR4_MA(10)!!!!
S!M_L_MA<11>!U2D1!DR60!@baseboard_fab2_lib.baseboard_fab2(sch_1):page61_i172@chpset_lib.skx_ext_b(chips)!SKX_EXT_B_BGA1-IC,TBD!!!F125!DDR4_MA(11)!!!!
S!M_L_MA<12>!U2D1!DN60!@baseboard_fab2_lib.baseboard_fab2(sch_1):page61_i172@chpset_lib.skx_ext_b(chips)!SKX_EXT_B_BGA1-IC,TBD!!!F125!DDR4_MA(12)!!!!
S!M_L_MA<13>!U2D1!DT51!@baseboard_fab2_lib.baseboard_fab2(sch_1):page61_i172@chpset_lib.skx_ext_b(chips)!SKX_EXT_B_BGA1-IC,TBD!!!F125!DDR4_MA(13)!!!!
S!M_L_MA<14>!U2D1!DM51!@baseboard_fab2_lib.baseboard_fab2(sch_1):page61_i172@chpset_lib.skx_ext_b(chips)!SKX_EXT_B_BGA1-IC,TBD!!!F125!DDR4_MA(14)!!!!
S!M_L_MA<15>!U2D1!DR52!@baseboard_fab2_lib.baseboard_fab2(sch_1):page61_i172@chpset_lib.skx_ext_b(chips)!SKX_EXT_B_BGA1-IC,TBD!!!F125!DDR4_MA(15)!!!!
S!M_L_MA<16>!U2D1!DN52!@baseboard_fab2_lib.baseboard_fab2(sch_1):page61_i172@chpset_lib.skx_ext_b(chips)!SKX_EXT_B_BGA1-IC,TBD!!!F125!DDR4_MA(16)!!!!
S!M_L_MA<17>!U2D1!DR48!@baseboard_fab2_lib.baseboard_fab2(sch_1):page61_i172@chpset_lib.skx_ext_b(chips)!SKX_EXT_B_BGA1-IC,TBD!!!F125!DDR4_MA(17)!!!!
S!M_L_MA<1>!U2D1!DW58!@baseboard_fab2_lib.baseboard_fab2(sch_1):page61_i172@chpset_lib.skx_ext_b(chips)!SKX_EXT_B_BGA1-IC,TBD!!!F125!DDR4_MA(1)!!!!
S!M_L_MA<2>!U2D1!DV57!@baseboard_fab2_lib.baseboard_fab2(sch_1):page61_i172@chpset_lib.skx_ext_b(chips)!SKX_EXT_B_BGA1-IC,TBD!!!F125!DDR4_MA(2)!!!!
S!M_L_MA<3>!U2D1!DR58!@baseboard_fab2_lib.baseboard_fab2(sch_1):page61_i172@chpset_lib.skx_ext_b(chips)!SKX_EXT_B_BGA1-IC,TBD!!!F125!DDR4_MA(3)!!!!
S!M_L_MA<4>!U2D1!DT59!@baseboard_fab2_lib.baseboard_fab2(sch_1):page61_i172@chpset_lib.skx_ext_b(chips)!SKX_EXT_B_BGA1-IC,TBD!!!F125!DDR4_MA(4)!!!!
S!M_L_MA<5>!U2D1!DN58!@baseboard_fab2_lib.baseboard_fab2(sch_1):page61_i172@chpset_lib.skx_ext_b(chips)!SKX_EXT_B_BGA1-IC,TBD!!!F125!DDR4_MA(5)!!!!
S!M_L_MA<6>!U2D1!DM59!@baseboard_fab2_lib.baseboard_fab2(sch_1):page61_i172@chpset_lib.skx_ext_b(chips)!SKX_EXT_B_BGA1-IC,TBD!!!F125!DDR4_MA(6)!!!!
S!M_L_MA<7>!U2D1!DK61!@baseboard_fab2_lib.baseboard_fab2(sch_1):page61_i172@chpset_lib.skx_ext_b(chips)!SKX_EXT_B_BGA1-IC,TBD!!!F125!DDR4_MA(7)!!!!
S!M_L_MA<8>!U2D1!DJ60!@baseboard_fab2_lib.baseboard_fab2(sch_1):page61_i172@chpset_lib.skx_ext_b(chips)!SKX_EXT_B_BGA1-IC,TBD!!!F125!DDR4_MA(8)!!!!
S!M_L_MA<9>!U2D1!DV59!@baseboard_fab2_lib.baseboard_fab2(sch_1):page61_i172@chpset_lib.skx_ext_b(chips)!SKX_EXT_B_BGA1-IC,TBD!!!F125!DDR4_MA(9)!!!!
S!M_L_ODT<0>!U2D1!DR50!@baseboard_fab2_lib.baseboard_fab2(sch_1):page61_i172@chpset_lib.skx_ext_b(chips)!SKX_EXT_B_BGA1-IC,TBD!!!F125!DDR4_ODT(0)!!!!
S!M_L_ODT<1>!U2D1!DN48!@baseboard_fab2_lib.baseboard_fab2(sch_1):page61_i172@chpset_lib.skx_ext_b(chips)!SKX_EXT_B_BGA1-IC,TBD!!!F125!DDR4_ODT(1)!!!!
S!M_L_ODT<2>!U2D1!DT49!@baseboard_fab2_lib.baseboard_fab2(sch_1):page61_i172@chpset_lib.skx_ext_b(chips)!SKX_EXT_B_BGA1-IC,TBD!!!F125!DDR4_ODT(2)!!!!
S!M_L_ODT<3>!U2D1!DM47!@baseboard_fab2_lib.baseboard_fab2(sch_1):page61_i172@chpset_lib.skx_ext_b(chips)!SKX_EXT_B_BGA1-IC,TBD!!!F125!DDR4_ODT(3)!!!!
S!M_L_PAR!U2D1!DV53!@baseboard_fab2_lib.baseboard_fab2(sch_1):page61_i172@chpset_lib.skx_ext_b(chips)!SKX_EXT_B_BGA1-IC,TBD!!!F125!DDR4_PAR!!!!
S!M_M_ACT_N!U2D1!DC62!@baseboard_fab2_lib.baseboard_fab2(sch_1):page62_i172@chpset_lib.skx_ext_b(chips)!SKX_EXT_B_BGA1-IC,TBD!!!F124!DDR5_ACT_N!!!!
S!M_M_ALERT_N!U2D1!DD61!@baseboard_fab2_lib.baseboard_fab2(sch_1):page62_i172@chpset_lib.skx_ext_b(chips)!SKX_EXT_B_BGA1-IC,TBD!!!F124!DDR5_ALERT_N!!!!
S!M_M_BA<0>!U2D1!DJ52!@baseboard_fab2_lib.baseboard_fab2(sch_1):page62_i172@chpset_lib.skx_ext_b(chips)!SKX_EXT_B_BGA1-IC,TBD!!!F124!DDR5_BA(0)!!!!
S!M_M_BA<1>!U2D1!DC56!@baseboard_fab2_lib.baseboard_fab2(sch_1):page62_i172@chpset_lib.skx_ext_b(chips)!SKX_EXT_B_BGA1-IC,TBD!!!F124!DDR5_BA(1)!!!!
S!M_M_BG<0>!U2D1!DA62!@baseboard_fab2_lib.baseboard_fab2(sch_1):page62_i172@chpset_lib.skx_ext_b(chips)!SKX_EXT_B_BGA1-IC,TBD!!!F124!DDR5_BG(0)!!!!
S!M_M_BG<1>!U2D1!DF61!@baseboard_fab2_lib.baseboard_fab2(sch_1):page62_i172@chpset_lib.skx_ext_b(chips)!SKX_EXT_B_BGA1-IC,TBD!!!F124!DDR5_BG(1)!!!!
S!M_M_C<2>!U2D1!DF45!@baseboard_fab2_lib.baseboard_fab2(sch_1):page62_i172@chpset_lib.skx_ext_b(chips)!SKX_EXT_B_BGA1-IC,TBD!!!F124!DDR5_CID(2)!!!!
S!M_M_CKE<0>!U2D1!DG62!@baseboard_fab2_lib.baseboard_fab2(sch_1):page62_i172@chpset_lib.skx_ext_b(chips)!SKX_EXT_B_BGA1-IC,TBD!!!F124!DDR5_CKE(0)!!!!
S!M_M_CKE<1>!U2D1!DD63!@baseboard_fab2_lib.baseboard_fab2(sch_1):page62_i172@chpset_lib.skx_ext_b(chips)!SKX_EXT_B_BGA1-IC,TBD!!!F124!DDR5_CKE(1)!!!!
S!M_M_CKE<2>!U2D1!DK63!@baseboard_fab2_lib.baseboard_fab2(sch_1):page62_i172@chpset_lib.skx_ext_b(chips)!SKX_EXT_B_BGA1-IC,TBD!!!F124!DDR5_CKE(2)!!!!
S!M_M_CKE<3>!U2D1!DF63!@baseboard_fab2_lib.baseboard_fab2(sch_1):page62_i172@chpset_lib.skx_ext_b(chips)!SKX_EXT_B_BGA1-IC,TBD!!!F124!DDR5_CKE(3)!!!!
S!M_M_CLK_DN<0>!U2D1!DK55!@baseboard_fab2_lib.baseboard_fab2(sch_1):page62_i172@chpset_lib.skx_ext_b(chips)!SKX_EXT_B_BGA1-IC,TBD!!!F124!DDR5_CLK_DN(0)!!!!
S!M_M_CLK_DN<2>!U2D1!DK57!@baseboard_fab2_lib.baseboard_fab2(sch_1):page62_i172@chpset_lib.skx_ext_b(chips)!SKX_EXT_B_BGA1-IC,TBD!!!F124!DDR5_CLK_DN(2)!!!!
S!M_M_CLK_DN<1>!U2D1!DF55!@baseboard_fab2_lib.baseboard_fab2(sch_1):page62_i172@chpset_lib.skx_ext_b(chips)!SKX_EXT_B_BGA1-IC,TBD!!!F124!DDR5_CLK_DN(1)!!!!
S!M_M_CLK_DN<3>!U2D1!DF57!@baseboard_fab2_lib.baseboard_fab2(sch_1):page62_i172@chpset_lib.skx_ext_b(chips)!SKX_EXT_B_BGA1-IC,TBD!!!F124!DDR5_CLK_DN(3)!!!!
S!M_M_CLK_DP<0>!U2D1!DJ54!@baseboard_fab2_lib.baseboard_fab2(sch_1):page62_i172@chpset_lib.skx_ext_b(chips)!SKX_EXT_B_BGA1-IC,TBD!!!F124!DDR5_CLK_DP(0)!!!!
S!M_M_CLK_DP<2>!U2D1!DJ56!@baseboard_fab2_lib.baseboard_fab2(sch_1):page62_i172@chpset_lib.skx_ext_b(chips)!SKX_EXT_B_BGA1-IC,TBD!!!F124!DDR5_CLK_DP(2)!!!!
S!M_M_CLK_DP<1>!U2D1!DG54!@baseboard_fab2_lib.baseboard_fab2(sch_1):page62_i172@chpset_lib.skx_ext_b(chips)!SKX_EXT_B_BGA1-IC,TBD!!!F124!DDR5_CLK_DP(1)!!!!
S!M_M_CLK_DP<3>!U2D1!DG56!@baseboard_fab2_lib.baseboard_fab2(sch_1):page62_i172@chpset_lib.skx_ext_b(chips)!SKX_EXT_B_BGA1-IC,TBD!!!F124!DDR5_CLK_DP(3)!!!!
S!M_M_CS_N<0>!U2D1!DK51!@baseboard_fab2_lib.baseboard_fab2(sch_1):page62_i172@chpset_lib.skx_ext_b(chips)!SKX_EXT_B_BGA1-IC,TBD!!!F124!DDR5_CS_N(0)!!!!
S!M_M_CS_N<1>!U2D1!DF49!@baseboard_fab2_lib.baseboard_fab2(sch_1):page62_i172@chpset_lib.skx_ext_b(chips)!SKX_EXT_B_BGA1-IC,TBD!!!F124!DDR5_CS_N(1)!!!!
S!M_M_CS_N<2>!U2D1!DJ46!@baseboard_fab2_lib.baseboard_fab2(sch_1):page62_i172@chpset_lib.skx_ext_b(chips)!SKX_EXT_B_BGA1-IC,TBD!!!F124!DDR5_CS_N(2)!!!!
S!M_M_CS_N<3>!U2D1!DG46!@baseboard_fab2_lib.baseboard_fab2(sch_1):page62_i172@chpset_lib.skx_ext_b(chips)!SKX_EXT_B_BGA1-IC,TBD!!!F124!DDR5_CS_N(3)!!!!
S!M_M_CS_N<4>!U2D1!DF51!@baseboard_fab2_lib.baseboard_fab2(sch_1):page62_i172@chpset_lib.skx_ext_b(chips)!SKX_EXT_B_BGA1-IC,TBD!!!F124!DDR5_CS_N(4)!!!!
S!M_M_CS_N<5>!U2D1!DJ48!@baseboard_fab2_lib.baseboard_fab2(sch_1):page62_i172@chpset_lib.skx_ext_b(chips)!SKX_EXT_B_BGA1-IC,TBD!!!F124!DDR5_CS_N(5)!!!!
S!M_M_CS_N<6>!U2D1!DM45!@baseboard_fab2_lib.baseboard_fab2(sch_1):page62_i172@chpset_lib.skx_ext_b(chips)!SKX_EXT_B_BGA1-IC,TBD!!!F124!DDR5_CS_N(6)!!!!
S!M_M_CS_N<7>!U2D1!DK45!@baseboard_fab2_lib.baseboard_fab2(sch_1):page62_i172@chpset_lib.skx_ext_b(chips)!SKX_EXT_B_BGA1-IC,TBD!!!F124!DDR5_CS_N(7)!!!!
S!M_M_DQ<0>!U2D1!CR74!@baseboard_fab2_lib.baseboard_fab2(sch_1):page62_i172@chpset_lib.skx_ext_b(chips)!SKX_EXT_B_BGA1-IC,TBD!!!F124!DDR5_DQ(0)!!!!
S!M_M_DQ<10>!U2D1!DH75!@baseboard_fab2_lib.baseboard_fab2(sch_1):page62_i172@chpset_lib.skx_ext_b(chips)!SKX_EXT_B_BGA1-IC,TBD!!!F124!DDR5_DQ(10)!!!!
S!M_M_DQ<11>!U2D1!DJ76!@baseboard_fab2_lib.baseboard_fab2(sch_1):page62_i172@chpset_lib.skx_ext_b(chips)!SKX_EXT_B_BGA1-IC,TBD!!!F124!DDR5_DQ(11)!!!!
S!M_M_DQ<12>!U2D1!DC74!@baseboard_fab2_lib.baseboard_fab2(sch_1):page62_i172@chpset_lib.skx_ext_b(chips)!SKX_EXT_B_BGA1-IC,TBD!!!F124!DDR5_DQ(12)!!!!
S!M_M_DQ<13>!U2D1!DB75!@baseboard_fab2_lib.baseboard_fab2(sch_1):page62_i172@chpset_lib.skx_ext_b(chips)!SKX_EXT_B_BGA1-IC,TBD!!!F124!DDR5_DQ(13)!!!!
S!M_M_DQ<14>!U2D1!DF77!@baseboard_fab2_lib.baseboard_fab2(sch_1):page62_i172@chpset_lib.skx_ext_b(chips)!SKX_EXT_B_BGA1-IC,TBD!!!F124!DDR5_DQ(14)!!!!
S!M_M_DQ<15>!U2D1!DH77!@baseboard_fab2_lib.baseboard_fab2(sch_1):page62_i172@chpset_lib.skx_ext_b(chips)!SKX_EXT_B_BGA1-IC,TBD!!!F124!DDR5_DQ(15)!!!!
S!M_M_DQ<16>!U2D1!DG70!@baseboard_fab2_lib.baseboard_fab2(sch_1):page62_i172@chpset_lib.skx_ext_b(chips)!SKX_EXT_B_BGA1-IC,TBD!!!F124!DDR5_DQ(16)!!!!
S!M_M_DQ<17>!U2D1!DJ72!@baseboard_fab2_lib.baseboard_fab2(sch_1):page62_i172@chpset_lib.skx_ext_b(chips)!SKX_EXT_B_BGA1-IC,TBD!!!F124!DDR5_DQ(17)!!!!
S!M_M_DQ<18>!U2D1!DM69!@baseboard_fab2_lib.baseboard_fab2(sch_1):page62_i172@chpset_lib.skx_ext_b(chips)!SKX_EXT_B_BGA1-IC,TBD!!!F124!DDR5_DQ(18)!!!!
S!M_M_DQ<19>!U2D1!DN70!@baseboard_fab2_lib.baseboard_fab2(sch_1):page62_i172@chpset_lib.skx_ext_b(chips)!SKX_EXT_B_BGA1-IC,TBD!!!F124!DDR5_DQ(19)!!!!
S!M_M_DQ<1>!U2D1!CN76!@baseboard_fab2_lib.baseboard_fab2(sch_1):page62_i172@chpset_lib.skx_ext_b(chips)!SKX_EXT_B_BGA1-IC,TBD!!!F124!DDR5_DQ(1)!!!!
S!M_M_DQ<20>!U2D1!DF71!@baseboard_fab2_lib.baseboard_fab2(sch_1):page62_i172@chpset_lib.skx_ext_b(chips)!SKX_EXT_B_BGA1-IC,TBD!!!F124!DDR5_DQ(20)!!!!
S!M_M_DQ<21>!U2D1!DG72!@baseboard_fab2_lib.baseboard_fab2(sch_1):page62_i172@chpset_lib.skx_ext_b(chips)!SKX_EXT_B_BGA1-IC,TBD!!!F124!DDR5_DQ(21)!!!!
S!M_M_DQ<22>!U2D1!DK69!@baseboard_fab2_lib.baseboard_fab2(sch_1):page62_i172@chpset_lib.skx_ext_b(chips)!SKX_EXT_B_BGA1-IC,TBD!!!F124!DDR5_DQ(22)!!!!
S!M_M_DQ<23>!U2D1!DM71!@baseboard_fab2_lib.baseboard_fab2(sch_1):page62_i172@chpset_lib.skx_ext_b(chips)!SKX_EXT_B_BGA1-IC,TBD!!!F124!DDR5_DQ(23)!!!!
S!M_M_DQ<24>!U2D1!CN66!@baseboard_fab2_lib.baseboard_fab2(sch_1):page62_i172@chpset_lib.skx_ext_b(chips)!SKX_EXT_B_BGA1-IC,TBD!!!F124!DDR5_DQ(24)!!!!
S!M_M_DQ<25>!U2D1!CU66!@baseboard_fab2_lib.baseboard_fab2(sch_1):page62_i172@chpset_lib.skx_ext_b(chips)!SKX_EXT_B_BGA1-IC,TBD!!!F124!DDR5_DQ(25)!!!!
S!M_M_DQ<26>!U2D1!CP63!@baseboard_fab2_lib.baseboard_fab2(sch_1):page62_i172@chpset_lib.skx_ext_b(chips)!SKX_EXT_B_BGA1-IC,TBD!!!F124!DDR5_DQ(26)!!!!
S!M_M_DQ<27>!U2D1!CT63!@baseboard_fab2_lib.baseboard_fab2(sch_1):page62_i172@chpset_lib.skx_ext_b(chips)!SKX_EXT_B_BGA1-IC,TBD!!!F124!DDR5_DQ(27)!!!!
S!M_M_DQ<28>!U2D1!CP67!@baseboard_fab2_lib.baseboard_fab2(sch_1):page62_i172@chpset_lib.skx_ext_b(chips)!SKX_EXT_B_BGA1-IC,TBD!!!F124!DDR5_DQ(28)!!!!
S!M_M_DQ<29>!U2D1!CT67!@baseboard_fab2_lib.baseboard_fab2(sch_1):page62_i172@chpset_lib.skx_ext_b(chips)!SKX_EXT_B_BGA1-IC,TBD!!!F124!DDR5_DQ(29)!!!!
S!M_M_DQ<2>!U2D1!CW76!@baseboard_fab2_lib.baseboard_fab2(sch_1):page62_i172@chpset_lib.skx_ext_b(chips)!SKX_EXT_B_BGA1-IC,TBD!!!F124!DDR5_DQ(2)!!!!
S!M_M_DQ<30>!U2D1!CN64!@baseboard_fab2_lib.baseboard_fab2(sch_1):page62_i172@chpset_lib.skx_ext_b(chips)!SKX_EXT_B_BGA1-IC,TBD!!!F124!DDR5_DQ(30)!!!!
S!M_M_DQ<31>!U2D1!CU64!@baseboard_fab2_lib.baseboard_fab2(sch_1):page62_i172@chpset_lib.skx_ext_b(chips)!SKX_EXT_B_BGA1-IC,TBD!!!F124!DDR5_DQ(31)!!!!
S!M_M_DQ<36>!U2D1!DA42!@baseboard_fab2_lib.baseboard_fab2(sch_1):page62_i172@chpset_lib.skx_ext_b(chips)!SKX_EXT_B_BGA1-IC,TBD!!!F124!DDR5_DQ(36)!!!!
S!M_M_DQ<32>!U2D1!DD41!@baseboard_fab2_lib.baseboard_fab2(sch_1):page62_i172@chpset_lib.skx_ext_b(chips)!SKX_EXT_B_BGA1-IC,TBD!!!F124!DDR5_DQ(32)!!!!
S!M_M_DQ<34>!U2D1!DE38!@baseboard_fab2_lib.baseboard_fab2(sch_1):page62_i172@chpset_lib.skx_ext_b(chips)!SKX_EXT_B_BGA1-IC,TBD!!!F124!DDR5_DQ(34)!!!!
S!M_M_DQ<35>!U2D1!DG38!@baseboard_fab2_lib.baseboard_fab2(sch_1):page62_i172@chpset_lib.skx_ext_b(chips)!SKX_EXT_B_BGA1-IC,TBD!!!F124!DDR5_DQ(35)!!!!
S!M_M_DQ<33>!U2D1!DG42!@baseboard_fab2_lib.baseboard_fab2(sch_1):page62_i172@chpset_lib.skx_ext_b(chips)!SKX_EXT_B_BGA1-IC,TBD!!!F124!DDR5_DQ(33)!!!!
S!M_M_DQ<37>!U2D1!DE42!@baseboard_fab2_lib.baseboard_fab2(sch_1):page62_i172@chpset_lib.skx_ext_b(chips)!SKX_EXT_B_BGA1-IC,TBD!!!F124!DDR5_DQ(37)!!!!
S!M_M_DQ<38>!U2D1!DD39!@baseboard_fab2_lib.baseboard_fab2(sch_1):page62_i172@chpset_lib.skx_ext_b(chips)!SKX_EXT_B_BGA1-IC,TBD!!!F124!DDR5_DQ(38)!!!!
S!M_M_DQ<39>!U2D1!DH39!@baseboard_fab2_lib.baseboard_fab2(sch_1):page62_i172@chpset_lib.skx_ext_b(chips)!SKX_EXT_B_BGA1-IC,TBD!!!F124!DDR5_DQ(39)!!!!
S!M_M_DQ<3>!U2D1!CV77!@baseboard_fab2_lib.baseboard_fab2(sch_1):page62_i172@chpset_lib.skx_ext_b(chips)!SKX_EXT_B_BGA1-IC,TBD!!!F124!DDR5_DQ(3)!!!!
S!M_M_DQ<40>!U2D1!DF33!@baseboard_fab2_lib.baseboard_fab2(sch_1):page62_i172@chpset_lib.skx_ext_b(chips)!SKX_EXT_B_BGA1-IC,TBD!!!F124!DDR5_DQ(40)!!!!
S!M_M_DQ<41>!U2D1!DK33!@baseboard_fab2_lib.baseboard_fab2(sch_1):page62_i172@chpset_lib.skx_ext_b(chips)!SKX_EXT_B_BGA1-IC,TBD!!!F124!DDR5_DQ(41)!!!!
S!M_M_DQ<42>!U2D1!DG30!@baseboard_fab2_lib.baseboard_fab2(sch_1):page62_i172@chpset_lib.skx_ext_b(chips)!SKX_EXT_B_BGA1-IC,TBD!!!F124!DDR5_DQ(42)!!!!
S!M_M_DQ<43>!U2D1!DJ30!@baseboard_fab2_lib.baseboard_fab2(sch_1):page62_i172@chpset_lib.skx_ext_b(chips)!SKX_EXT_B_BGA1-IC,TBD!!!F124!DDR5_DQ(43)!!!!
S!M_M_DQ<44>!U2D1!DG34!@baseboard_fab2_lib.baseboard_fab2(sch_1):page62_i172@chpset_lib.skx_ext_b(chips)!SKX_EXT_B_BGA1-IC,TBD!!!F124!DDR5_DQ(44)!!!!
S!M_M_DQ<45>!U2D1!DJ34!@baseboard_fab2_lib.baseboard_fab2(sch_1):page62_i172@chpset_lib.skx_ext_b(chips)!SKX_EXT_B_BGA1-IC,TBD!!!F124!DDR5_DQ(45)!!!!
S!M_M_DQ<46>!U2D1!DF31!@baseboard_fab2_lib.baseboard_fab2(sch_1):page62_i172@chpset_lib.skx_ext_b(chips)!SKX_EXT_B_BGA1-IC,TBD!!!F124!DDR5_DQ(46)!!!!
S!M_M_DQ<47>!U2D1!DK31!@baseboard_fab2_lib.baseboard_fab2(sch_1):page62_i172@chpset_lib.skx_ext_b(chips)!SKX_EXT_B_BGA1-IC,TBD!!!F124!DDR5_DQ(47)!!!!
S!M_M_DQ<48>!U2D1!CW36!@baseboard_fab2_lib.baseboard_fab2(sch_1):page62_i172@chpset_lib.skx_ext_b(chips)!SKX_EXT_B_BGA1-IC,TBD!!!F124!DDR5_DQ(48)!!!!
S!M_M_DQ<49>!U2D1!DC36!@baseboard_fab2_lib.baseboard_fab2(sch_1):page62_i172@chpset_lib.skx_ext_b(chips)!SKX_EXT_B_BGA1-IC,TBD!!!F124!DDR5_DQ(49)!!!!
S!M_M_DQ<4>!U2D1!CN74!@baseboard_fab2_lib.baseboard_fab2(sch_1):page62_i172@chpset_lib.skx_ext_b(chips)!SKX_EXT_B_BGA1-IC,TBD!!!F124!DDR5_DQ(4)!!!!
S!M_M_DQ<50>!U2D1!CY33!@baseboard_fab2_lib.baseboard_fab2(sch_1):page62_i172@chpset_lib.skx_ext_b(chips)!SKX_EXT_B_BGA1-IC,TBD!!!F124!DDR5_DQ(50)!!!!
S!M_M_DQ<51>!U2D1!DB33!@baseboard_fab2_lib.baseboard_fab2(sch_1):page62_i172@chpset_lib.skx_ext_b(chips)!SKX_EXT_B_BGA1-IC,TBD!!!F124!DDR5_DQ(51)!!!!
S!M_M_DQ<52>!U2D1!CY37!@baseboard_fab2_lib.baseboard_fab2(sch_1):page62_i172@chpset_lib.skx_ext_b(chips)!SKX_EXT_B_BGA1-IC,TBD!!!F124!DDR5_DQ(52)!!!!
S!M_M_DQ<53>!U2D1!DB37!@baseboard_fab2_lib.baseboard_fab2(sch_1):page62_i172@chpset_lib.skx_ext_b(chips)!SKX_EXT_B_BGA1-IC,TBD!!!F124!DDR5_DQ(53)!!!!
S!M_M_DQ<54>!U2D1!CW34!@baseboard_fab2_lib.baseboard_fab2(sch_1):page62_i172@chpset_lib.skx_ext_b(chips)!SKX_EXT_B_BGA1-IC,TBD!!!F124!DDR5_DQ(54)!!!!
S!M_M_DQ<55>!U2D1!DC34!@baseboard_fab2_lib.baseboard_fab2(sch_1):page62_i172@chpset_lib.skx_ext_b(chips)!SKX_EXT_B_BGA1-IC,TBD!!!F124!DDR5_DQ(55)!!!!
S!M_M_DQ<56>!U2D1!CW30!@baseboard_fab2_lib.baseboard_fab2(sch_1):page62_i172@chpset_lib.skx_ext_b(chips)!SKX_EXT_B_BGA1-IC,TBD!!!F124!DDR5_DQ(56)!!!!
S!M_M_DQ<57>!U2D1!DC30!@baseboard_fab2_lib.baseboard_fab2(sch_1):page62_i172@chpset_lib.skx_ext_b(chips)!SKX_EXT_B_BGA1-IC,TBD!!!F124!DDR5_DQ(57)!!!!
S!M_M_DQ<58>!U2D1!CY27!@baseboard_fab2_lib.baseboard_fab2(sch_1):page62_i172@chpset_lib.skx_ext_b(chips)!SKX_EXT_B_BGA1-IC,TBD!!!F124!DDR5_DQ(58)!!!!
S!M_M_DQ<59>!U2D1!DB27!@baseboard_fab2_lib.baseboard_fab2(sch_1):page62_i172@chpset_lib.skx_ext_b(chips)!SKX_EXT_B_BGA1-IC,TBD!!!F124!DDR5_DQ(59)!!!!
S!M_M_DQ<5>!U2D1!CM75!@baseboard_fab2_lib.baseboard_fab2(sch_1):page62_i172@chpset_lib.skx_ext_b(chips)!SKX_EXT_B_BGA1-IC,TBD!!!F124!DDR5_DQ(5)!!!!
S!M_M_DQ<60>!U2D1!CY31!@baseboard_fab2_lib.baseboard_fab2(sch_1):page62_i172@chpset_lib.skx_ext_b(chips)!SKX_EXT_B_BGA1-IC,TBD!!!F124!DDR5_DQ(60)!!!!
S!M_M_DQ<61>!U2D1!DB31!@baseboard_fab2_lib.baseboard_fab2(sch_1):page62_i172@chpset_lib.skx_ext_b(chips)!SKX_EXT_B_BGA1-IC,TBD!!!F124!DDR5_DQ(61)!!!!
S!M_M_DQ<62>!U2D1!CW28!@baseboard_fab2_lib.baseboard_fab2(sch_1):page62_i172@chpset_lib.skx_ext_b(chips)!SKX_EXT_B_BGA1-IC,TBD!!!F124!DDR5_DQ(62)!!!!
S!M_M_DQ<63>!U2D1!DC28!@baseboard_fab2_lib.baseboard_fab2(sch_1):page62_i172@chpset_lib.skx_ext_b(chips)!SKX_EXT_B_BGA1-IC,TBD!!!F124!DDR5_DQ(63)!!!!
S!M_M_DQ<6>!U2D1!CV75!@baseboard_fab2_lib.baseboard_fab2(sch_1):page62_i172@chpset_lib.skx_ext_b(chips)!SKX_EXT_B_BGA1-IC,TBD!!!F124!DDR5_DQ(6)!!!!
S!M_M_DQ<7>!U2D1!CT77!@baseboard_fab2_lib.baseboard_fab2(sch_1):page62_i172@chpset_lib.skx_ext_b(chips)!SKX_EXT_B_BGA1-IC,TBD!!!F124!DDR5_DQ(7)!!!!
S!M_M_DQ<8>!U2D1!DE74!@baseboard_fab2_lib.baseboard_fab2(sch_1):page62_i172@chpset_lib.skx_ext_b(chips)!SKX_EXT_B_BGA1-IC,TBD!!!F124!DDR5_DQ(8)!!!!
S!M_M_DQ<9>!U2D1!DC76!@baseboard_fab2_lib.baseboard_fab2(sch_1):page62_i172@chpset_lib.skx_ext_b(chips)!SKX_EXT_B_BGA1-IC,TBD!!!F124!DDR5_DQ(9)!!!!
S!M_M_DQS_DN<0>!U2D1!CP77!@baseboard_fab2_lib.baseboard_fab2(sch_1):page62_i172@chpset_lib.skx_ext_b(chips)!SKX_EXT_B_BGA1-IC,TBD!!!F124!DDR5_DQS_DN(0)!!!!
S!M_M_DQS_DN<10>!U2D1!DF75!@baseboard_fab2_lib.baseboard_fab2(sch_1):page62_i172@chpset_lib.skx_ext_b(chips)!SKX_EXT_B_BGA1-IC,TBD!!!F124!DDR5_DQS_DN(10)!!!!
S!M_M_DQS_DN<11>!U2D1!DJ70!@baseboard_fab2_lib.baseboard_fab2(sch_1):page62_i172@chpset_lib.skx_ext_b(chips)!SKX_EXT_B_BGA1-IC,TBD!!!F124!DDR5_DQS_DN(11)!!!!
S!M_M_DQS_DN<12>!U2D1!CP65!@baseboard_fab2_lib.baseboard_fab2(sch_1):page62_i172@chpset_lib.skx_ext_b(chips)!SKX_EXT_B_BGA1-IC,TBD!!!F124!DDR5_DQS_DN(12)!!!!
S!M_M_DQS_DN<13>!U2D1!DE40!@baseboard_fab2_lib.baseboard_fab2(sch_1):page62_i172@chpset_lib.skx_ext_b(chips)!SKX_EXT_B_BGA1-IC,TBD!!!F124!DDR5_DQS_DN(13)!!!!
S!M_M_DQS_DN<14>!U2D1!DG32!@baseboard_fab2_lib.baseboard_fab2(sch_1):page62_i172@chpset_lib.skx_ext_b(chips)!SKX_EXT_B_BGA1-IC,TBD!!!F124!DDR5_DQS_DN(14)!!!!
S!M_M_DQS_DN<15>!U2D1!CY35!@baseboard_fab2_lib.baseboard_fab2(sch_1):page62_i172@chpset_lib.skx_ext_b(chips)!SKX_EXT_B_BGA1-IC,TBD!!!F124!DDR5_DQS_DN(15)!!!!
S!M_M_DQS_DN<16>!U2D1!CY29!@baseboard_fab2_lib.baseboard_fab2(sch_1):page62_i172@chpset_lib.skx_ext_b(chips)!SKX_EXT_B_BGA1-IC,TBD!!!F124!DDR5_DQS_DN(16)!!!!
S!M_M_DQS_DN<17>!U2D1!CJ70!@baseboard_fab2_lib.baseboard_fab2(sch_1):page62_i172@chpset_lib.skx_ext_b(chips)!SKX_EXT_B_BGA1-IC,TBD!!!F124!DDR5_DQS_DN(17)!!!!
S!M_M_DQS_DN<1>!U2D1!DD77!@baseboard_fab2_lib.baseboard_fab2(sch_1):page62_i172@chpset_lib.skx_ext_b(chips)!SKX_EXT_B_BGA1-IC,TBD!!!F124!DDR5_DQS_DN(1)!!!!
S!M_M_DQS_DN<2>!U2D1!DL72!@baseboard_fab2_lib.baseboard_fab2(sch_1):page62_i172@chpset_lib.skx_ext_b(chips)!SKX_EXT_B_BGA1-IC,TBD!!!F124!DDR5_DQS_DN(2)!!!!
S!M_M_DQS_DN<3>!U2D1!CV65!@baseboard_fab2_lib.baseboard_fab2(sch_1):page62_i172@chpset_lib.skx_ext_b(chips)!SKX_EXT_B_BGA1-IC,TBD!!!F124!DDR5_DQS_DN(3)!!!!
S!M_M_DQS_DN<4>!U2D1!DG40!@baseboard_fab2_lib.baseboard_fab2(sch_1):page62_i172@chpset_lib.skx_ext_b(chips)!SKX_EXT_B_BGA1-IC,TBD!!!F124!DDR5_DQS_DN(4)!!!!
S!M_M_DQS_DN<5>!U2D1!DL32!@baseboard_fab2_lib.baseboard_fab2(sch_1):page62_i172@chpset_lib.skx_ext_b(chips)!SKX_EXT_B_BGA1-IC,TBD!!!F124!DDR5_DQS_DN(5)!!!!
S!M_M_DQS_DN<6>!U2D1!DD35!@baseboard_fab2_lib.baseboard_fab2(sch_1):page62_i172@chpset_lib.skx_ext_b(chips)!SKX_EXT_B_BGA1-IC,TBD!!!F124!DDR5_DQS_DN(6)!!!!
S!M_M_DQS_DN<7>!U2D1!DD29!@baseboard_fab2_lib.baseboard_fab2(sch_1):page62_i172@chpset_lib.skx_ext_b(chips)!SKX_EXT_B_BGA1-IC,TBD!!!F124!DDR5_DQS_DN(7)!!!!
S!M_M_DQS_DN<8>!U2D1!CN70!@baseboard_fab2_lib.baseboard_fab2(sch_1):page62_i172@chpset_lib.skx_ext_b(chips)!SKX_EXT_B_BGA1-IC,TBD!!!F124!DDR5_DQS_DN(8)!!!!
S!M_M_DQS_DN<9>!U2D1!CT75!@baseboard_fab2_lib.baseboard_fab2(sch_1):page62_i172@chpset_lib.skx_ext_b(chips)!SKX_EXT_B_BGA1-IC,TBD!!!F124!DDR5_DQS_DN(9)!!!!
S!M_M_DQS_DP<0>!U2D1!CR76!@baseboard_fab2_lib.baseboard_fab2(sch_1):page62_i172@chpset_lib.skx_ext_b(chips)!SKX_EXT_B_BGA1-IC,TBD!!!F124!DDR5_DQS_DP(0)!!!!
S!M_M_DQS_DP<10>!U2D1!DG74!@baseboard_fab2_lib.baseboard_fab2(sch_1):page62_i172@chpset_lib.skx_ext_b(chips)!SKX_EXT_B_BGA1-IC,TBD!!!F124!DDR5_DQS_DP(10)!!!!
S!M_M_DQS_DP<11>!U2D1!DH69!@baseboard_fab2_lib.baseboard_fab2(sch_1):page62_i172@chpset_lib.skx_ext_b(chips)!SKX_EXT_B_BGA1-IC,TBD!!!F124!DDR5_DQS_DP(11)!!!!
S!M_M_DQS_DP<12>!U2D1!CM65!@baseboard_fab2_lib.baseboard_fab2(sch_1):page62_i172@chpset_lib.skx_ext_b(chips)!SKX_EXT_B_BGA1-IC,TBD!!!F124!DDR5_DQS_DP(12)!!!!
S!M_M_DQS_DP<13>!U2D1!DC40!@baseboard_fab2_lib.baseboard_fab2(sch_1):page62_i172@chpset_lib.skx_ext_b(chips)!SKX_EXT_B_BGA1-IC,TBD!!!F124!DDR5_DQS_DP(13)!!!!
S!M_M_DQS_DP<14>!U2D1!DE32!@baseboard_fab2_lib.baseboard_fab2(sch_1):page62_i172@chpset_lib.skx_ext_b(chips)!SKX_EXT_B_BGA1-IC,TBD!!!F124!DDR5_DQS_DP(14)!!!!
S!M_M_DQS_DP<15>!U2D1!CV35!@baseboard_fab2_lib.baseboard_fab2(sch_1):page62_i172@chpset_lib.skx_ext_b(chips)!SKX_EXT_B_BGA1-IC,TBD!!!F124!DDR5_DQS_DP(15)!!!!
S!M_M_DQS_DP<16>!U2D1!CV29!@baseboard_fab2_lib.baseboard_fab2(sch_1):page62_i172@chpset_lib.skx_ext_b(chips)!SKX_EXT_B_BGA1-IC,TBD!!!F124!DDR5_DQS_DP(16)!!!!
S!M_M_DQS_DP<17>!U2D1!CG70!@baseboard_fab2_lib.baseboard_fab2(sch_1):page62_i172@chpset_lib.skx_ext_b(chips)!SKX_EXT_B_BGA1-IC,TBD!!!F124!DDR5_DQS_DP(17)!!!!
S!M_M_DQS_DP<1>!U2D1!DE76!@baseboard_fab2_lib.baseboard_fab2(sch_1):page62_i172@chpset_lib.skx_ext_b(chips)!SKX_EXT_B_BGA1-IC,TBD!!!F124!DDR5_DQS_DP(1)!!!!
S!M_M_DQS_DP<2>!U2D1!DK71!@baseboard_fab2_lib.baseboard_fab2(sch_1):page62_i172@chpset_lib.skx_ext_b(chips)!SKX_EXT_B_BGA1-IC,TBD!!!F124!DDR5_DQS_DP(2)!!!!
S!M_M_DQS_DP<3>!U2D1!CT65!@baseboard_fab2_lib.baseboard_fab2(sch_1):page62_i172@chpset_lib.skx_ext_b(chips)!SKX_EXT_B_BGA1-IC,TBD!!!F124!DDR5_DQS_DP(3)!!!!
S!M_M_DQS_DP<4>!U2D1!DJ40!@baseboard_fab2_lib.baseboard_fab2(sch_1):page62_i172@chpset_lib.skx_ext_b(chips)!SKX_EXT_B_BGA1-IC,TBD!!!F124!DDR5_DQS_DP(4)!!!!
S!M_M_DQS_DP<5>!U2D1!DJ32!@baseboard_fab2_lib.baseboard_fab2(sch_1):page62_i172@chpset_lib.skx_ext_b(chips)!SKX_EXT_B_BGA1-IC,TBD!!!F124!DDR5_DQS_DP(5)!!!!
S!M_M_DQS_DP<6>!U2D1!DB35!@baseboard_fab2_lib.baseboard_fab2(sch_1):page62_i172@chpset_lib.skx_ext_b(chips)!SKX_EXT_B_BGA1-IC,TBD!!!F124!DDR5_DQS_DP(6)!!!!
S!M_M_DQS_DP<7>!U2D1!DB29!@baseboard_fab2_lib.baseboard_fab2(sch_1):page62_i172@chpset_lib.skx_ext_b(chips)!SKX_EXT_B_BGA1-IC,TBD!!!F124!DDR5_DQS_DP(7)!!!!
S!M_M_DQS_DP<8>!U2D1!CL70!@baseboard_fab2_lib.baseboard_fab2(sch_1):page62_i172@chpset_lib.skx_ext_b(chips)!SKX_EXT_B_BGA1-IC,TBD!!!F124!DDR5_DQS_DP(8)!!!!
S!M_M_DQS_DP<9>!U2D1!CU74!@baseboard_fab2_lib.baseboard_fab2(sch_1):page62_i172@chpset_lib.skx_ext_b(chips)!SKX_EXT_B_BGA1-IC,TBD!!!F124!DDR5_DQS_DP(9)!!!!
S!M_M_ECC<0>!U2D1!CH71!@baseboard_fab2_lib.baseboard_fab2(sch_1):page62_i172@chpset_lib.skx_ext_b(chips)!SKX_EXT_B_BGA1-IC,TBD!!!F124!DDR5_ECC(0)!!!!
S!M_M_ECC<1>!U2D1!CM71!@baseboard_fab2_lib.baseboard_fab2(sch_1):page62_i172@chpset_lib.skx_ext_b(chips)!SKX_EXT_B_BGA1-IC,TBD!!!F124!DDR5_ECC(1)!!!!
S!M_M_ECC<2>!U2D1!CJ68!@baseboard_fab2_lib.baseboard_fab2(sch_1):page62_i172@chpset_lib.skx_ext_b(chips)!SKX_EXT_B_BGA1-IC,TBD!!!F124!DDR5_ECC(2)!!!!
S!M_M_ECC<3>!U2D1!CL68!@baseboard_fab2_lib.baseboard_fab2(sch_1):page62_i172@chpset_lib.skx_ext_b(chips)!SKX_EXT_B_BGA1-IC,TBD!!!F124!DDR5_ECC(3)!!!!
S!M_M_ECC<4>!U2D1!CJ72!@baseboard_fab2_lib.baseboard_fab2(sch_1):page62_i172@chpset_lib.skx_ext_b(chips)!SKX_EXT_B_BGA1-IC,TBD!!!F124!DDR5_ECC(4)!!!!
S!M_M_ECC<5>!U2D1!CL72!@baseboard_fab2_lib.baseboard_fab2(sch_1):page62_i172@chpset_lib.skx_ext_b(chips)!SKX_EXT_B_BGA1-IC,TBD!!!F124!DDR5_ECC(5)!!!!
S!M_M_ECC<6>!U2D1!CH69!@baseboard_fab2_lib.baseboard_fab2(sch_1):page62_i172@chpset_lib.skx_ext_b(chips)!SKX_EXT_B_BGA1-IC,TBD!!!F124!DDR5_ECC(6)!!!!
S!M_M_ECC<7>!U2D1!CM69!@baseboard_fab2_lib.baseboard_fab2(sch_1):page62_i172@chpset_lib.skx_ext_b(chips)!SKX_EXT_B_BGA1-IC,TBD!!!F124!DDR5_ECC(7)!!!!
S!M_M_MA<0>!U2D1!DF53!@baseboard_fab2_lib.baseboard_fab2(sch_1):page62_i172@chpset_lib.skx_ext_b(chips)!SKX_EXT_B_BGA1-IC,TBD!!!F124!DDR5_MA(0)!!!!
S!M_M_MA<10>!U2D1!DD55!@baseboard_fab2_lib.baseboard_fab2(sch_1):page62_i172@chpset_lib.skx_ext_b(chips)!SKX_EXT_B_BGA1-IC,TBD!!!F124!DDR5_MA(10)!!!!
S!M_M_MA<11>!U2D1!DA60!@baseboard_fab2_lib.baseboard_fab2(sch_1):page62_i172@chpset_lib.skx_ext_b(chips)!SKX_EXT_B_BGA1-IC,TBD!!!F124!DDR5_MA(11)!!!!
S!M_M_MA<12>!U2D1!DG60!@baseboard_fab2_lib.baseboard_fab2(sch_1):page62_i172@chpset_lib.skx_ext_b(chips)!SKX_EXT_B_BGA1-IC,TBD!!!F124!DDR5_MA(12)!!!!
S!M_M_MA<13>!U2D1!DD53!@baseboard_fab2_lib.baseboard_fab2(sch_1):page62_i172@chpset_lib.skx_ext_b(chips)!SKX_EXT_B_BGA1-IC,TBD!!!F124!DDR5_MA(13)!!!!
S!M_M_MA<14>!U2D1!DJ50!@baseboard_fab2_lib.baseboard_fab2(sch_1):page62_i172@chpset_lib.skx_ext_b(chips)!SKX_EXT_B_BGA1-IC,TBD!!!F124!DDR5_MA(14)!!!!
S!M_M_MA<15>!U2D1!DC54!@baseboard_fab2_lib.baseboard_fab2(sch_1):page62_i172@chpset_lib.skx_ext_b(chips)!SKX_EXT_B_BGA1-IC,TBD!!!F124!DDR5_MA(15)!!!!
S!M_M_MA<16>!U2D1!DG52!@baseboard_fab2_lib.baseboard_fab2(sch_1):page62_i172@chpset_lib.skx_ext_b(chips)!SKX_EXT_B_BGA1-IC,TBD!!!F124!DDR5_MA(16)!!!!
S!M_M_MA<17>!U2D1!DE46!@baseboard_fab2_lib.baseboard_fab2(sch_1):page62_i172@chpset_lib.skx_ext_b(chips)!SKX_EXT_B_BGA1-IC,TBD!!!F124!DDR5_MA(17)!!!!
S!M_M_MA<1>!U2D1!DC58!@baseboard_fab2_lib.baseboard_fab2(sch_1):page62_i172@chpset_lib.skx_ext_b(chips)!SKX_EXT_B_BGA1-IC,TBD!!!F124!DDR5_MA(1)!!!!
S!M_M_MA<2>!U2D1!DD57!@baseboard_fab2_lib.baseboard_fab2(sch_1):page62_i172@chpset_lib.skx_ext_b(chips)!SKX_EXT_B_BGA1-IC,TBD!!!F124!DDR5_MA(2)!!!!
S!M_M_MA<3>!U2D1!DG58!@baseboard_fab2_lib.baseboard_fab2(sch_1):page62_i172@chpset_lib.skx_ext_b(chips)!SKX_EXT_B_BGA1-IC,TBD!!!F124!DDR5_MA(3)!!!!
S!M_M_MA<4>!U2D1!DJ58!@baseboard_fab2_lib.baseboard_fab2(sch_1):page62_i172@chpset_lib.skx_ext_b(chips)!SKX_EXT_B_BGA1-IC,TBD!!!F124!DDR5_MA(4)!!!!
S!M_M_MA<5>!U2D1!DF59!@baseboard_fab2_lib.baseboard_fab2(sch_1):page62_i172@chpset_lib.skx_ext_b(chips)!SKX_EXT_B_BGA1-IC,TBD!!!F124!DDR5_MA(5)!!!!
S!M_M_MA<6>!U2D1!DK59!@baseboard_fab2_lib.baseboard_fab2(sch_1):page62_i172@chpset_lib.skx_ext_b(chips)!SKX_EXT_B_BGA1-IC,TBD!!!F124!DDR5_MA(6)!!!!
S!M_M_MA<7>!U2D1!DC60!@baseboard_fab2_lib.baseboard_fab2(sch_1):page62_i172@chpset_lib.skx_ext_b(chips)!SKX_EXT_B_BGA1-IC,TBD!!!F124!DDR5_MA(7)!!!!
S!M_M_MA<8>!U2D1!DD59!@baseboard_fab2_lib.baseboard_fab2(sch_1):page62_i172@chpset_lib.skx_ext_b(chips)!SKX_EXT_B_BGA1-IC,TBD!!!F124!DDR5_MA(8)!!!!
S!M_M_MA<9>!U2D1!DA58!@baseboard_fab2_lib.baseboard_fab2(sch_1):page62_i172@chpset_lib.skx_ext_b(chips)!SKX_EXT_B_BGA1-IC,TBD!!!F124!DDR5_MA(9)!!!!
S!M_M_ODT<0>!U2D1!DG50!@baseboard_fab2_lib.baseboard_fab2(sch_1):page62_i172@chpset_lib.skx_ext_b(chips)!SKX_EXT_B_BGA1-IC,TBD!!!F124!DDR5_ODT(0)!!!!
S!M_M_ODT<1>!U2D1!DG48!@baseboard_fab2_lib.baseboard_fab2(sch_1):page62_i172@chpset_lib.skx_ext_b(chips)!SKX_EXT_B_BGA1-IC,TBD!!!F124!DDR5_ODT(1)!!!!
S!M_M_ODT<2>!U2D1!DK49!@baseboard_fab2_lib.baseboard_fab2(sch_1):page62_i172@chpset_lib.skx_ext_b(chips)!SKX_EXT_B_BGA1-IC,TBD!!!F124!DDR5_ODT(2)!!!!
S!M_M_ODT<3>!U2D1!DF47!@baseboard_fab2_lib.baseboard_fab2(sch_1):page62_i172@chpset_lib.skx_ext_b(chips)!SKX_EXT_B_BGA1-IC,TBD!!!F124!DDR5_ODT(3)!!!!
S!M_M_PAR!U2D1!DK53!@baseboard_fab2_lib.baseboard_fab2(sch_1):page62_i172@chpset_lib.skx_ext_b(chips)!SKX_EXT_B_BGA1-IC,TBD!!!F124!DDR5_PAR!!!!
S!TP_SMB_CPU1_CD_HFI0_I2CCLK!U2D1!BN22!@baseboard_fab2_lib.baseboard_fab2(sch_1):page63_i23@chpset_lib.skx_ext_b(chips)!SKX_EXT_B_BGA1-IC,TBD!!!F123!CD_HFI0_I2CCLK!!!!
S!TP_SMB_CPU1_CD_HFI0_I2CDAT!U2D1!BP23!@baseboard_fab2_lib.baseboard_fab2(sch_1):page63_i23@chpset_lib.skx_ext_b(chips)!SKX_EXT_B_BGA1-IC,TBD!!!F123!CD_HFI0_I2CDAT!!!!
S!TP_IRQ_CPU1_CD_HFI0_N!U2D1!BP19!@baseboard_fab2_lib.baseboard_fab2(sch_1):page63_i23@chpset_lib.skx_ext_b(chips)!SKX_EXT_B_BGA1-IC,TBD!!!F123!CD_HFI0_INT_N!!!!
S!TP_LED_CPU1_CD_HFI0_N!U2D1!BK21!@baseboard_fab2_lib.baseboard_fab2(sch_1):page63_i23@chpset_lib.skx_ext_b(chips)!SKX_EXT_B_BGA1-IC,TBD!!!F123!CD_HFI0_LED_N!!!!
S!TP_FM_CPU1_CD_HFI0_MODPRST_N!U2D1!BR20!@baseboard_fab2_lib.baseboard_fab2(sch_1):page63_i23@chpset_lib.skx_ext_b(chips)!SKX_EXT_B_BGA1-IC,TBD!!!F123!CD_HFI0_MODPRST_N!!!!
S!TP_RST_CPU1_CD_HFI0_N!U2D1!BN24!@baseboard_fab2_lib.baseboard_fab2(sch_1):page63_i23@chpset_lib.skx_ext_b(chips)!SKX_EXT_B_BGA1-IC,TBD!!!F123!CD_HFI0_RESET_N!!!!
S!TP_CD_HFI1_CPU1_I2CLK!U2D1!BJ22!@baseboard_fab2_lib.baseboard_fab2(sch_1):page63_i23@chpset_lib.skx_ext_b(chips)!SKX_EXT_B_BGA1-IC,TBD!!!F123!CD_HFI1_I2CCLK!!!!
S!TP_CD_HFI1_CPU1_I2CDAT!U2D1!BH23!@baseboard_fab2_lib.baseboard_fab2(sch_1):page63_i23@chpset_lib.skx_ext_b(chips)!SKX_EXT_B_BGA1-IC,TBD!!!F123!CD_HFI1_I2CDAT!!!!
S!TP_CD_HFI1_CPU1_INT_N!U2D1!BM21!@baseboard_fab2_lib.baseboard_fab2(sch_1):page63_i23@chpset_lib.skx_ext_b(chips)!SKX_EXT_B_BGA1-IC,TBD!!!F123!CD_HFI1_INT_N!!!!
S!TP_CD_HFI1_CPU1_LED_N!U2D1!BM23!@baseboard_fab2_lib.baseboard_fab2(sch_1):page63_i23@chpset_lib.skx_ext_b(chips)!SKX_EXT_B_BGA1-IC,TBD!!!F123!CD_HFI1_LED_N!!!!
S!TP_CD_HFI1_CPU1_MODPRST_N!U2D1!BT19!@baseboard_fab2_lib.baseboard_fab2(sch_1):page63_i23@chpset_lib.skx_ext_b(chips)!SKX_EXT_B_BGA1-IC,TBD!!!F123!CD_HFI1_MODPRST_N!!!!
S!TP_CD_HFI1_CPU1_RESET_N!U2D1!BK23!@baseboard_fab2_lib.baseboard_fab2(sch_1):page63_i23@chpset_lib.skx_ext_b(chips)!SKX_EXT_B_BGA1-IC,TBD!!!F123!CD_HFI1_RESET_N!!!!
S!CLK_156M_OSC_CPU1_HFI_DN!U2D1!BE16!@baseboard_fab2_lib.baseboard_fab2(sch_1):page63_i23@chpset_lib.skx_ext_b(chips)!SKX_EXT_B_BGA1-IC,TBD!!!F123!CD_HFI_REFCLK_DN!!!!
S!CLK_156M_OSC_CPU1_HFI_DP!U2D1!BG16!@baseboard_fab2_lib.baseboard_fab2(sch_1):page63_i23@chpset_lib.skx_ext_b(chips)!SKX_EXT_B_BGA1-IC,TBD!!!F123!CD_HFI_REFCLK_DP!!!!
S!CLK_100M_CPU1_PE_REFCLK_DN!U2D1!BU24!@baseboard_fab2_lib.baseboard_fab2(sch_1):page63_i23@chpset_lib.skx_ext_b(chips)!SKX_EXT_B_BGA1-IC,TBD!!!F123!CD_PE_REFCLK_DN!!!!
S!CLK_100M_CPU1_PE_REFCLK_DP!U2D1!BW24!@baseboard_fab2_lib.baseboard_fab2(sch_1):page63_i23@chpset_lib.skx_ext_b(chips)!SKX_EXT_B_BGA1-IC,TBD!!!F123!CD_PE_REFCLK_DP!!!!
S!RST_CD_CPU1_POR_N!U2D1!CF25!@baseboard_fab2_lib.baseboard_fab2(sch_1):page63_i23@chpset_lib.skx_ext_b(chips)!SKX_EXT_B_BGA1-IC,TBD!!!F123!CD_POR_N!!!!
S!JTAG_MCP_TCK!U2D1!CB23!@baseboard_fab2_lib.baseboard_fab2(sch_1):page63_i23@chpset_lib.skx_ext_b(chips)!SKX_EXT_B_BGA1-IC,TBD!!!F123!CD_TCLK!!!!
S!JTAG_MCP_CPU1_TDI!U2D1!BY21!@baseboard_fab2_lib.baseboard_fab2(sch_1):page63_i23@chpset_lib.skx_ext_b(chips)!SKX_EXT_B_BGA1-IC,TBD!!!F123!CD_TDI!!!!
S!JTAG_MCP_CPU1_TDO!U2D1!CC22!@baseboard_fab2_lib.baseboard_fab2(sch_1):page63_i23@chpset_lib.skx_ext_b(chips)!SKX_EXT_B_BGA1-IC,TBD!!!F123!CD_TDO!!!!
S!JTAG_MCP_TMS!U2D1!CE24!@baseboard_fab2_lib.baseboard_fab2(sch_1):page63_i23@chpset_lib.skx_ext_b(chips)!SKX_EXT_B_BGA1-IC,TBD!!!F123!CD_TMS!!!!
S!JTAG_MCP_TRST_N!U2D1!CD23!@baseboard_fab2_lib.baseboard_fab2(sch_1):page63_i23@chpset_lib.skx_ext_b(chips)!SKX_EXT_B_BGA1-IC,TBD!!!F123!CD_TRST_N!!!!
S!TP_CPU1_DMI_RX_DN0!U2D1!CK9!@baseboard_fab2_lib.baseboard_fab2(sch_1):page63_i23@chpset_lib.skx_ext_b(chips)!SKX_EXT_B_BGA1-IC,TBD!!!F123!DMI_RX_DN(0)!!!!
S!TP_CPU1_DMI_RX_DN1!U2D1!CM11!@baseboard_fab2_lib.baseboard_fab2(sch_1):page63_i23@chpset_lib.skx_ext_b(chips)!SKX_EXT_B_BGA1-IC,TBD!!!F123!DMI_RX_DN(1)!!!!
S!TP_CPU1_DMI_RX_DN2!U2D1!CR12!@baseboard_fab2_lib.baseboard_fab2(sch_1):page63_i23@chpset_lib.skx_ext_b(chips)!SKX_EXT_B_BGA1-IC,TBD!!!F123!DMI_RX_DN(2)!!!!
S!TP_CPU1_DMI_RX_DN3!U2D1!CT11!@baseboard_fab2_lib.baseboard_fab2(sch_1):page63_i23@chpset_lib.skx_ext_b(chips)!SKX_EXT_B_BGA1-IC,TBD!!!F123!DMI_RX_DN(3)!!!!
S!TP_CPU1_DMI_RX_DP0!U2D1!CL10!@baseboard_fab2_lib.baseboard_fab2(sch_1):page63_i23@chpset_lib.skx_ext_b(chips)!SKX_EXT_B_BGA1-IC,TBD!!!F123!DMI_RX_DP(0)!!!!
S!TP_CPU1_DMI_RX_DP1!U2D1!CN10!@baseboard_fab2_lib.baseboard_fab2(sch_1):page63_i23@chpset_lib.skx_ext_b(chips)!SKX_EXT_B_BGA1-IC,TBD!!!F123!DMI_RX_DP(1)!!!!
S!TP_CPU1_DMI_RX_DP2!U2D1!CP11!@baseboard_fab2_lib.baseboard_fab2(sch_1):page63_i23@chpset_lib.skx_ext_b(chips)!SKX_EXT_B_BGA1-IC,TBD!!!F123!DMI_RX_DP(2)!!!!
S!TP_CPU1_DMI_RX_DP3!U2D1!CV11!@baseboard_fab2_lib.baseboard_fab2(sch_1):page63_i23@chpset_lib.skx_ext_b(chips)!SKX_EXT_B_BGA1-IC,TBD!!!F123!DMI_RX_DP(3)!!!!
S!TP_CPU1_DMI_TX_DN0!U2D1!CG4!@baseboard_fab2_lib.baseboard_fab2(sch_1):page63_i23@chpset_lib.skx_ext_b(chips)!SKX_EXT_B_BGA1-IC,TBD!!!F123!DMI_TX_DN(0)!!!!
S!TP_CPU1_DMI_TX_DN1!U2D1!CJ4!@baseboard_fab2_lib.baseboard_fab2(sch_1):page63_i23@chpset_lib.skx_ext_b(chips)!SKX_EXT_B_BGA1-IC,TBD!!!F123!DMI_TX_DN(1)!!!!
S!TP_CPU1_DMI_TX_DN2!U2D1!CN4!@baseboard_fab2_lib.baseboard_fab2(sch_1):page63_i23@chpset_lib.skx_ext_b(chips)!SKX_EXT_B_BGA1-IC,TBD!!!F123!DMI_TX_DN(2)!!!!
S!TP_CPU1_DMI_TX_DN3!U2D1!CP5!@baseboard_fab2_lib.baseboard_fab2(sch_1):page63_i23@chpset_lib.skx_ext_b(chips)!SKX_EXT_B_BGA1-IC,TBD!!!F123!DMI_TX_DN(3)!!!!
S!TP_CPU1_DMI_TX_DP0!U2D1!CH5!@baseboard_fab2_lib.baseboard_fab2(sch_1):page63_i23@chpset_lib.skx_ext_b(chips)!SKX_EXT_B_BGA1-IC,TBD!!!F123!DMI_TX_DP(0)!!!!
S!TP_CPU1_DMI_TX_DP1!U2D1!CL4!@baseboard_fab2_lib.baseboard_fab2(sch_1):page63_i23@chpset_lib.skx_ext_b(chips)!SKX_EXT_B_BGA1-IC,TBD!!!F123!DMI_TX_DP(1)!!!!
S!TP_CPU1_DMI_TX_DP2!U2D1!CM3!@baseboard_fab2_lib.baseboard_fab2(sch_1):page63_i23@chpset_lib.skx_ext_b(chips)!SKX_EXT_B_BGA1-IC,TBD!!!F123!DMI_TX_DP(2)!!!!
S!TP_CPU1_DMI_TX_DP3!U2D1!CR4!@baseboard_fab2_lib.baseboard_fab2(sch_1):page63_i23@chpset_lib.skx_ext_b(chips)!SKX_EXT_B_BGA1-IC,TBD!!!F123!DMI_TX_DP(3)!!!!
S!CLK_322M_OSC_CPU1_RC_DN!U2D1!AL26!@baseboard_fab2_lib.baseboard_fab2(sch_1):page56_i169@chpset_lib.skx_ext_b(chips)!SKX_EXT_B_BGA1-IC,TBD!!!F130!RSVD(213)!!!!
S!CLK_322M_OSC_CPU1_RC_DP!U2D1!AK27!@baseboard_fab2_lib.baseboard_fab2(sch_1):page56_i169@chpset_lib.skx_ext_b(chips)!SKX_EXT_B_BGA1-IC,TBD!!!F130!RSVD(220)!!!!
S!TP_CPU1_RSVD_242!U2D1!AF53!@baseboard_fab2_lib.baseboard_fab2(sch_1):page56_i169@chpset_lib.skx_ext_b(chips)!SKX_EXT_B_BGA1-IC,TBD!!!F130!RSVD(242)!!!!
S!TP_CPU1_RSVD_237!U2D1!AG52!@baseboard_fab2_lib.baseboard_fab2(sch_1):page56_i169@chpset_lib.skx_ext_b(chips)!SKX_EXT_B_BGA1-IC,TBD!!!F130!RSVD(237)!!!!
S!TP_CPU1_RSVD_236!U2D1!AG54!@baseboard_fab2_lib.baseboard_fab2(sch_1):page56_i169@chpset_lib.skx_ext_b(chips)!SKX_EXT_B_BGA1-IC,TBD!!!F130!RSVD(236)!!!!
S!TP_CPU1_RSVD_231!U2D1!AH55!@baseboard_fab2_lib.baseboard_fab2(sch_1):page56_i169@chpset_lib.skx_ext_b(chips)!SKX_EXT_B_BGA1-IC,TBD!!!F130!RSVD(231)!!!!
S!TP_CPU1_RSVD_235!U2D1!AG56!@baseboard_fab2_lib.baseboard_fab2(sch_1):page56_i169@chpset_lib.skx_ext_b(chips)!SKX_EXT_B_BGA1-IC,TBD!!!F130!RSVD(235)!!!!
S!TP_CPU1_RSVD_226!U2D1!AJ56!@baseboard_fab2_lib.baseboard_fab2(sch_1):page56_i169@chpset_lib.skx_ext_b(chips)!SKX_EXT_B_BGA1-IC,TBD!!!F130!RSVD(226)!!!!
S!TP_CPU1_RSVD_219!U2D1!AK57!@baseboard_fab2_lib.baseboard_fab2(sch_1):page56_i169@chpset_lib.skx_ext_b(chips)!SKX_EXT_B_BGA1-IC,TBD!!!F130!RSVD(219)!!!!
S!TP_CPU1_RSVD_248!U2D1!AE52!@baseboard_fab2_lib.baseboard_fab2(sch_1):page56_i169@chpset_lib.skx_ext_b(chips)!SKX_EXT_B_BGA1-IC,TBD!!!F130!RSVD(248)!!!!
S!TP_CPU1_RSVD_250!U2D1!AE48!@baseboard_fab2_lib.baseboard_fab2(sch_1):page56_i169@chpset_lib.skx_ext_b(chips)!SKX_EXT_B_BGA1-IC,TBD!!!F130!RSVD(250)!!!!
S!TP_CPU1_RSVD_239!U2D1!AG48!@baseboard_fab2_lib.baseboard_fab2(sch_1):page56_i169@chpset_lib.skx_ext_b(chips)!SKX_EXT_B_BGA1-IC,TBD!!!F130!RSVD(239)!!!!
S!TP_CPU1_RSVD_244!U2D1!AF49!@baseboard_fab2_lib.baseboard_fab2(sch_1):page56_i169@chpset_lib.skx_ext_b(chips)!SKX_EXT_B_BGA1-IC,TBD!!!F130!RSVD(244)!!!!
S!TP_CPU1_RSVD_253!U2D1!AD49!@baseboard_fab2_lib.baseboard_fab2(sch_1):page56_i169@chpset_lib.skx_ext_b(chips)!SKX_EXT_B_BGA1-IC,TBD!!!F130!RSVD(253)!!!!
S!TP_CPU1_RSVD_249!U2D1!AE50!@baseboard_fab2_lib.baseboard_fab2(sch_1):page56_i169@chpset_lib.skx_ext_b(chips)!SKX_EXT_B_BGA1-IC,TBD!!!F130!RSVD(249)!!!!
S!TP_CPU1_RSVD_238!U2D1!AG50!@baseboard_fab2_lib.baseboard_fab2(sch_1):page56_i169@chpset_lib.skx_ext_b(chips)!SKX_EXT_B_BGA1-IC,TBD!!!F130!RSVD(238)!!!!
S!TP_CPU1_RSVD_243!U2D1!AF51!@baseboard_fab2_lib.baseboard_fab2(sch_1):page56_i169@chpset_lib.skx_ext_b(chips)!SKX_EXT_B_BGA1-IC,TBD!!!F130!RSVD(243)!!!!
S!TP_CPU1_RSVD_252!U2D1!AD51!@baseboard_fab2_lib.baseboard_fab2(sch_1):page56_i169@chpset_lib.skx_ext_b(chips)!SKX_EXT_B_BGA1-IC,TBD!!!F130!RSVD(252)!!!!
S!CLK_100M_CPU1_RC_REFCLK0_DN!U2D1!AP27!@baseboard_fab2_lib.baseboard_fab2(sch_1):page56_i169@chpset_lib.skx_ext_b(chips)!SKX_EXT_B_BGA1-IC,TBD!!!F130!RSVD(195)!!!!
S!PVCCIO_CPU1!U2D1!AR28!@baseboard_fab2_lib.baseboard_fab2(sch_1):page72_i33@chpset_lib.skx_ext_b(chips)!SKX_EXT_B_BGA1-IC,TBD!!!F111!VCCIO(104)!!!!
S!TP_P3E_CPU1_PE1_MP_RXN<0>!U2D1!CW8!@baseboard_fab2_lib.baseboard_fab2(sch_1):page64_i68@chpset_lib.skx_ext_b(chips)!SKX_EXT_B_BGA1-IC,TBD!!!F122!PE1_RX_DN(0)!!!!
S!TP_P3E_CPU1_PE1_RSR3_RXN<10>!U2D1!DT11!@baseboard_fab2_lib.baseboard_fab2(sch_1):page64_i68@chpset_lib.skx_ext_b(chips)!SKX_EXT_B_BGA1-IC,TBD!!!F122!PE1_RX_DN(10)!!!!
S!TP_P3E_CPU1_PE1_RSR3_RXN<11>!U2D1!DT13!@baseboard_fab2_lib.baseboard_fab2(sch_1):page64_i68@chpset_lib.skx_ext_b(chips)!SKX_EXT_B_BGA1-IC,TBD!!!F122!PE1_RX_DN(11)!!!!
S!TP_P3E_CPU1_PE1_RSR3_RXN<12>!U2D1!DV13!@baseboard_fab2_lib.baseboard_fab2(sch_1):page64_i68@chpset_lib.skx_ext_b(chips)!SKX_EXT_B_BGA1-IC,TBD!!!F122!PE1_RX_DN(12)!!!!
S!TP_P3E_CPU1_PE1_RSR3_RXN<13>!U2D1!DW14!@baseboard_fab2_lib.baseboard_fab2(sch_1):page64_i68@chpset_lib.skx_ext_b(chips)!SKX_EXT_B_BGA1-IC,TBD!!!F122!PE1_RX_DN(13)!!!!
S!TP_P3E_CPU1_PE1_RSR3_RXN<14>!U2D1!DY15!@baseboard_fab2_lib.baseboard_fab2(sch_1):page64_i68@chpset_lib.skx_ext_b(chips)!SKX_EXT_B_BGA1-IC,TBD!!!F122!PE1_RX_DN(14)!!!!
S!TP_P3E_CPU1_PE1_RSR3_RXN<15>!U2D1!DU16!@baseboard_fab2_lib.baseboard_fab2(sch_1):page64_i68@chpset_lib.skx_ext_b(chips)!SKX_EXT_B_BGA1-IC,TBD!!!F122!PE1_RX_DN(15)!!!!
S!TP_P3E_CPU1_PE1_MP_RXN<1>!U2D1!DA8!@baseboard_fab2_lib.baseboard_fab2(sch_1):page64_i68@chpset_lib.skx_ext_b(chips)!SKX_EXT_B_BGA1-IC,TBD!!!F122!PE1_RX_DN(1)!!!!
S!TP_P3E_CPU1_PE1_MP_RXN<2>!U2D1!DC8!@baseboard_fab2_lib.baseboard_fab2(sch_1):page64_i68@chpset_lib.skx_ext_b(chips)!SKX_EXT_B_BGA1-IC,TBD!!!F122!PE1_RX_DN(2)!!!!
S!TP_P3E_CPU1_PE1_MP_RXN<3>!U2D1!DC10!@baseboard_fab2_lib.baseboard_fab2(sch_1):page64_i68@chpset_lib.skx_ext_b(chips)!SKX_EXT_B_BGA1-IC,TBD!!!F122!PE1_RX_DN(3)!!!!
S!TP_P3E_CPU1_PE1_MP_RXN<4>!U2D1!DE10!@baseboard_fab2_lib.baseboard_fab2(sch_1):page64_i68@chpset_lib.skx_ext_b(chips)!SKX_EXT_B_BGA1-IC,TBD!!!F122!PE1_RX_DN(4)!!!!
S!TP_P3E_CPU1_PE1_MP_RXN<5>!U2D1!DH9!@baseboard_fab2_lib.baseboard_fab2(sch_1):page64_i68@chpset_lib.skx_ext_b(chips)!SKX_EXT_B_BGA1-IC,TBD!!!F122!PE1_RX_DN(5)!!!!
S!TP_P3E_CPU1_PE1_MP_RXN<6>!U2D1!DK9!@baseboard_fab2_lib.baseboard_fab2(sch_1):page64_i68@chpset_lib.skx_ext_b(chips)!SKX_EXT_B_BGA1-IC,TBD!!!F122!PE1_RX_DN(6)!!!!
S!TP_P3E_CPU1_PE1_MP_RXN<7>!U2D1!DM9!@baseboard_fab2_lib.baseboard_fab2(sch_1):page64_i68@chpset_lib.skx_ext_b(chips)!SKX_EXT_B_BGA1-IC,TBD!!!F122!PE1_RX_DN(7)!!!!
S!TP_P3E_CPU1_PE1_RSR3_RXN<8>!U2D1!DM11!@baseboard_fab2_lib.baseboard_fab2(sch_1):page64_i68@chpset_lib.skx_ext_b(chips)!SKX_EXT_B_BGA1-IC,TBD!!!F122!PE1_RX_DN(8)!!!!
S!TP_P3E_CPU1_PE1_RSR3_RXN<9>!U2D1!DP11!@baseboard_fab2_lib.baseboard_fab2(sch_1):page64_i68@chpset_lib.skx_ext_b(chips)!SKX_EXT_B_BGA1-IC,TBD!!!F122!PE1_RX_DN(9)!!!!
S!TP_P3E_CPU1_PE1_MP_RXP<0>!U2D1!CU8!@baseboard_fab2_lib.baseboard_fab2(sch_1):page64_i68@chpset_lib.skx_ext_b(chips)!SKX_EXT_B_BGA1-IC,TBD!!!F122!PE1_RX_DP(0)!!!!
S!TP_P3E_CPU1_PE1_RSR3_RXP<10>!U2D1!DR12!@baseboard_fab2_lib.baseboard_fab2(sch_1):page64_i68@chpset_lib.skx_ext_b(chips)!SKX_EXT_B_BGA1-IC,TBD!!!F122!PE1_RX_DP(10)!!!!
S!TP_P3E_CPU1_PE1_RSR3_RXP<11>!U2D1!DP13!@baseboard_fab2_lib.baseboard_fab2(sch_1):page64_i68@chpset_lib.skx_ext_b(chips)!SKX_EXT_B_BGA1-IC,TBD!!!F122!PE1_RX_DP(11)!!!!
S!TP_P3E_CPU1_PE1_RSR3_RXP<12>!U2D1!DU12!@baseboard_fab2_lib.baseboard_fab2(sch_1):page64_i68@chpset_lib.skx_ext_b(chips)!SKX_EXT_B_BGA1-IC,TBD!!!F122!PE1_RX_DP(12)!!!!
S!TP_P3E_CPU1_PE1_RSR3_RXP<13>!U2D1!DY13!@baseboard_fab2_lib.baseboard_fab2(sch_1):page64_i68@chpset_lib.skx_ext_b(chips)!SKX_EXT_B_BGA1-IC,TBD!!!F122!PE1_RX_DP(13)!!!!
S!TP_P3E_CPU1_PE1_RSR3_RXP<14>!U2D1!DV15!@baseboard_fab2_lib.baseboard_fab2(sch_1):page64_i68@chpset_lib.skx_ext_b(chips)!SKX_EXT_B_BGA1-IC,TBD!!!F122!PE1_RX_DP(14)!!!!
S!TP_P3E_CPU1_PE1_RSR3_RXP<15>!U2D1!DT15!@baseboard_fab2_lib.baseboard_fab2(sch_1):page64_i68@chpset_lib.skx_ext_b(chips)!SKX_EXT_B_BGA1-IC,TBD!!!F122!PE1_RX_DP(15)!!!!
S!TP_P3E_CPU1_PE1_MP_RXP<1>!U2D1!CY7!@baseboard_fab2_lib.baseboard_fab2(sch_1):page64_i68@chpset_lib.skx_ext_b(chips)!SKX_EXT_B_BGA1-IC,TBD!!!F122!PE1_RX_DP(1)!!!!
S!TP_P3E_CPU1_PE1_MP_RXP<2>!U2D1!DB9!@baseboard_fab2_lib.baseboard_fab2(sch_1):page64_i68@chpset_lib.skx_ext_b(chips)!SKX_EXT_B_BGA1-IC,TBD!!!F122!PE1_RX_DP(2)!!!!
S!TP_P3E_CPU1_PE1_MP_RXP<3>!U2D1!DA10!@baseboard_fab2_lib.baseboard_fab2(sch_1):page64_i68@chpset_lib.skx_ext_b(chips)!SKX_EXT_B_BGA1-IC,TBD!!!F122!PE1_RX_DP(3)!!!!
S!TP_P3E_CPU1_PE1_MP_RXP<4>!U2D1!DD9!@baseboard_fab2_lib.baseboard_fab2(sch_1):page64_i68@chpset_lib.skx_ext_b(chips)!SKX_EXT_B_BGA1-IC,TBD!!!F122!PE1_RX_DP(4)!!!!
S!TP_P3E_CPU1_PE1_MP_RXP<5>!U2D1!DF9!@baseboard_fab2_lib.baseboard_fab2(sch_1):page64_i68@chpset_lib.skx_ext_b(chips)!SKX_EXT_B_BGA1-IC,TBD!!!F122!PE1_RX_DP(5)!!!!
S!TP_P3E_CPU1_PE1_MP_RXP<6>!U2D1!DJ8!@baseboard_fab2_lib.baseboard_fab2(sch_1):page64_i68@chpset_lib.skx_ext_b(chips)!SKX_EXT_B_BGA1-IC,TBD!!!F122!PE1_RX_DP(6)!!!!
S!TP_P3E_CPU1_PE1_MP_RXP<7>!U2D1!DL10!@baseboard_fab2_lib.baseboard_fab2(sch_1):page64_i68@chpset_lib.skx_ext_b(chips)!SKX_EXT_B_BGA1-IC,TBD!!!F122!PE1_RX_DP(7)!!!!
S!TP_P3E_CPU1_PE1_RSR3_RXP<8>!U2D1!DK11!@baseboard_fab2_lib.baseboard_fab2(sch_1):page64_i68@chpset_lib.skx_ext_b(chips)!SKX_EXT_B_BGA1-IC,TBD!!!F122!PE1_RX_DP(8)!!!!
S!TP_P3E_CPU1_PE1_RSR3_RXP<9>!U2D1!DN10!@baseboard_fab2_lib.baseboard_fab2(sch_1):page64_i68@chpset_lib.skx_ext_b(chips)!SKX_EXT_B_BGA1-IC,TBD!!!F122!PE1_RX_DP(9)!!!!
S!TP_P3E_CPU1_PE1_MP_TXN<0>!U2D1!DA2!@baseboard_fab2_lib.baseboard_fab2(sch_1):page64_i68@chpset_lib.skx_ext_b(chips)!SKX_EXT_B_BGA1-IC,TBD!!!F122!PE1_TX_DN(0)!!!!
S!TP_P3E_CPU1_PE1_RSR3_TXN<10>!U2D1!DW4!@baseboard_fab2_lib.baseboard_fab2(sch_1):page64_i68@chpset_lib.skx_ext_b(chips)!SKX_EXT_B_BGA1-IC,TBD!!!F122!PE1_TX_DN(10)!!!!
S!TP_P3E_CPU1_PE1_RSR3_TXN<11>!U2D1!DU6!@baseboard_fab2_lib.baseboard_fab2(sch_1):page64_i68@chpset_lib.skx_ext_b(chips)!SKX_EXT_B_BGA1-IC,TBD!!!F122!PE1_TX_DN(11)!!!!
S!TP_P3E_CPU1_PE1_RSR3_TXN<12>!U2D1!DV7!@baseboard_fab2_lib.baseboard_fab2(sch_1):page64_i68@chpset_lib.skx_ext_b(chips)!SKX_EXT_B_BGA1-IC,TBD!!!F122!PE1_TX_DN(12)!!!!
S!TP_P3E_CPU1_PE1_RSR3_TXN<13>!U2D1!DY7!@baseboard_fab2_lib.baseboard_fab2(sch_1):page64_i68@chpset_lib.skx_ext_b(chips)!SKX_EXT_B_BGA1-IC,TBD!!!F122!PE1_TX_DN(13)!!!!
S!TP_P3E_CPU1_PE1_RSR3_TXN<14>!U2D1!EA8!@baseboard_fab2_lib.baseboard_fab2(sch_1):page64_i68@chpset_lib.skx_ext_b(chips)!SKX_EXT_B_BGA1-IC,TBD!!!F122!PE1_TX_DN(14)!!!!
S!TP_P3E_CPU1_PE1_RSR3_TXN<15>!U2D1!ED9!@baseboard_fab2_lib.baseboard_fab2(sch_1):page64_i68@chpset_lib.skx_ext_b(chips)!SKX_EXT_B_BGA1-IC,TBD!!!F122!PE1_TX_DN(15)!!!!
S!TP_P3E_CPU1_PE1_MP_TXN<1>!U2D1!DC2!@baseboard_fab2_lib.baseboard_fab2(sch_1):page64_i68@chpset_lib.skx_ext_b(chips)!SKX_EXT_B_BGA1-IC,TBD!!!F122!PE1_TX_DN(1)!!!!
S!TP_P3E_CPU1_PE1_MP_TXN<2>!U2D1!DE2!@baseboard_fab2_lib.baseboard_fab2(sch_1):page64_i68@chpset_lib.skx_ext_b(chips)!SKX_EXT_B_BGA1-IC,TBD!!!F122!PE1_TX_DN(2)!!!!
S!TP_P3E_CPU1_PE1_MP_TXN<3>!U2D1!DE4!@baseboard_fab2_lib.baseboard_fab2(sch_1):page64_i68@chpset_lib.skx_ext_b(chips)!SKX_EXT_B_BGA1-IC,TBD!!!F122!PE1_TX_DN(3)!!!!
S!TP_P3E_CPU1_PE1_MP_TXN<4>!U2D1!DG4!@baseboard_fab2_lib.baseboard_fab2(sch_1):page64_i68@chpset_lib.skx_ext_b(chips)!SKX_EXT_B_BGA1-IC,TBD!!!F122!PE1_TX_DN(4)!!!!
S!TP_P3E_CPU1_PE1_MP_TXN<5>!U2D1!DK3!@baseboard_fab2_lib.baseboard_fab2(sch_1):page64_i68@chpset_lib.skx_ext_b(chips)!SKX_EXT_B_BGA1-IC,TBD!!!F122!PE1_TX_DN(5)!!!!
S!TP_P3E_CPU1_PE1_MP_TXN<6>!U2D1!DM3!@baseboard_fab2_lib.baseboard_fab2(sch_1):page64_i68@chpset_lib.skx_ext_b(chips)!SKX_EXT_B_BGA1-IC,TBD!!!F122!PE1_TX_DN(6)!!!!
S!TP_P3E_CPU1_PE1_MP_TXN<7>!U2D1!DN4!@baseboard_fab2_lib.baseboard_fab2(sch_1):page64_i68@chpset_lib.skx_ext_b(chips)!SKX_EXT_B_BGA1-IC,TBD!!!F122!PE1_TX_DN(7)!!!!
S!TP_P3E_CPU1_PE1_RSR3_TXN<8>!U2D1!DT5!@baseboard_fab2_lib.baseboard_fab2(sch_1):page64_i68@chpset_lib.skx_ext_b(chips)!SKX_EXT_B_BGA1-IC,TBD!!!F122!PE1_TX_DN(8)!!!!
S!TP_P3E_CPU1_PE1_RSR3_TXN<9>!U2D1!DV3!@baseboard_fab2_lib.baseboard_fab2(sch_1):page64_i68@chpset_lib.skx_ext_b(chips)!SKX_EXT_B_BGA1-IC,TBD!!!F122!PE1_TX_DN(9)!!!!
S!TP_P3E_CPU1_PE1_MP_TXP<0>!U2D1!CW2!@baseboard_fab2_lib.baseboard_fab2(sch_1):page64_i68@chpset_lib.skx_ext_b(chips)!SKX_EXT_B_BGA1-IC,TBD!!!F122!PE1_TX_DP(0)!!!!
S!TP_P3E_CPU1_PE1_RSR3_TXP<10>!U2D1!DU4!@baseboard_fab2_lib.baseboard_fab2(sch_1):page64_i68@chpset_lib.skx_ext_b(chips)!SKX_EXT_B_BGA1-IC,TBD!!!F122!PE1_TX_DP(10)!!!!
S!TP_P3E_CPU1_PE1_RSR3_TXP<11>!U2D1!DV5!@baseboard_fab2_lib.baseboard_fab2(sch_1):page64_i68@chpset_lib.skx_ext_b(chips)!SKX_EXT_B_BGA1-IC,TBD!!!F122!PE1_TX_DP(11)!!!!
S!TP_P3E_CPU1_PE1_RSR3_TXP<12>!U2D1!DT7!@baseboard_fab2_lib.baseboard_fab2(sch_1):page64_i68@chpset_lib.skx_ext_b(chips)!SKX_EXT_B_BGA1-IC,TBD!!!F122!PE1_TX_DP(12)!!!!
S!TP_P3E_CPU1_PE1_RSR3_TXP<13>!U2D1!DW6!@baseboard_fab2_lib.baseboard_fab2(sch_1):page64_i68@chpset_lib.skx_ext_b(chips)!SKX_EXT_B_BGA1-IC,TBD!!!F122!PE1_TX_DP(13)!!!!
S!TP_P3E_CPU1_PE1_RSR3_TXP<14>!U2D1!EB7!@baseboard_fab2_lib.baseboard_fab2(sch_1):page64_i68@chpset_lib.skx_ext_b(chips)!SKX_EXT_B_BGA1-IC,TBD!!!F122!PE1_TX_DP(14)!!!!
S!TP_P3E_CPU1_PE1_RSR3_TXP<15>!U2D1!EC8!@baseboard_fab2_lib.baseboard_fab2(sch_1):page64_i68@chpset_lib.skx_ext_b(chips)!SKX_EXT_B_BGA1-IC,TBD!!!F122!PE1_TX_DP(15)!!!!
S!TP_P3E_CPU1_PE1_MP_TXP<1>!U2D1!DB1!@baseboard_fab2_lib.baseboard_fab2(sch_1):page64_i68@chpset_lib.skx_ext_b(chips)!SKX_EXT_B_BGA1-IC,TBD!!!F122!PE1_TX_DP(1)!!!!
S!TP_P3E_CPU1_PE1_MP_TXP<2>!U2D1!DD3!@baseboard_fab2_lib.baseboard_fab2(sch_1):page64_i68@chpset_lib.skx_ext_b(chips)!SKX_EXT_B_BGA1-IC,TBD!!!F122!PE1_TX_DP(2)!!!!
S!TP_P3E_CPU1_PE1_MP_TXP<3>!U2D1!DC4!@baseboard_fab2_lib.baseboard_fab2(sch_1):page64_i68@chpset_lib.skx_ext_b(chips)!SKX_EXT_B_BGA1-IC,TBD!!!F122!PE1_TX_DP(3)!!!!
S!TP_P3E_CPU1_PE1_MP_TXP<4>!U2D1!DF3!@baseboard_fab2_lib.baseboard_fab2(sch_1):page64_i68@chpset_lib.skx_ext_b(chips)!SKX_EXT_B_BGA1-IC,TBD!!!F122!PE1_TX_DP(4)!!!!
S!TP_P3E_CPU1_PE1_MP_TXP<5>!U2D1!DH3!@baseboard_fab2_lib.baseboard_fab2(sch_1):page64_i68@chpset_lib.skx_ext_b(chips)!SKX_EXT_B_BGA1-IC,TBD!!!F122!PE1_TX_DP(5)!!!!
S!TP_P3E_CPU1_PE1_MP_TXP<6>!U2D1!DL2!@baseboard_fab2_lib.baseboard_fab2(sch_1):page64_i68@chpset_lib.skx_ext_b(chips)!SKX_EXT_B_BGA1-IC,TBD!!!F122!PE1_TX_DP(6)!!!!
S!TP_P3E_CPU1_PE1_MP_TXP<7>!U2D1!DP3!@baseboard_fab2_lib.baseboard_fab2(sch_1):page64_i68@chpset_lib.skx_ext_b(chips)!SKX_EXT_B_BGA1-IC,TBD!!!F122!PE1_TX_DP(7)!!!!
S!TP_P3E_CPU1_PE1_RSR3_TXP<8>!U2D1!DR4!@baseboard_fab2_lib.baseboard_fab2(sch_1):page64_i68@chpset_lib.skx_ext_b(chips)!SKX_EXT_B_BGA1-IC,TBD!!!F122!PE1_TX_DP(8)!!!!
S!TP_P3E_CPU1_PE1_RSR3_TXP<9>!U2D1!DU2!@baseboard_fab2_lib.baseboard_fab2(sch_1):page64_i68@chpset_lib.skx_ext_b(chips)!SKX_EXT_B_BGA1-IC,TBD!!!F122!PE1_TX_DP(9)!!!!
S!TP_P3E_CPU1_PE2_RSR_RXN<0>!U2D1!CT9!@baseboard_fab2_lib.baseboard_fab2(sch_1):page65_i68@chpset_lib.skx_ext_b(chips)!SKX_EXT_B_BGA1-IC,TBD!!!F121!PE2_RX_DN(0)!!!!
S!TP_P3E_CPU1_PE2_RSR_RXN<10>!U2D1!BV7!@baseboard_fab2_lib.baseboard_fab2(sch_1):page65_i68@chpset_lib.skx_ext_b(chips)!SKX_EXT_B_BGA1-IC,TBD!!!F121!PE2_RX_DN(10)!!!!
S!TP_P3E_CPU1_PE2_RSR_RXN<11>!U2D1!BT7!@baseboard_fab2_lib.baseboard_fab2(sch_1):page65_i68@chpset_lib.skx_ext_b(chips)!SKX_EXT_B_BGA1-IC,TBD!!!F121!PE2_RX_DN(11)!!!!
S!TP_P3E_CPU1_PE2_RSR_RXN<12>!U2D1!BR8!@baseboard_fab2_lib.baseboard_fab2(sch_1):page65_i68@chpset_lib.skx_ext_b(chips)!SKX_EXT_B_BGA1-IC,TBD!!!F121!PE2_RX_DN(12)!!!!
S!TP_P3E_CPU1_PE2_RSR_RXN<13>!U2D1!BN8!@baseboard_fab2_lib.baseboard_fab2(sch_1):page65_i68@chpset_lib.skx_ext_b(chips)!SKX_EXT_B_BGA1-IC,TBD!!!F121!PE2_RX_DN(13)!!!!
S!TP_P3E_CPU1_PE2_RSR_RXN<14>!U2D1!BL8!@baseboard_fab2_lib.baseboard_fab2(sch_1):page65_i68@chpset_lib.skx_ext_b(chips)!SKX_EXT_B_BGA1-IC,TBD!!!F121!PE2_RX_DN(14)!!!!
S!TP_P3E_CPU1_PE2_RSR_RXN<15>!U2D1!BK9!@baseboard_fab2_lib.baseboard_fab2(sch_1):page65_i68@chpset_lib.skx_ext_b(chips)!SKX_EXT_B_BGA1-IC,TBD!!!F121!PE2_RX_DN(15)!!!!
S!TP_P3E_CPU1_PE2_RSR_RXN<1>!U2D1!CP9!@baseboard_fab2_lib.baseboard_fab2(sch_1):page65_i68@chpset_lib.skx_ext_b(chips)!SKX_EXT_B_BGA1-IC,TBD!!!F121!PE2_RX_DN(1)!!!!
S!TP_P3E_CPU1_PE2_RSR_RXN<2>!U2D1!CP7!@baseboard_fab2_lib.baseboard_fab2(sch_1):page65_i68@chpset_lib.skx_ext_b(chips)!SKX_EXT_B_BGA1-IC,TBD!!!F121!PE2_RX_DN(2)!!!!
S!TP_P3E_CPU1_PE2_RSR_RXN<3>!U2D1!CM7!@baseboard_fab2_lib.baseboard_fab2(sch_1):page65_i68@chpset_lib.skx_ext_b(chips)!SKX_EXT_B_BGA1-IC,TBD!!!F121!PE2_RX_DN(3)!!!!
S!TP_P3E_CPU1_PE2_RSR_RXN<4>!U2D1!CK7!@baseboard_fab2_lib.baseboard_fab2(sch_1):page65_i68@chpset_lib.skx_ext_b(chips)!SKX_EXT_B_BGA1-IC,TBD!!!F121!PE2_RX_DN(4)!!!!
S!TP_P3E_CPU1_PE2_RSR_RXN<5>!U2D1!CG8!@baseboard_fab2_lib.baseboard_fab2(sch_1):page65_i68@chpset_lib.skx_ext_b(chips)!SKX_EXT_B_BGA1-IC,TBD!!!F121!PE2_RX_DN(5)!!!!
S!TP_P3E_CPU1_PE2_RSR_RXN<6>!U2D1!CE6!@baseboard_fab2_lib.baseboard_fab2(sch_1):page65_i68@chpset_lib.skx_ext_b(chips)!SKX_EXT_B_BGA1-IC,TBD!!!F121!PE2_RX_DN(6)!!!!
S!TP_P3E_CPU1_PE2_RSR_RXN<7>!U2D1!CE8!@baseboard_fab2_lib.baseboard_fab2(sch_1):page65_i68@chpset_lib.skx_ext_b(chips)!SKX_EXT_B_BGA1-IC,TBD!!!F121!PE2_RX_DN(7)!!!!
S!TP_P3E_CPU1_PE2_RSR_RXN<8>!U2D1!BY9!@baseboard_fab2_lib.baseboard_fab2(sch_1):page65_i68@chpset_lib.skx_ext_b(chips)!SKX_EXT_B_BGA1-IC,TBD!!!F121!PE2_RX_DN(8)!!!!
S!TP_P3E_CPU1_PE2_RSR_RXN<9>!U2D1!BY7!@baseboard_fab2_lib.baseboard_fab2(sch_1):page65_i68@chpset_lib.skx_ext_b(chips)!SKX_EXT_B_BGA1-IC,TBD!!!F121!PE2_RX_DN(9)!!!!
S!TP_P3E_CPU1_PE2_RSR_RXP<0>!U2D1!CR8!@baseboard_fab2_lib.baseboard_fab2(sch_1):page65_i68@chpset_lib.skx_ext_b(chips)!SKX_EXT_B_BGA1-IC,TBD!!!F121!PE2_RX_DP(0)!!!!
S!TP_P3E_CPU1_PE2_RSR_RXP<10>!U2D1!BU6!@baseboard_fab2_lib.baseboard_fab2(sch_1):page65_i68@chpset_lib.skx_ext_b(chips)!SKX_EXT_B_BGA1-IC,TBD!!!F121!PE2_RX_DP(10)!!!!
S!TP_P3E_CPU1_PE2_RSR_RXP<11>!U2D1!BP7!@baseboard_fab2_lib.baseboard_fab2(sch_1):page65_i68@chpset_lib.skx_ext_b(chips)!SKX_EXT_B_BGA1-IC,TBD!!!F121!PE2_RX_DP(11)!!!!
S!TP_P3E_CPU1_PE2_RSR_RXP<12>!U2D1!BP9!@baseboard_fab2_lib.baseboard_fab2(sch_1):page65_i68@chpset_lib.skx_ext_b(chips)!SKX_EXT_B_BGA1-IC,TBD!!!F121!PE2_RX_DP(12)!!!!
S!TP_P3E_CPU1_PE2_RSR_RXP<13>!U2D1!BM7!@baseboard_fab2_lib.baseboard_fab2(sch_1):page65_i68@chpset_lib.skx_ext_b(chips)!SKX_EXT_B_BGA1-IC,TBD!!!F121!PE2_RX_DP(13)!!!!
S!TP_P3E_CPU1_PE2_RSR_RXP<14>!U2D1!BJ8!@baseboard_fab2_lib.baseboard_fab2(sch_1):page65_i68@chpset_lib.skx_ext_b(chips)!SKX_EXT_B_BGA1-IC,TBD!!!F121!PE2_RX_DP(14)!!!!
S!TP_P3E_CPU1_PE2_RSR_RXP<15>!U2D1!BJ10!@baseboard_fab2_lib.baseboard_fab2(sch_1):page65_i68@chpset_lib.skx_ext_b(chips)!SKX_EXT_B_BGA1-IC,TBD!!!F121!PE2_RX_DP(15)!!!!
S!TP_P3E_CPU1_PE2_RSR_RXP<1>!U2D1!CM9!@baseboard_fab2_lib.baseboard_fab2(sch_1):page65_i68@chpset_lib.skx_ext_b(chips)!SKX_EXT_B_BGA1-IC,TBD!!!F121!PE2_RX_DP(1)!!!!
S!TP_P3E_CPU1_PE2_RSR_RXP<2>!U2D1!CN8!@baseboard_fab2_lib.baseboard_fab2(sch_1):page65_i68@chpset_lib.skx_ext_b(chips)!SKX_EXT_B_BGA1-IC,TBD!!!F121!PE2_RX_DP(2)!!!!
S!TP_P3E_CPU1_PE2_RSR_RXP<3>!U2D1!CL6!@baseboard_fab2_lib.baseboard_fab2(sch_1):page65_i68@chpset_lib.skx_ext_b(chips)!SKX_EXT_B_BGA1-IC,TBD!!!F121!PE2_RX_DP(3)!!!!
S!TP_P3E_CPU1_PE2_RSR_RXP<4>!U2D1!CH7!@baseboard_fab2_lib.baseboard_fab2(sch_1):page65_i68@chpset_lib.skx_ext_b(chips)!SKX_EXT_B_BGA1-IC,TBD!!!F121!PE2_RX_DP(4)!!!!
S!TP_P3E_CPU1_PE2_RSR_RXP<5>!U2D1!CF7!@baseboard_fab2_lib.baseboard_fab2(sch_1):page65_i68@chpset_lib.skx_ext_b(chips)!SKX_EXT_B_BGA1-IC,TBD!!!F121!PE2_RX_DP(5)!!!!
S!TP_P3E_CPU1_PE2_RSR_RXP<6>!U2D1!CD7!@baseboard_fab2_lib.baseboard_fab2(sch_1):page65_i68@chpset_lib.skx_ext_b(chips)!SKX_EXT_B_BGA1-IC,TBD!!!F121!PE2_RX_DP(6)!!!!
S!TP_P3E_CPU1_PE2_RSR_RXP<7>!U2D1!CC8!@baseboard_fab2_lib.baseboard_fab2(sch_1):page65_i68@chpset_lib.skx_ext_b(chips)!SKX_EXT_B_BGA1-IC,TBD!!!F121!PE2_RX_DP(7)!!!!
S!TP_P3E_CPU1_PE2_RSR_RXP<8>!U2D1!BV9!@baseboard_fab2_lib.baseboard_fab2(sch_1):page65_i68@chpset_lib.skx_ext_b(chips)!SKX_EXT_B_BGA1-IC,TBD!!!F121!PE2_RX_DP(8)!!!!
S!TP_P3E_CPU1_PE2_RSR_RXP<9>!U2D1!BW8!@baseboard_fab2_lib.baseboard_fab2(sch_1):page65_i68@chpset_lib.skx_ext_b(chips)!SKX_EXT_B_BGA1-IC,TBD!!!F121!PE2_RX_DP(9)!!!!
S!TP_P3E_CPU1_PE2_RSR_TXN<0>!U2D1!CY3!@baseboard_fab2_lib.baseboard_fab2(sch_1):page65_i68@chpset_lib.skx_ext_b(chips)!SKX_EXT_B_BGA1-IC,TBD!!!F121!PE2_TX_DN(0)!!!!
S!TP_P3E_CPU1_PE2_RSR_TXN<10>!U2D1!CA4!@baseboard_fab2_lib.baseboard_fab2(sch_1):page65_i68@chpset_lib.skx_ext_b(chips)!SKX_EXT_B_BGA1-IC,TBD!!!F121!PE2_TX_DN(10)!!!!
S!TP_P3E_CPU1_PE2_RSR_TXN<11>!U2D1!BW4!@baseboard_fab2_lib.baseboard_fab2(sch_1):page65_i68@chpset_lib.skx_ext_b(chips)!SKX_EXT_B_BGA1-IC,TBD!!!F121!PE2_TX_DN(11)!!!!
S!TP_P3E_CPU1_PE2_RSR_TXN<12>!U2D1!BU4!@baseboard_fab2_lib.baseboard_fab2(sch_1):page65_i68@chpset_lib.skx_ext_b(chips)!SKX_EXT_B_BGA1-IC,TBD!!!F121!PE2_TX_DN(12)!!!!
S!TP_P3E_CPU1_PE2_RSR_TXN<13>!U2D1!BP5!@baseboard_fab2_lib.baseboard_fab2(sch_1):page65_i68@chpset_lib.skx_ext_b(chips)!SKX_EXT_B_BGA1-IC,TBD!!!F121!PE2_TX_DN(13)!!!!
S!TP_P3E_CPU1_PE2_RSR_TXN<14>!U2D1!BL4!@baseboard_fab2_lib.baseboard_fab2(sch_1):page65_i68@chpset_lib.skx_ext_b(chips)!SKX_EXT_B_BGA1-IC,TBD!!!F121!PE2_TX_DN(14)!!!!
S!TP_P3E_CPU1_PE2_RSR_TXN<15>!U2D1!BM5!@baseboard_fab2_lib.baseboard_fab2(sch_1):page65_i68@chpset_lib.skx_ext_b(chips)!SKX_EXT_B_BGA1-IC,TBD!!!F121!PE2_TX_DN(15)!!!!
S!TP_P3E_CPU1_PE2_RSR_TXN<1>!U2D1!CV3!@baseboard_fab2_lib.baseboard_fab2(sch_1):page65_i68@chpset_lib.skx_ext_b(chips)!SKX_EXT_B_BGA1-IC,TBD!!!F121!PE2_TX_DN(1)!!!!
S!TP_P3E_CPU1_PE2_RSR_TXN<2>!U2D1!CT1!@baseboard_fab2_lib.baseboard_fab2(sch_1):page65_i68@chpset_lib.skx_ext_b(chips)!SKX_EXT_B_BGA1-IC,TBD!!!F121!PE2_TX_DN(2)!!!!
S!TP_P3E_CPU1_PE2_RSR_TXN<3>!U2D1!CT3!@baseboard_fab2_lib.baseboard_fab2(sch_1):page65_i68@chpset_lib.skx_ext_b(chips)!SKX_EXT_B_BGA1-IC,TBD!!!F121!PE2_TX_DN(3)!!!!
S!TP_P3E_CPU1_PE2_RSR_TXN<4>!U2D1!CM1!@baseboard_fab2_lib.baseboard_fab2(sch_1):page65_i68@chpset_lib.skx_ext_b(chips)!SKX_EXT_B_BGA1-IC,TBD!!!F121!PE2_TX_DN(4)!!!!
S!TP_P3E_CPU1_PE2_RSR_TXN<5>!U2D1!CL2!@baseboard_fab2_lib.baseboard_fab2(sch_1):page65_i68@chpset_lib.skx_ext_b(chips)!SKX_EXT_B_BGA1-IC,TBD!!!F121!PE2_TX_DN(5)!!!!
S!TP_P3E_CPU1_PE2_RSR_TXN<6>!U2D1!CG2!@baseboard_fab2_lib.baseboard_fab2(sch_1):page65_i68@chpset_lib.skx_ext_b(chips)!SKX_EXT_B_BGA1-IC,TBD!!!F121!PE2_TX_DN(6)!!!!
S!TP_P3E_CPU1_PE2_RSR_TXN<7>!U2D1!CF3!@baseboard_fab2_lib.baseboard_fab2(sch_1):page65_i68@chpset_lib.skx_ext_b(chips)!SKX_EXT_B_BGA1-IC,TBD!!!F121!PE2_TX_DN(7)!!!!
S!TP_P3E_CPU1_PE2_RSR_TXN<8>!U2D1!CC2!@baseboard_fab2_lib.baseboard_fab2(sch_1):page65_i68@chpset_lib.skx_ext_b(chips)!SKX_EXT_B_BGA1-IC,TBD!!!F121!PE2_TX_DN(8)!!!!
S!TP_P3E_CPU1_PE2_RSR_TXN<9>!U2D1!CB3!@baseboard_fab2_lib.baseboard_fab2(sch_1):page65_i68@chpset_lib.skx_ext_b(chips)!SKX_EXT_B_BGA1-IC,TBD!!!F121!PE2_TX_DN(9)!!!!
S!TP_P3E_CPU1_PE2_RSR_TXP<0>!U2D1!CW4!@baseboard_fab2_lib.baseboard_fab2(sch_1):page65_i68@chpset_lib.skx_ext_b(chips)!SKX_EXT_B_BGA1-IC,TBD!!!F121!PE2_TX_DP(0)!!!!
S!TP_P3E_CPU1_PE2_RSR_TXP<10>!U2D1!BY5!@baseboard_fab2_lib.baseboard_fab2(sch_1):page65_i68@chpset_lib.skx_ext_b(chips)!SKX_EXT_B_BGA1-IC,TBD!!!F121!PE2_TX_DP(10)!!!!
S!TP_P3E_CPU1_PE2_RSR_TXP<11>!U2D1!BV3!@baseboard_fab2_lib.baseboard_fab2(sch_1):page65_i68@chpset_lib.skx_ext_b(chips)!SKX_EXT_B_BGA1-IC,TBD!!!F121!PE2_TX_DP(11)!!!!
S!TP_P3E_CPU1_PE2_RSR_TXP<12>!U2D1!BR4!@baseboard_fab2_lib.baseboard_fab2(sch_1):page65_i68@chpset_lib.skx_ext_b(chips)!SKX_EXT_B_BGA1-IC,TBD!!!F121!PE2_TX_DP(12)!!!!
S!TP_P3E_CPU1_PE2_RSR_TXP<13>!U2D1!BN4!@baseboard_fab2_lib.baseboard_fab2(sch_1):page65_i68@chpset_lib.skx_ext_b(chips)!SKX_EXT_B_BGA1-IC,TBD!!!F121!PE2_TX_DP(13)!!!!
S!TP_P3E_CPU1_PE2_RSR_TXP<14>!U2D1!BM3!@baseboard_fab2_lib.baseboard_fab2(sch_1):page65_i68@chpset_lib.skx_ext_b(chips)!SKX_EXT_B_BGA1-IC,TBD!!!F121!PE2_TX_DP(14)!!!!
S!TP_P3E_CPU1_PE2_RSR_TXP<15>!U2D1!BK5!@baseboard_fab2_lib.baseboard_fab2(sch_1):page65_i68@chpset_lib.skx_ext_b(chips)!SKX_EXT_B_BGA1-IC,TBD!!!F121!PE2_TX_DP(15)!!!!
S!TP_P3E_CPU1_PE2_RSR_TXP<1>!U2D1!CU2!@baseboard_fab2_lib.baseboard_fab2(sch_1):page65_i68@chpset_lib.skx_ext_b(chips)!SKX_EXT_B_BGA1-IC,TBD!!!F121!PE2_TX_DP(1)!!!!
S!TP_P3E_CPU1_PE2_RSR_TXP<2>!U2D1!CR2!@baseboard_fab2_lib.baseboard_fab2(sch_1):page65_i68@chpset_lib.skx_ext_b(chips)!SKX_EXT_B_BGA1-IC,TBD!!!F121!PE2_TX_DP(2)!!!!
S!TP_P3E_CPU1_PE2_RSR_TXP<3>!U2D1!CP3!@baseboard_fab2_lib.baseboard_fab2(sch_1):page65_i68@chpset_lib.skx_ext_b(chips)!SKX_EXT_B_BGA1-IC,TBD!!!F121!PE2_TX_DP(3)!!!!
S!TP_P3E_CPU1_PE2_RSR_TXP<4>!U2D1!CK1!@baseboard_fab2_lib.baseboard_fab2(sch_1):page65_i68@chpset_lib.skx_ext_b(chips)!SKX_EXT_B_BGA1-IC,TBD!!!F121!PE2_TX_DP(4)!!!!
S!TP_P3E_CPU1_PE2_RSR_TXP<5>!U2D1!CK3!@baseboard_fab2_lib.baseboard_fab2(sch_1):page65_i68@chpset_lib.skx_ext_b(chips)!SKX_EXT_B_BGA1-IC,TBD!!!F121!PE2_TX_DP(5)!!!!
S!TP_P3E_CPU1_PE2_RSR_TXP<6>!U2D1!CE2!@baseboard_fab2_lib.baseboard_fab2(sch_1):page65_i68@chpset_lib.skx_ext_b(chips)!SKX_EXT_B_BGA1-IC,TBD!!!F121!PE2_TX_DP(6)!!!!
S!TP_P3E_CPU1_PE2_RSR_TXP<7>!U2D1!CE4!@baseboard_fab2_lib.baseboard_fab2(sch_1):page65_i68@chpset_lib.skx_ext_b(chips)!SKX_EXT_B_BGA1-IC,TBD!!!F121!PE2_TX_DP(7)!!!!
S!TP_P3E_CPU1_PE2_RSR_TXP<8>!U2D1!CD3!@baseboard_fab2_lib.baseboard_fab2(sch_1):page65_i68@chpset_lib.skx_ext_b(chips)!SKX_EXT_B_BGA1-IC,TBD!!!F121!PE2_TX_DP(8)!!!!
S!TP_P3E_CPU1_PE2_RSR_TXP<9>!U2D1!BY3!@baseboard_fab2_lib.baseboard_fab2(sch_1):page65_i68@chpset_lib.skx_ext_b(chips)!SKX_EXT_B_BGA1-IC,TBD!!!F121!PE2_TX_DP(9)!!!!
S!P3E_CPU1_PE3_MP_RXN<0>!U2D1!EA18!@baseboard_fab2_lib.baseboard_fab2(sch_1):page66_i84@chpset_lib.skx_ext_b(chips)!SKX_EXT_B_BGA1-IC,TBD!!!F120!PE3_RX_DN(0)!!!!
S!P3E_CPU1_PE3_MP_RXN<10>!U2D1!DG12!@baseboard_fab2_lib.baseboard_fab2(sch_1):page66_i84@chpset_lib.skx_ext_b(chips)!SKX_EXT_B_BGA1-IC,TBD!!!F120!PE3_RX_DN(10)!!!!
S!P3E_CPU1_PE3_MP_RXN<11>!U2D1!DG10!@baseboard_fab2_lib.baseboard_fab2(sch_1):page66_i84@chpset_lib.skx_ext_b(chips)!SKX_EXT_B_BGA1-IC,TBD!!!F120!PE3_RX_DN(11)!!!!
S!P3E_CPU1_PE3_MP_RXP<12>!U2D1!DD13!@baseboard_fab2_lib.baseboard_fab2(sch_1):page66_i84@chpset_lib.skx_ext_b(chips)!SKX_EXT_B_BGA1-IC,TBD!!!F120!PE3_RX_DN(12)!!!!
S!P3E_CPU1_PE3_MP_RXN<13>!U2D1!DB11!@baseboard_fab2_lib.baseboard_fab2(sch_1):page66_i84@chpset_lib.skx_ext_b(chips)!SKX_EXT_B_BGA1-IC,TBD!!!F120!PE3_RX_DN(13)!!!!
S!P3E_CPU1_PE3_MP_RXN<14>!U2D1!CY11!@baseboard_fab2_lib.baseboard_fab2(sch_1):page66_i84@chpset_lib.skx_ext_b(chips)!SKX_EXT_B_BGA1-IC,TBD!!!F120!PE3_RX_DN(14)!!!!
S!P3E_CPU1_PE3_MP_RXN<15>!U2D1!CV9!@baseboard_fab2_lib.baseboard_fab2(sch_1):page66_i84@chpset_lib.skx_ext_b(chips)!SKX_EXT_B_BGA1-IC,TBD!!!F120!PE3_RX_DN(15)!!!!
S!P3E_CPU1_PE3_MP_RXN<1>!U2D1!DW18!@baseboard_fab2_lib.baseboard_fab2(sch_1):page66_i84@chpset_lib.skx_ext_b(chips)!SKX_EXT_B_BGA1-IC,TBD!!!F120!PE3_RX_DN(1)!!!!
S!P3E_CPU1_PE3_MP_RXN<2>!U2D1!DW16!@baseboard_fab2_lib.baseboard_fab2(sch_1):page66_i84@chpset_lib.skx_ext_b(chips)!SKX_EXT_B_BGA1-IC,TBD!!!F120!PE3_RX_DN(2)!!!!
S!P3E_CPU1_PE3_MP_RXN<3>!U2D1!DT19!@baseboard_fab2_lib.baseboard_fab2(sch_1):page66_i84@chpset_lib.skx_ext_b(chips)!SKX_EXT_B_BGA1-IC,TBD!!!F120!PE3_RX_DN(3)!!!!
S!P3E_CPU1_PE3_MP_RXN<4>!U2D1!DR16!@baseboard_fab2_lib.baseboard_fab2(sch_1):page66_i84@chpset_lib.skx_ext_b(chips)!SKX_EXT_B_BGA1-IC,TBD!!!F120!PE3_RX_DN(4)!!!!
S!P3E_CPU1_PE3_MP_RXN<5>!U2D1!DR14!@baseboard_fab2_lib.baseboard_fab2(sch_1):page66_i84@chpset_lib.skx_ext_b(chips)!SKX_EXT_B_BGA1-IC,TBD!!!F120!PE3_RX_DN(5)!!!!
S!P3E_CPU1_PE3_MP_RXN<6>!U2D1!DN14!@baseboard_fab2_lib.baseboard_fab2(sch_1):page66_i84@chpset_lib.skx_ext_b(chips)!SKX_EXT_B_BGA1-IC,TBD!!!F120!PE3_RX_DN(6)!!!!
S!P3E_CPU1_PE3_MP_RXN<7>!U2D1!DL14!@baseboard_fab2_lib.baseboard_fab2(sch_1):page66_i84@chpset_lib.skx_ext_b(chips)!SKX_EXT_B_BGA1-IC,TBD!!!F120!PE3_RX_DN(7)!!!!
S!P3E_CPU1_PE3_MP_RXN<8>!U2D1!DL12!@baseboard_fab2_lib.baseboard_fab2(sch_1):page66_i84@chpset_lib.skx_ext_b(chips)!SKX_EXT_B_BGA1-IC,TBD!!!F120!PE3_RX_DN(8)!!!!
S!P3E_CPU1_PE3_MP_RXN<9>!U2D1!DJ12!@baseboard_fab2_lib.baseboard_fab2(sch_1):page66_i84@chpset_lib.skx_ext_b(chips)!SKX_EXT_B_BGA1-IC,TBD!!!F120!PE3_RX_DN(9)!!!!
S!P3E_CPU1_PE3_MP_RXP<0>!U2D1!DY17!@baseboard_fab2_lib.baseboard_fab2(sch_1):page66_i84@chpset_lib.skx_ext_b(chips)!SKX_EXT_B_BGA1-IC,TBD!!!F120!PE3_RX_DP(0)!!!!
S!P3E_CPU1_PE3_MP_RXP<10>!U2D1!DE12!@baseboard_fab2_lib.baseboard_fab2(sch_1):page66_i84@chpset_lib.skx_ext_b(chips)!SKX_EXT_B_BGA1-IC,TBD!!!F120!PE3_RX_DP(10)!!!!
S!P3E_CPU1_PE3_MP_RXP<11>!U2D1!DF11!@baseboard_fab2_lib.baseboard_fab2(sch_1):page66_i84@chpset_lib.skx_ext_b(chips)!SKX_EXT_B_BGA1-IC,TBD!!!F120!PE3_RX_DP(11)!!!!
S!P3E_CPU1_PE3_MP_RXN<12>!U2D1!DC12!@baseboard_fab2_lib.baseboard_fab2(sch_1):page66_i84@chpset_lib.skx_ext_b(chips)!SKX_EXT_B_BGA1-IC,TBD!!!F120!PE3_RX_DP(12)!!!!
S!P3E_CPU1_PE3_MP_RXP<13>!U2D1!DA12!@baseboard_fab2_lib.baseboard_fab2(sch_1):page66_i84@chpset_lib.skx_ext_b(chips)!SKX_EXT_B_BGA1-IC,TBD!!!F120!PE3_RX_DP(13)!!!!
S!P3E_CPU1_PE3_MP_RXP<14>!U2D1!CW10!@baseboard_fab2_lib.baseboard_fab2(sch_1):page66_i84@chpset_lib.skx_ext_b(chips)!SKX_EXT_B_BGA1-IC,TBD!!!F120!PE3_RX_DP(14)!!!!
S!P3E_CPU1_PE3_MP_RXP<15>!U2D1!CU10!@baseboard_fab2_lib.baseboard_fab2(sch_1):page66_i84@chpset_lib.skx_ext_b(chips)!SKX_EXT_B_BGA1-IC,TBD!!!F120!PE3_RX_DP(15)!!!!
S!P3E_CPU1_PE3_MP_RXP<1>!U2D1!DU18!@baseboard_fab2_lib.baseboard_fab2(sch_1):page66_i84@chpset_lib.skx_ext_b(chips)!SKX_EXT_B_BGA1-IC,TBD!!!F120!PE3_RX_DP(1)!!!!
S!P3E_CPU1_PE3_MP_RXP<2>!U2D1!DV17!@baseboard_fab2_lib.baseboard_fab2(sch_1):page66_i84@chpset_lib.skx_ext_b(chips)!SKX_EXT_B_BGA1-IC,TBD!!!F120!PE3_RX_DP(2)!!!!
S!P3E_CPU1_PE3_MP_RXP<3>!U2D1!DR18!@baseboard_fab2_lib.baseboard_fab2(sch_1):page66_i84@chpset_lib.skx_ext_b(chips)!SKX_EXT_B_BGA1-IC,TBD!!!F120!PE3_RX_DP(3)!!!!
S!P3E_CPU1_PE3_MP_RXP<4>!U2D1!DN16!@baseboard_fab2_lib.baseboard_fab2(sch_1):page66_i84@chpset_lib.skx_ext_b(chips)!SKX_EXT_B_BGA1-IC,TBD!!!F120!PE3_RX_DP(4)!!!!
S!P3E_CPU1_PE3_MP_RXP<5>!U2D1!DP15!@baseboard_fab2_lib.baseboard_fab2(sch_1):page66_i84@chpset_lib.skx_ext_b(chips)!SKX_EXT_B_BGA1-IC,TBD!!!F120!PE3_RX_DP(5)!!!!
S!P3E_CPU1_PE3_MP_RXP<6>!U2D1!DM13!@baseboard_fab2_lib.baseboard_fab2(sch_1):page66_i84@chpset_lib.skx_ext_b(chips)!SKX_EXT_B_BGA1-IC,TBD!!!F120!PE3_RX_DP(6)!!!!
S!P3E_CPU1_PE3_MP_RXP<7>!U2D1!DJ14!@baseboard_fab2_lib.baseboard_fab2(sch_1):page66_i84@chpset_lib.skx_ext_b(chips)!SKX_EXT_B_BGA1-IC,TBD!!!F120!PE3_RX_DP(7)!!!!
S!P3E_CPU1_PE3_MP_RXP<8>!U2D1!DK13!@baseboard_fab2_lib.baseboard_fab2(sch_1):page66_i84@chpset_lib.skx_ext_b(chips)!SKX_EXT_B_BGA1-IC,TBD!!!F120!PE3_RX_DP(8)!!!!
S!P3E_CPU1_PE3_MP_RXP<9>!U2D1!DH11!@baseboard_fab2_lib.baseboard_fab2(sch_1):page66_i84@chpset_lib.skx_ext_b(chips)!SKX_EXT_B_BGA1-IC,TBD!!!F120!PE3_RX_DP(9)!!!!
S!P3E_CPU1_PE3_MP_TXN<0>!U2D1!EE14!@baseboard_fab2_lib.baseboard_fab2(sch_1):page66_i84@chpset_lib.skx_ext_b(chips)!SKX_EXT_B_BGA1-IC,TBD!!!F120!PE3_TX_DN(0)!!!!
S!P3E_CPU1_PE3_MP_TXN<10>!U2D1!DL6!@baseboard_fab2_lib.baseboard_fab2(sch_1):page66_i84@chpset_lib.skx_ext_b(chips)!SKX_EXT_B_BGA1-IC,TBD!!!F120!PE3_TX_DN(10)!!!!
S!P3E_CPU1_PE3_MP_TXN<11>!U2D1!DJ4!@baseboard_fab2_lib.baseboard_fab2(sch_1):page66_i84@chpset_lib.skx_ext_b(chips)!SKX_EXT_B_BGA1-IC,TBD!!!F120!PE3_TX_DN(11)!!!!
S!P3E_CPU1_PE3_MP_TXN<12>!U2D1!DJ6!@baseboard_fab2_lib.baseboard_fab2(sch_1):page66_i84@chpset_lib.skx_ext_b(chips)!SKX_EXT_B_BGA1-IC,TBD!!!F120!PE3_TX_DN(12)!!!!
S!P3E_CPU1_PE3_MP_TXN<13>!U2D1!DD5!@baseboard_fab2_lib.baseboard_fab2(sch_1):page66_i84@chpset_lib.skx_ext_b(chips)!SKX_EXT_B_BGA1-IC,TBD!!!F120!PE3_TX_DN(13)!!!!
S!P3E_CPU1_PE3_MP_TXN<14>!U2D1!DB5!@baseboard_fab2_lib.baseboard_fab2(sch_1):page66_i84@chpset_lib.skx_ext_b(chips)!SKX_EXT_B_BGA1-IC,TBD!!!F120!PE3_TX_DN(14)!!!!
S!P3E_CPU1_PE3_MP_TXN<15>!U2D1!CY5!@baseboard_fab2_lib.baseboard_fab2(sch_1):page66_i84@chpset_lib.skx_ext_b(chips)!SKX_EXT_B_BGA1-IC,TBD!!!F120!PE3_TX_DN(15)!!!!
S!P3E_CPU1_PE3_MP_TXN<1>!U2D1!EE12!@baseboard_fab2_lib.baseboard_fab2(sch_1):page66_i84@chpset_lib.skx_ext_b(chips)!SKX_EXT_B_BGA1-IC,TBD!!!F120!PE3_TX_DN(1)!!!!
S!P3E_CPU1_PE3_MP_TXN<2>!U2D1!EC12!@baseboard_fab2_lib.baseboard_fab2(sch_1):page66_i84@chpset_lib.skx_ext_b(chips)!SKX_EXT_B_BGA1-IC,TBD!!!F120!PE3_TX_DN(2)!!!!
S!P3E_CPU1_PE3_MP_TXN<3>!U2D1!DY11!@baseboard_fab2_lib.baseboard_fab2(sch_1):page66_i84@chpset_lib.skx_ext_b(chips)!SKX_EXT_B_BGA1-IC,TBD!!!F120!PE3_TX_DN(3)!!!!
S!P3E_CPU1_PE3_MP_TXN<4>!U2D1!EB9!@baseboard_fab2_lib.baseboard_fab2(sch_1):page66_i84@chpset_lib.skx_ext_b(chips)!SKX_EXT_B_BGA1-IC,TBD!!!F120!PE3_TX_DN(4)!!!!
S!P3E_CPU1_PE3_MP_TXN<5>!U2D1!DW10!@baseboard_fab2_lib.baseboard_fab2(sch_1):page66_i84@chpset_lib.skx_ext_b(chips)!SKX_EXT_B_BGA1-IC,TBD!!!F120!PE3_TX_DN(5)!!!!
S!P3E_CPU1_PE3_MP_TXN<6>!U2D1!DU8!@baseboard_fab2_lib.baseboard_fab2(sch_1):page66_i84@chpset_lib.skx_ext_b(chips)!SKX_EXT_B_BGA1-IC,TBD!!!F120!PE3_TX_DN(6)!!!!
S!P3E_CPU1_PE3_MP_TXN<7>!U2D1!DR8!@baseboard_fab2_lib.baseboard_fab2(sch_1):page66_i84@chpset_lib.skx_ext_b(chips)!SKX_EXT_B_BGA1-IC,TBD!!!F120!PE3_TX_DN(7)!!!!
S!P3E_CPU1_PE3_MP_TXN<8>!U2D1!DM7!@baseboard_fab2_lib.baseboard_fab2(sch_1):page66_i84@chpset_lib.skx_ext_b(chips)!SKX_EXT_B_BGA1-IC,TBD!!!F120!PE3_TX_DN(8)!!!!
S!P3E_CPU1_PE3_MP_TXN<9>!U2D1!DP5!@baseboard_fab2_lib.baseboard_fab2(sch_1):page66_i84@chpset_lib.skx_ext_b(chips)!SKX_EXT_B_BGA1-IC,TBD!!!F120!PE3_TX_DN(9)!!!!
S!P3E_CPU1_PE3_MP_TXP<0>!U2D1!EC14!@baseboard_fab2_lib.baseboard_fab2(sch_1):page66_i84@chpset_lib.skx_ext_b(chips)!SKX_EXT_B_BGA1-IC,TBD!!!F120!PE3_TX_DP(0)!!!!
S!P3E_CPU1_PE3_MP_TXP<10>!U2D1!DK5!@baseboard_fab2_lib.baseboard_fab2(sch_1):page66_i84@chpset_lib.skx_ext_b(chips)!SKX_EXT_B_BGA1-IC,TBD!!!F120!PE3_TX_DP(10)!!!!
S!P3E_CPU1_PE3_MP_TXP<11>!U2D1!DH5!@baseboard_fab2_lib.baseboard_fab2(sch_1):page66_i84@chpset_lib.skx_ext_b(chips)!SKX_EXT_B_BGA1-IC,TBD!!!F120!PE3_TX_DP(11)!!!!
S!P3E_CPU1_PE3_MP_TXP<12>!U2D1!DG6!@baseboard_fab2_lib.baseboard_fab2(sch_1):page66_i84@chpset_lib.skx_ext_b(chips)!SKX_EXT_B_BGA1-IC,TBD!!!F120!PE3_TX_DP(12)!!!!
S!P3E_CPU1_PE3_MP_TXP<13>!U2D1!DC6!@baseboard_fab2_lib.baseboard_fab2(sch_1):page66_i84@chpset_lib.skx_ext_b(chips)!SKX_EXT_B_BGA1-IC,TBD!!!F120!PE3_TX_DP(13)!!!!
S!P3E_CPU1_PE3_MP_TXP<14>!U2D1!DA4!@baseboard_fab2_lib.baseboard_fab2(sch_1):page66_i84@chpset_lib.skx_ext_b(chips)!SKX_EXT_B_BGA1-IC,TBD!!!F120!PE3_TX_DP(14)!!!!
S!P3E_CPU1_PE3_MP_TXP<15>!U2D1!CV5!@baseboard_fab2_lib.baseboard_fab2(sch_1):page66_i84@chpset_lib.skx_ext_b(chips)!SKX_EXT_B_BGA1-IC,TBD!!!F120!PE3_TX_DP(15)!!!!
S!P3E_CPU1_PE3_MP_TXP<1>!U2D1!ED13!@baseboard_fab2_lib.baseboard_fab2(sch_1):page66_i84@chpset_lib.skx_ext_b(chips)!SKX_EXT_B_BGA1-IC,TBD!!!F120!PE3_TX_DP(1)!!!!
S!P3E_CPU1_PE3_MP_TXP<2>!U2D1!EB11!@baseboard_fab2_lib.baseboard_fab2(sch_1):page66_i84@chpset_lib.skx_ext_b(chips)!SKX_EXT_B_BGA1-IC,TBD!!!F120!PE3_TX_DP(2)!!!!
S!P3E_CPU1_PE3_MP_TXP<3>!U2D1!EA10!@baseboard_fab2_lib.baseboard_fab2(sch_1):page66_i84@chpset_lib.skx_ext_b(chips)!SKX_EXT_B_BGA1-IC,TBD!!!F120!PE3_TX_DP(3)!!!!
S!P3E_CPU1_PE3_MP_TXP<4>!U2D1!DY9!@baseboard_fab2_lib.baseboard_fab2(sch_1):page66_i84@chpset_lib.skx_ext_b(chips)!SKX_EXT_B_BGA1-IC,TBD!!!F120!PE3_TX_DP(4)!!!!
S!P3E_CPU1_PE3_MP_TXP<5>!U2D1!DV9!@baseboard_fab2_lib.baseboard_fab2(sch_1):page66_i84@chpset_lib.skx_ext_b(chips)!SKX_EXT_B_BGA1-IC,TBD!!!F120!PE3_TX_DP(5)!!!!
S!P3E_CPU1_PE3_MP_TXP<6>!U2D1!DT9!@baseboard_fab2_lib.baseboard_fab2(sch_1):page66_i84@chpset_lib.skx_ext_b(chips)!SKX_EXT_B_BGA1-IC,TBD!!!F120!PE3_TX_DP(6)!!!!
S!P3E_CPU1_PE3_MP_TXP<7>!U2D1!DP7!@baseboard_fab2_lib.baseboard_fab2(sch_1):page66_i84@chpset_lib.skx_ext_b(chips)!SKX_EXT_B_BGA1-IC,TBD!!!F120!PE3_TX_DP(7)!!!!
S!P3E_CPU1_PE3_MP_TXP<8>!U2D1!DN6!@baseboard_fab2_lib.baseboard_fab2(sch_1):page66_i84@chpset_lib.skx_ext_b(chips)!SKX_EXT_B_BGA1-IC,TBD!!!F120!PE3_TX_DP(8)!!!!
S!P3E_CPU1_PE3_MP_TXP<9>!U2D1!DM5!@baseboard_fab2_lib.baseboard_fab2(sch_1):page66_i84@chpset_lib.skx_ext_b(chips)!SKX_EXT_B_BGA1-IC,TBD!!!F120!PE3_TX_DP(9)!!!!
S!UPI_CPU0_CPU1_P0P0_DP<0>!U2D1!AC10!@baseboard_fab2_lib.baseboard_fab2(sch_1):page67_i132@chpset_lib.skx_ext_b(chips)!SKX_EXT_B_BGA1-IC,TBD!!!F119!UPI0_RX_DN(0)!!!!
S!UPI_CPU0_CPU1_P0P0_DN<10>!U2D1!AP7!@baseboard_fab2_lib.baseboard_fab2(sch_1):page67_i132@chpset_lib.skx_ext_b(chips)!SKX_EXT_B_BGA1-IC,TBD!!!F119!UPI0_RX_DN(10)!!!!
S!UPI_CPU0_CPU1_P0P0_DP<11>!U2D1!AR8!@baseboard_fab2_lib.baseboard_fab2(sch_1):page67_i132@chpset_lib.skx_ext_b(chips)!SKX_EXT_B_BGA1-IC,TBD!!!F119!UPI0_RX_DN(11)!!!!
S!UPI_CPU0_CPU1_P0P0_DN<12>!U2D1!AU10!@baseboard_fab2_lib.baseboard_fab2(sch_1):page67_i132@chpset_lib.skx_ext_b(chips)!SKX_EXT_B_BGA1-IC,TBD!!!F119!UPI0_RX_DN(12)!!!!
S!UPI_CPU0_CPU1_P0P0_DN<13>!U2D1!BA8!@baseboard_fab2_lib.baseboard_fab2(sch_1):page67_i132@chpset_lib.skx_ext_b(chips)!SKX_EXT_B_BGA1-IC,TBD!!!F119!UPI0_RX_DN(13)!!!!
S!UPI_CPU0_CPU1_P0P0_DP<14>!U2D1!BC6!@baseboard_fab2_lib.baseboard_fab2(sch_1):page67_i132@chpset_lib.skx_ext_b(chips)!SKX_EXT_B_BGA1-IC,TBD!!!F119!UPI0_RX_DN(14)!!!!
S!UPI_CPU0_CPU1_P0P0_DN<15>!U2D1!BD7!@baseboard_fab2_lib.baseboard_fab2(sch_1):page67_i132@chpset_lib.skx_ext_b(chips)!SKX_EXT_B_BGA1-IC,TBD!!!F119!UPI0_RX_DN(15)!!!!
S!UPI_CPU0_CPU1_P0P0_DN<16>!U2D1!AW8!@baseboard_fab2_lib.baseboard_fab2(sch_1):page67_i132@chpset_lib.skx_ext_b(chips)!SKX_EXT_B_BGA1-IC,TBD!!!F119!UPI0_RX_DN(16)!!!!
S!UPI_CPU0_CPU1_P0P0_DN<17>!U2D1!AY9!@baseboard_fab2_lib.baseboard_fab2(sch_1):page67_i132@chpset_lib.skx_ext_b(chips)!SKX_EXT_B_BGA1-IC,TBD!!!F119!UPI0_RX_DN(17)!!!!
S!UPI_CPU0_CPU1_P0P0_DP<18>!U2D1!BD9!@baseboard_fab2_lib.baseboard_fab2(sch_1):page67_i132@chpset_lib.skx_ext_b(chips)!SKX_EXT_B_BGA1-IC,TBD!!!F119!UPI0_RX_DN(18)!!!!
S!UPI_CPU0_CPU1_P0P0_DP<19>!U2D1!BB11!@baseboard_fab2_lib.baseboard_fab2(sch_1):page67_i132@chpset_lib.skx_ext_b(chips)!SKX_EXT_B_BGA1-IC,TBD!!!F119!UPI0_RX_DN(19)!!!!
S!UPI_CPU0_CPU1_P0P0_DN<1>!U2D1!AA8!@baseboard_fab2_lib.baseboard_fab2(sch_1):page67_i132@chpset_lib.skx_ext_b(chips)!SKX_EXT_B_BGA1-IC,TBD!!!F119!UPI0_RX_DN(1)!!!!
S!UPI_CPU0_CPU1_P0P0_DN<2>!U2D1!AB7!@baseboard_fab2_lib.baseboard_fab2(sch_1):page67_i132@chpset_lib.skx_ext_b(chips)!SKX_EXT_B_BGA1-IC,TBD!!!F119!UPI0_RX_DN(2)!!!!
S!UPI_CPU0_CPU1_P0P0_DP<3>!U2D1!AD5!@baseboard_fab2_lib.baseboard_fab2(sch_1):page67_i132@chpset_lib.skx_ext_b(chips)!SKX_EXT_B_BGA1-IC,TBD!!!F119!UPI0_RX_DN(3)!!!!
S!UPI_CPU0_CPU1_P0P0_DP<4>!U2D1!AE6!@baseboard_fab2_lib.baseboard_fab2(sch_1):page67_i132@chpset_lib.skx_ext_b(chips)!SKX_EXT_B_BGA1-IC,TBD!!!F119!UPI0_RX_DN(4)!!!!
S!UPI_CPU0_CPU1_P0P0_DP<5>!U2D1!AG8!@baseboard_fab2_lib.baseboard_fab2(sch_1):page67_i132@chpset_lib.skx_ext_b(chips)!SKX_EXT_B_BGA1-IC,TBD!!!F119!UPI0_RX_DN(5)!!!!
S!UPI_CPU0_CPU1_P0P0_DP<6>!U2D1!AJ6!@baseboard_fab2_lib.baseboard_fab2(sch_1):page67_i132@chpset_lib.skx_ext_b(chips)!SKX_EXT_B_BGA1-IC,TBD!!!F119!UPI0_RX_DN(6)!!!!
S!UPI_CPU0_CPU1_P0P0_DP<7>!U2D1!AL6!@baseboard_fab2_lib.baseboard_fab2(sch_1):page67_i132@chpset_lib.skx_ext_b(chips)!SKX_EXT_B_BGA1-IC,TBD!!!F119!UPI0_RX_DN(7)!!!!
S!UPI_CPU0_CPU1_P0P0_DP<8>!U2D1!AK7!@baseboard_fab2_lib.baseboard_fab2(sch_1):page67_i132@chpset_lib.skx_ext_b(chips)!SKX_EXT_B_BGA1-IC,TBD!!!F119!UPI0_RX_DN(8)!!!!
S!UPI_CPU0_CPU1_P0P0_DP<9>!U2D1!AM9!@baseboard_fab2_lib.baseboard_fab2(sch_1):page67_i132@chpset_lib.skx_ext_b(chips)!SKX_EXT_B_BGA1-IC,TBD!!!F119!UPI0_RX_DN(9)!!!!
S!UPI_CPU0_CPU1_P0P0_DN<0>!U2D1!AB9!@baseboard_fab2_lib.baseboard_fab2(sch_1):page67_i132@chpset_lib.skx_ext_b(chips)!SKX_EXT_B_BGA1-IC,TBD!!!F119!UPI0_RX_DP(0)!!!!
S!UPI_CPU0_CPU1_P0P0_DP<10>!U2D1!AN8!@baseboard_fab2_lib.baseboard_fab2(sch_1):page67_i132@chpset_lib.skx_ext_b(chips)!SKX_EXT_B_BGA1-IC,TBD!!!F119!UPI0_RX_DP(10)!!!!
S!UPI_CPU0_CPU1_P0P0_DN<11>!U2D1!AU8!@baseboard_fab2_lib.baseboard_fab2(sch_1):page67_i132@chpset_lib.skx_ext_b(chips)!SKX_EXT_B_BGA1-IC,TBD!!!F119!UPI0_RX_DP(11)!!!!
S!UPI_CPU0_CPU1_P0P0_DP<12>!U2D1!AT9!@baseboard_fab2_lib.baseboard_fab2(sch_1):page67_i132@chpset_lib.skx_ext_b(chips)!SKX_EXT_B_BGA1-IC,TBD!!!F119!UPI0_RX_DP(12)!!!!
S!UPI_CPU0_CPU1_P0P0_DP<13>!U2D1!AY7!@baseboard_fab2_lib.baseboard_fab2(sch_1):page67_i132@chpset_lib.skx_ext_b(chips)!SKX_EXT_B_BGA1-IC,TBD!!!F119!UPI0_RX_DP(13)!!!!
S!UPI_CPU0_CPU1_P0P0_DN<14>!U2D1!BB7!@baseboard_fab2_lib.baseboard_fab2(sch_1):page67_i132@chpset_lib.skx_ext_b(chips)!SKX_EXT_B_BGA1-IC,TBD!!!F119!UPI0_RX_DP(14)!!!!
S!UPI_CPU0_CPU1_P0P0_DP<15>!U2D1!BF7!@baseboard_fab2_lib.baseboard_fab2(sch_1):page67_i132@chpset_lib.skx_ext_b(chips)!SKX_EXT_B_BGA1-IC,TBD!!!F119!UPI0_RX_DP(15)!!!!
S!UPI_CPU0_CPU1_P0P0_DP<16>!U2D1!AV9!@baseboard_fab2_lib.baseboard_fab2(sch_1):page67_i132@chpset_lib.skx_ext_b(chips)!SKX_EXT_B_BGA1-IC,TBD!!!F119!UPI0_RX_DP(16)!!!!
S!UPI_CPU0_CPU1_P0P0_DP<17>!U2D1!BB9!@baseboard_fab2_lib.baseboard_fab2(sch_1):page67_i132@chpset_lib.skx_ext_b(chips)!SKX_EXT_B_BGA1-IC,TBD!!!F119!UPI0_RX_DP(17)!!!!
S!UPI_CPU0_CPU1_P0P0_DN<18>!U2D1!BC10!@baseboard_fab2_lib.baseboard_fab2(sch_1):page67_i132@chpset_lib.skx_ext_b(chips)!SKX_EXT_B_BGA1-IC,TBD!!!F119!UPI0_RX_DP(18)!!!!
S!UPI_CPU0_CPU1_P0P0_DN<19>!U2D1!BA10!@baseboard_fab2_lib.baseboard_fab2(sch_1):page67_i132@chpset_lib.skx_ext_b(chips)!SKX_EXT_B_BGA1-IC,TBD!!!F119!UPI0_RX_DP(19)!!!!
S!UPI_CPU0_CPU1_P0P0_DP<1>!U2D1!AC8!@baseboard_fab2_lib.baseboard_fab2(sch_1):page67_i132@chpset_lib.skx_ext_b(chips)!SKX_EXT_B_BGA1-IC,TBD!!!F119!UPI0_RX_DP(1)!!!!
S!UPI_CPU0_CPU1_P0P0_DP<2>!U2D1!AA6!@baseboard_fab2_lib.baseboard_fab2(sch_1):page67_i132@chpset_lib.skx_ext_b(chips)!SKX_EXT_B_BGA1-IC,TBD!!!F119!UPI0_RX_DP(2)!!!!
S!UPI_CPU0_CPU1_P0P0_DN<3>!U2D1!AC6!@baseboard_fab2_lib.baseboard_fab2(sch_1):page67_i132@chpset_lib.skx_ext_b(chips)!SKX_EXT_B_BGA1-IC,TBD!!!F119!UPI0_RX_DP(3)!!!!
S!UPI_CPU0_CPU1_P0P0_DN<4>!U2D1!AG6!@baseboard_fab2_lib.baseboard_fab2(sch_1):page67_i132@chpset_lib.skx_ext_b(chips)!SKX_EXT_B_BGA1-IC,TBD!!!F119!UPI0_RX_DP(4)!!!!
S!UPI_CPU0_CPU1_P0P0_DN<5>!U2D1!AF7!@baseboard_fab2_lib.baseboard_fab2(sch_1):page67_i132@chpset_lib.skx_ext_b(chips)!SKX_EXT_B_BGA1-IC,TBD!!!F119!UPI0_RX_DP(5)!!!!
S!UPI_CPU0_CPU1_P0P0_DN<6>!U2D1!AH7!@baseboard_fab2_lib.baseboard_fab2(sch_1):page67_i132@chpset_lib.skx_ext_b(chips)!SKX_EXT_B_BGA1-IC,TBD!!!F119!UPI0_RX_DP(6)!!!!
S!UPI_CPU0_CPU1_P0P0_DN<7>!U2D1!AK5!@baseboard_fab2_lib.baseboard_fab2(sch_1):page67_i132@chpset_lib.skx_ext_b(chips)!SKX_EXT_B_BGA1-IC,TBD!!!F119!UPI0_RX_DP(7)!!!!
S!UPI_CPU0_CPU1_P0P0_DN<8>!U2D1!AM7!@baseboard_fab2_lib.baseboard_fab2(sch_1):page67_i132@chpset_lib.skx_ext_b(chips)!SKX_EXT_B_BGA1-IC,TBD!!!F119!UPI0_RX_DP(8)!!!!
S!UPI_CPU0_CPU1_P0P0_DN<9>!U2D1!AL8!@baseboard_fab2_lib.baseboard_fab2(sch_1):page67_i132@chpset_lib.skx_ext_b(chips)!SKX_EXT_B_BGA1-IC,TBD!!!F119!UPI0_RX_DP(9)!!!!
S!UPI_CPU1_CPU0_P0P0_DP<0>!U2D1!N2!@baseboard_fab2_lib.baseboard_fab2(sch_1):page67_i132@chpset_lib.skx_ext_b(chips)!SKX_EXT_B_BGA1-IC,TBD!!!F119!UPI0_TX_DN(0)!!!!
S!UPI_CPU1_CPU0_P0P0_DP<10>!U2D1!AM3!@baseboard_fab2_lib.baseboard_fab2(sch_1):page67_i132@chpset_lib.skx_ext_b(chips)!SKX_EXT_B_BGA1-IC,TBD!!!F119!UPI0_TX_DN(10)!!!!
S!UPI_CPU1_CPU0_P0P0_DP<11>!U2D1!AN4!@baseboard_fab2_lib.baseboard_fab2(sch_1):page67_i132@chpset_lib.skx_ext_b(chips)!SKX_EXT_B_BGA1-IC,TBD!!!F119!UPI0_TX_DN(11)!!!!
S!UPI_CPU1_CPU0_P0P0_DP<12>!U2D1!AT1!@baseboard_fab2_lib.baseboard_fab2(sch_1):page67_i132@chpset_lib.skx_ext_b(chips)!SKX_EXT_B_BGA1-IC,TBD!!!F119!UPI0_TX_DN(12)!!!!
S!UPI_CPU1_CPU0_P0P0_DP<13>!U2D1!AT3!@baseboard_fab2_lib.baseboard_fab2(sch_1):page67_i132@chpset_lib.skx_ext_b(chips)!SKX_EXT_B_BGA1-IC,TBD!!!F119!UPI0_TX_DN(13)!!!!
S!UPI_CPU1_CPU0_P0P0_DP<14>!U2D1!AU4!@baseboard_fab2_lib.baseboard_fab2(sch_1):page67_i132@chpset_lib.skx_ext_b(chips)!SKX_EXT_B_BGA1-IC,TBD!!!F119!UPI0_TX_DN(14)!!!!
S!UPI_CPU1_CPU0_P0P0_DP<15>!U2D1!AV5!@baseboard_fab2_lib.baseboard_fab2(sch_1):page67_i132@chpset_lib.skx_ext_b(chips)!SKX_EXT_B_BGA1-IC,TBD!!!F119!UPI0_TX_DN(15)!!!!
S!UPI_CPU1_CPU0_P0P0_DP<16>!U2D1!BA4!@baseboard_fab2_lib.baseboard_fab2(sch_1):page67_i132@chpset_lib.skx_ext_b(chips)!SKX_EXT_B_BGA1-IC,TBD!!!F119!UPI0_TX_DN(16)!!!!
S!UPI_CPU1_CPU0_P0P0_DN<17>!U2D1!BB3!@baseboard_fab2_lib.baseboard_fab2(sch_1):page67_i132@chpset_lib.skx_ext_b(chips)!SKX_EXT_B_BGA1-IC,TBD!!!F119!UPI0_TX_DN(17)!!!!
S!UPI_CPU1_CPU0_P0P0_DN<18>!U2D1!BF3!@baseboard_fab2_lib.baseboard_fab2(sch_1):page67_i132@chpset_lib.skx_ext_b(chips)!SKX_EXT_B_BGA1-IC,TBD!!!F119!UPI0_TX_DN(18)!!!!
S!UPI_CPU1_CPU0_P0P0_DP<19>!U2D1!BG4!@baseboard_fab2_lib.baseboard_fab2(sch_1):page67_i132@chpset_lib.skx_ext_b(chips)!SKX_EXT_B_BGA1-IC,TBD!!!F119!UPI0_TX_DN(19)!!!!
S!UPI_CPU1_CPU0_P0P0_DP<1>!U2D1!P1!@baseboard_fab2_lib.baseboard_fab2(sch_1):page67_i132@chpset_lib.skx_ext_b(chips)!SKX_EXT_B_BGA1-IC,TBD!!!F119!UPI0_TX_DN(1)!!!!
S!UPI_CPU1_CPU0_P0P0_DN<2>!U2D1!V3!@baseboard_fab2_lib.baseboard_fab2(sch_1):page67_i132@chpset_lib.skx_ext_b(chips)!SKX_EXT_B_BGA1-IC,TBD!!!F119!UPI0_TX_DN(2)!!!!
S!UPI_CPU1_CPU0_P0P0_DN<3>!U2D1!Y1!@baseboard_fab2_lib.baseboard_fab2(sch_1):page67_i132@chpset_lib.skx_ext_b(chips)!SKX_EXT_B_BGA1-IC,TBD!!!F119!UPI0_TX_DN(3)!!!!
S!UPI_CPU1_CPU0_P0P0_DN<4>!U2D1!AB3!@baseboard_fab2_lib.baseboard_fab2(sch_1):page67_i132@chpset_lib.skx_ext_b(chips)!SKX_EXT_B_BGA1-IC,TBD!!!F119!UPI0_TX_DN(4)!!!!
S!UPI_CPU1_CPU0_P0P0_DP<5>!U2D1!AC2!@baseboard_fab2_lib.baseboard_fab2(sch_1):page67_i132@chpset_lib.skx_ext_b(chips)!SKX_EXT_B_BGA1-IC,TBD!!!F119!UPI0_TX_DN(5)!!!!
S!UPI_CPU1_CPU0_P0P0_DN<6>!U2D1!AG4!@baseboard_fab2_lib.baseboard_fab2(sch_1):page67_i132@chpset_lib.skx_ext_b(chips)!SKX_EXT_B_BGA1-IC,TBD!!!F119!UPI0_TX_DN(6)!!!!
S!UPI_CPU1_CPU0_P0P0_DN<7>!U2D1!AE2!@baseboard_fab2_lib.baseboard_fab2(sch_1):page67_i132@chpset_lib.skx_ext_b(chips)!SKX_EXT_B_BGA1-IC,TBD!!!F119!UPI0_TX_DN(7)!!!!
S!UPI_CPU1_CPU0_P0P0_DP<8>!U2D1!AH3!@baseboard_fab2_lib.baseboard_fab2(sch_1):page67_i132@chpset_lib.skx_ext_b(chips)!SKX_EXT_B_BGA1-IC,TBD!!!F119!UPI0_TX_DN(8)!!!!
S!UPI_CPU1_CPU0_P0P0_DN<9>!U2D1!AL2!@baseboard_fab2_lib.baseboard_fab2(sch_1):page67_i132@chpset_lib.skx_ext_b(chips)!SKX_EXT_B_BGA1-IC,TBD!!!F119!UPI0_TX_DN(9)!!!!
S!UPI_CPU1_CPU0_P0P0_DN<0>!U2D1!M1!@baseboard_fab2_lib.baseboard_fab2(sch_1):page67_i132@chpset_lib.skx_ext_b(chips)!SKX_EXT_B_BGA1-IC,TBD!!!F119!UPI0_TX_DP(0)!!!!
S!UPI_CPU1_CPU0_P0P0_DN<10>!U2D1!AK3!@baseboard_fab2_lib.baseboard_fab2(sch_1):page67_i132@chpset_lib.skx_ext_b(chips)!SKX_EXT_B_BGA1-IC,TBD!!!F119!UPI0_TX_DP(10)!!!!
S!UPI_CPU1_CPU0_P0P0_DN<11>!U2D1!AP3!@baseboard_fab2_lib.baseboard_fab2(sch_1):page67_i132@chpset_lib.skx_ext_b(chips)!SKX_EXT_B_BGA1-IC,TBD!!!F119!UPI0_TX_DP(11)!!!!
S!UPI_CPU1_CPU0_P0P0_DN<12>!U2D1!AP1!@baseboard_fab2_lib.baseboard_fab2(sch_1):page67_i132@chpset_lib.skx_ext_b(chips)!SKX_EXT_B_BGA1-IC,TBD!!!F119!UPI0_TX_DP(12)!!!!
S!UPI_CPU1_CPU0_P0P0_DN<13>!U2D1!AR2!@baseboard_fab2_lib.baseboard_fab2(sch_1):page67_i132@chpset_lib.skx_ext_b(chips)!SKX_EXT_B_BGA1-IC,TBD!!!F119!UPI0_TX_DP(13)!!!!
S!UPI_CPU1_CPU0_P0P0_DN<14>!U2D1!AR4!@baseboard_fab2_lib.baseboard_fab2(sch_1):page67_i132@chpset_lib.skx_ext_b(chips)!SKX_EXT_B_BGA1-IC,TBD!!!F119!UPI0_TX_DP(14)!!!!
S!UPI_CPU1_CPU0_P0P0_DN<15>!U2D1!AW4!@baseboard_fab2_lib.baseboard_fab2(sch_1):page67_i132@chpset_lib.skx_ext_b(chips)!SKX_EXT_B_BGA1-IC,TBD!!!F119!UPI0_TX_DP(15)!!!!
S!UPI_CPU1_CPU0_P0P0_DN<16>!U2D1!AY3!@baseboard_fab2_lib.baseboard_fab2(sch_1):page67_i132@chpset_lib.skx_ext_b(chips)!SKX_EXT_B_BGA1-IC,TBD!!!F119!UPI0_TX_DP(16)!!!!
S!UPI_CPU1_CPU0_P0P0_DP<17>!U2D1!BC2!@baseboard_fab2_lib.baseboard_fab2(sch_1):page67_i132@chpset_lib.skx_ext_b(chips)!SKX_EXT_B_BGA1-IC,TBD!!!F119!UPI0_TX_DP(17)!!!!
S!UPI_CPU1_CPU0_P0P0_DP<18>!U2D1!BD3!@baseboard_fab2_lib.baseboard_fab2(sch_1):page67_i132@chpset_lib.skx_ext_b(chips)!SKX_EXT_B_BGA1-IC,TBD!!!F119!UPI0_TX_DP(18)!!!!
S!UPI_CPU1_CPU0_P0P0_DN<19>!U2D1!BH3!@baseboard_fab2_lib.baseboard_fab2(sch_1):page67_i132@chpset_lib.skx_ext_b(chips)!SKX_EXT_B_BGA1-IC,TBD!!!F119!UPI0_TX_DP(19)!!!!
S!UPI_CPU1_CPU0_P0P0_DN<1>!U2D1!T1!@baseboard_fab2_lib.baseboard_fab2(sch_1):page67_i132@chpset_lib.skx_ext_b(chips)!SKX_EXT_B_BGA1-IC,TBD!!!F119!UPI0_TX_DP(1)!!!!
S!UPI_CPU1_CPU0_P0P0_DP<2>!U2D1!Y3!@baseboard_fab2_lib.baseboard_fab2(sch_1):page67_i132@chpset_lib.skx_ext_b(chips)!SKX_EXT_B_BGA1-IC,TBD!!!F119!UPI0_TX_DP(2)!!!!
S!UPI_CPU1_CPU0_P0P0_DP<3>!U2D1!W2!@baseboard_fab2_lib.baseboard_fab2(sch_1):page67_i132@chpset_lib.skx_ext_b(chips)!SKX_EXT_B_BGA1-IC,TBD!!!F119!UPI0_TX_DP(3)!!!!
S!UPI_CPU1_CPU0_P0P0_DP<4>!U2D1!AA2!@baseboard_fab2_lib.baseboard_fab2(sch_1):page67_i132@chpset_lib.skx_ext_b(chips)!SKX_EXT_B_BGA1-IC,TBD!!!F119!UPI0_TX_DP(4)!!!!
S!UPI_CPU1_CPU0_P0P0_DN<5>!U2D1!AD1!@baseboard_fab2_lib.baseboard_fab2(sch_1):page67_i132@chpset_lib.skx_ext_b(chips)!SKX_EXT_B_BGA1-IC,TBD!!!F119!UPI0_TX_DP(5)!!!!
S!UPI_CPU1_CPU0_P0P0_DP<6>!U2D1!AF3!@baseboard_fab2_lib.baseboard_fab2(sch_1):page67_i132@chpset_lib.skx_ext_b(chips)!SKX_EXT_B_BGA1-IC,TBD!!!F119!UPI0_TX_DP(6)!!!!
S!UPI_CPU1_CPU0_P0P0_DP<7>!U2D1!AG2!@baseboard_fab2_lib.baseboard_fab2(sch_1):page67_i132@chpset_lib.skx_ext_b(chips)!SKX_EXT_B_BGA1-IC,TBD!!!F119!UPI0_TX_DP(7)!!!!
S!UPI_CPU1_CPU0_P0P0_DN<8>!U2D1!AJ2!@baseboard_fab2_lib.baseboard_fab2(sch_1):page67_i132@chpset_lib.skx_ext_b(chips)!SKX_EXT_B_BGA1-IC,TBD!!!F119!UPI0_TX_DP(8)!!!!
S!UPI_CPU1_CPU0_P0P0_DP<9>!U2D1!AK1!@baseboard_fab2_lib.baseboard_fab2(sch_1):page67_i132@chpset_lib.skx_ext_b(chips)!SKX_EXT_B_BGA1-IC,TBD!!!F119!UPI0_TX_DP(9)!!!!
S!UPI_CPU0_CPU1_P1P1_DP<0>!U2D1!T5!@baseboard_fab2_lib.baseboard_fab2(sch_1):page68_i125@chpset_lib.skx_ext_b(chips)!SKX_EXT_B_BGA1-IC,TBD!!!F118!UPI1_RX_DN(0)!!!!
S!UPI_CPU0_CPU1_P1P1_DN<10>!U2D1!R16!@baseboard_fab2_lib.baseboard_fab2(sch_1):page68_i125@chpset_lib.skx_ext_b(chips)!SKX_EXT_B_BGA1-IC,TBD!!!F118!UPI1_RX_DN(10)!!!!
S!UPI_CPU0_CPU1_P1P1_DP<11>!U2D1!P17!@baseboard_fab2_lib.baseboard_fab2(sch_1):page68_i125@chpset_lib.skx_ext_b(chips)!SKX_EXT_B_BGA1-IC,TBD!!!F118!UPI1_RX_DN(11)!!!!
S!UPI_CPU0_CPU1_P1P1_DP<12>!U2D1!U16!@baseboard_fab2_lib.baseboard_fab2(sch_1):page68_i125@chpset_lib.skx_ext_b(chips)!SKX_EXT_B_BGA1-IC,TBD!!!F118!UPI1_RX_DN(12)!!!!
S!UPI_CPU0_CPU1_P1P1_DP<13>!U2D1!W18!@baseboard_fab2_lib.baseboard_fab2(sch_1):page68_i125@chpset_lib.skx_ext_b(chips)!SKX_EXT_B_BGA1-IC,TBD!!!F118!UPI1_RX_DN(13)!!!!
S!UPI_CPU0_CPU1_P1P1_DN<14>!U2D1!R20!@baseboard_fab2_lib.baseboard_fab2(sch_1):page68_i125@chpset_lib.skx_ext_b(chips)!SKX_EXT_B_BGA1-IC,TBD!!!F118!UPI1_RX_DN(14)!!!!
S!UPI_CPU0_CPU1_P1P1_DN<15>!U2D1!U18!@baseboard_fab2_lib.baseboard_fab2(sch_1):page68_i125@chpset_lib.skx_ext_b(chips)!SKX_EXT_B_BGA1-IC,TBD!!!F118!UPI1_RX_DN(15)!!!!
S!UPI_CPU0_CPU1_P1P1_DN<16>!U2D1!P21!@baseboard_fab2_lib.baseboard_fab2(sch_1):page68_i125@chpset_lib.skx_ext_b(chips)!SKX_EXT_B_BGA1-IC,TBD!!!F118!UPI1_RX_DN(16)!!!!
S!UPI_CPU0_CPU1_P1P1_DN<17>!U2D1!V19!@baseboard_fab2_lib.baseboard_fab2(sch_1):page68_i125@chpset_lib.skx_ext_b(chips)!SKX_EXT_B_BGA1-IC,TBD!!!F118!UPI1_RX_DN(17)!!!!
S!UPI_CPU0_CPU1_P1P1_DP<18>!U2D1!Y21!@baseboard_fab2_lib.baseboard_fab2(sch_1):page68_i125@chpset_lib.skx_ext_b(chips)!SKX_EXT_B_BGA1-IC,TBD!!!F118!UPI1_RX_DN(18)!!!!
S!UPI_CPU0_CPU1_P1P1_DP<19>!U2D1!AB19!@baseboard_fab2_lib.baseboard_fab2(sch_1):page68_i125@chpset_lib.skx_ext_b(chips)!SKX_EXT_B_BGA1-IC,TBD!!!F118!UPI1_RX_DN(19)!!!!
S!UPI_CPU0_CPU1_P1P1_DN<1>!U2D1!P7!@baseboard_fab2_lib.baseboard_fab2(sch_1):page68_i125@chpset_lib.skx_ext_b(chips)!SKX_EXT_B_BGA1-IC,TBD!!!F118!UPI1_RX_DN(1)!!!!
S!UPI_CPU0_CPU1_P1P1_DN<2>!U2D1!V7!@baseboard_fab2_lib.baseboard_fab2(sch_1):page68_i125@chpset_lib.skx_ext_b(chips)!SKX_EXT_B_BGA1-IC,TBD!!!F118!UPI1_RX_DN(2)!!!!
S!UPI_CPU0_CPU1_P1P1_DN<3>!U2D1!T9!@baseboard_fab2_lib.baseboard_fab2(sch_1):page68_i125@chpset_lib.skx_ext_b(chips)!SKX_EXT_B_BGA1-IC,TBD!!!F118!UPI1_RX_DN(3)!!!!
S!UPI_CPU0_CPU1_P1P1_DN<4>!U2D1!P9!@baseboard_fab2_lib.baseboard_fab2(sch_1):page68_i125@chpset_lib.skx_ext_b(chips)!SKX_EXT_B_BGA1-IC,TBD!!!F118!UPI1_RX_DN(4)!!!!
S!UPI_CPU0_CPU1_P1P1_DN<5>!U2D1!R10!@baseboard_fab2_lib.baseboard_fab2(sch_1):page68_i125@chpset_lib.skx_ext_b(chips)!SKX_EXT_B_BGA1-IC,TBD!!!F118!UPI1_RX_DN(5)!!!!
S!UPI_CPU0_CPU1_P1P1_DN<6>!U2D1!U12!@baseboard_fab2_lib.baseboard_fab2(sch_1):page68_i125@chpset_lib.skx_ext_b(chips)!SKX_EXT_B_BGA1-IC,TBD!!!F118!UPI1_RX_DN(6)!!!!
S!UPI_CPU0_CPU1_P1P1_DN<7>!U2D1!L12!@baseboard_fab2_lib.baseboard_fab2(sch_1):page68_i125@chpset_lib.skx_ext_b(chips)!SKX_EXT_B_BGA1-IC,TBD!!!F118!UPI1_RX_DN(7)!!!!
S!UPI_CPU0_CPU1_P1P1_DP<8>!U2D1!N14!@baseboard_fab2_lib.baseboard_fab2(sch_1):page68_i125@chpset_lib.skx_ext_b(chips)!SKX_EXT_B_BGA1-IC,TBD!!!F118!UPI1_RX_DN(8)!!!!
S!UPI_CPU0_CPU1_P1P1_DN<9>!U2D1!R12!@baseboard_fab2_lib.baseboard_fab2(sch_1):page68_i125@chpset_lib.skx_ext_b(chips)!SKX_EXT_B_BGA1-IC,TBD!!!F118!UPI1_RX_DN(9)!!!!
S!UPI_CPU0_CPU1_P1P1_DN<0>!U2D1!R6!@baseboard_fab2_lib.baseboard_fab2(sch_1):page68_i125@chpset_lib.skx_ext_b(chips)!SKX_EXT_B_BGA1-IC,TBD!!!F118!UPI1_RX_DP(0)!!!!
S!UPI_CPU0_CPU1_P1P1_DP<10>!U2D1!T15!@baseboard_fab2_lib.baseboard_fab2(sch_1):page68_i125@chpset_lib.skx_ext_b(chips)!SKX_EXT_B_BGA1-IC,TBD!!!F118!UPI1_RX_DP(10)!!!!
S!UPI_CPU0_CPU1_P1P1_DN<11>!U2D1!N16!@baseboard_fab2_lib.baseboard_fab2(sch_1):page68_i125@chpset_lib.skx_ext_b(chips)!SKX_EXT_B_BGA1-IC,TBD!!!F118!UPI1_RX_DP(11)!!!!
S!UPI_CPU0_CPU1_P1P1_DN<12>!U2D1!W16!@baseboard_fab2_lib.baseboard_fab2(sch_1):page68_i125@chpset_lib.skx_ext_b(chips)!SKX_EXT_B_BGA1-IC,TBD!!!F118!UPI1_RX_DP(12)!!!!
S!UPI_CPU0_CPU1_P1P1_DN<13>!U2D1!V17!@baseboard_fab2_lib.baseboard_fab2(sch_1):page68_i125@chpset_lib.skx_ext_b(chips)!SKX_EXT_B_BGA1-IC,TBD!!!F118!UPI1_RX_DP(13)!!!!
S!UPI_CPU0_CPU1_P1P1_DP<14>!U2D1!P19!@baseboard_fab2_lib.baseboard_fab2(sch_1):page68_i125@chpset_lib.skx_ext_b(chips)!SKX_EXT_B_BGA1-IC,TBD!!!F118!UPI1_RX_DP(14)!!!!
S!UPI_CPU0_CPU1_P1P1_DP<15>!U2D1!T19!@baseboard_fab2_lib.baseboard_fab2(sch_1):page68_i125@chpset_lib.skx_ext_b(chips)!SKX_EXT_B_BGA1-IC,TBD!!!F118!UPI1_RX_DP(15)!!!!
S!UPI_CPU0_CPU1_P1P1_DP<16>!U2D1!T21!@baseboard_fab2_lib.baseboard_fab2(sch_1):page68_i125@chpset_lib.skx_ext_b(chips)!SKX_EXT_B_BGA1-IC,TBD!!!F118!UPI1_RX_DP(16)!!!!
S!UPI_CPU0_CPU1_P1P1_DP<17>!U2D1!Y19!@baseboard_fab2_lib.baseboard_fab2(sch_1):page68_i125@chpset_lib.skx_ext_b(chips)!SKX_EXT_B_BGA1-IC,TBD!!!F118!UPI1_RX_DP(17)!!!!
S!UPI_CPU0_CPU1_P1P1_DN<18>!U2D1!W20!@baseboard_fab2_lib.baseboard_fab2(sch_1):page68_i125@chpset_lib.skx_ext_b(chips)!SKX_EXT_B_BGA1-IC,TBD!!!F118!UPI1_RX_DP(18)!!!!
S!UPI_CPU0_CPU1_P1P1_DN<19>!U2D1!AA20!@baseboard_fab2_lib.baseboard_fab2(sch_1):page68_i125@chpset_lib.skx_ext_b(chips)!SKX_EXT_B_BGA1-IC,TBD!!!F118!UPI1_RX_DP(19)!!!!
S!UPI_CPU0_CPU1_P1P1_DP<1>!U2D1!T7!@baseboard_fab2_lib.baseboard_fab2(sch_1):page68_i125@chpset_lib.skx_ext_b(chips)!SKX_EXT_B_BGA1-IC,TBD!!!F118!UPI1_RX_DP(1)!!!!
S!UPI_CPU0_CPU1_P1P1_DP<2>!U2D1!U8!@baseboard_fab2_lib.baseboard_fab2(sch_1):page68_i125@chpset_lib.skx_ext_b(chips)!SKX_EXT_B_BGA1-IC,TBD!!!F118!UPI1_RX_DP(2)!!!!
S!UPI_CPU0_CPU1_P1P1_DP<3>!U2D1!R8!@baseboard_fab2_lib.baseboard_fab2(sch_1):page68_i125@chpset_lib.skx_ext_b(chips)!SKX_EXT_B_BGA1-IC,TBD!!!F118!UPI1_RX_DP(3)!!!!
S!UPI_CPU0_CPU1_P1P1_DP<4>!U2D1!N10!@baseboard_fab2_lib.baseboard_fab2(sch_1):page68_i125@chpset_lib.skx_ext_b(chips)!SKX_EXT_B_BGA1-IC,TBD!!!F118!UPI1_RX_DP(4)!!!!
S!UPI_CPU0_CPU1_P1P1_DP<5>!U2D1!U10!@baseboard_fab2_lib.baseboard_fab2(sch_1):page68_i125@chpset_lib.skx_ext_b(chips)!SKX_EXT_B_BGA1-IC,TBD!!!F118!UPI1_RX_DP(5)!!!!
S!UPI_CPU0_CPU1_P1P1_DP<6>!U2D1!T11!@baseboard_fab2_lib.baseboard_fab2(sch_1):page68_i125@chpset_lib.skx_ext_b(chips)!SKX_EXT_B_BGA1-IC,TBD!!!F118!UPI1_RX_DP(6)!!!!
S!UPI_CPU0_CPU1_P1P1_DP<7>!U2D1!N12!@baseboard_fab2_lib.baseboard_fab2(sch_1):page68_i125@chpset_lib.skx_ext_b(chips)!SKX_EXT_B_BGA1-IC,TBD!!!F118!UPI1_RX_DP(7)!!!!
S!UPI_CPU0_CPU1_P1P1_DN<8>!U2D1!M13!@baseboard_fab2_lib.baseboard_fab2(sch_1):page68_i125@chpset_lib.skx_ext_b(chips)!SKX_EXT_B_BGA1-IC,TBD!!!F118!UPI1_RX_DP(8)!!!!
S!UPI_CPU0_CPU1_P1P1_DP<9>!U2D1!P13!@baseboard_fab2_lib.baseboard_fab2(sch_1):page68_i125@chpset_lib.skx_ext_b(chips)!SKX_EXT_B_BGA1-IC,TBD!!!F118!UPI1_RX_DP(9)!!!!
S!UPI_CPU1_CPU0_P1P1_DP<0>!U2D1!M3!@baseboard_fab2_lib.baseboard_fab2(sch_1):page68_i125@chpset_lib.skx_ext_b(chips)!SKX_EXT_B_BGA1-IC,TBD!!!F118!UPI1_TX_DN(0)!!!!
S!UPI_CPU1_CPU0_P1P1_DN<10>!U2D1!E12!@baseboard_fab2_lib.baseboard_fab2(sch_1):page68_i125@chpset_lib.skx_ext_b(chips)!SKX_EXT_B_BGA1-IC,TBD!!!F118!UPI1_TX_DN(10)!!!!
S!UPI_CPU1_CPU0_P1P1_DP<11>!U2D1!G14!@baseboard_fab2_lib.baseboard_fab2(sch_1):page68_i125@chpset_lib.skx_ext_b(chips)!SKX_EXT_B_BGA1-IC,TBD!!!F118!UPI1_TX_DN(11)!!!!
S!UPI_CPU1_CPU0_P1P1_DN<12>!U2D1!D15!@baseboard_fab2_lib.baseboard_fab2(sch_1):page68_i125@chpset_lib.skx_ext_b(chips)!SKX_EXT_B_BGA1-IC,TBD!!!F118!UPI1_TX_DN(12)!!!!
S!UPI_CPU1_CPU0_P1P1_DN<13>!U2D1!F15!@baseboard_fab2_lib.baseboard_fab2(sch_1):page68_i125@chpset_lib.skx_ext_b(chips)!SKX_EXT_B_BGA1-IC,TBD!!!F118!UPI1_TX_DN(13)!!!!
S!UPI_CPU1_CPU0_P1P1_DN<14>!U2D1!H17!@baseboard_fab2_lib.baseboard_fab2(sch_1):page68_i125@chpset_lib.skx_ext_b(chips)!SKX_EXT_B_BGA1-IC,TBD!!!F118!UPI1_TX_DN(14)!!!!
S!UPI_CPU1_CPU0_P1P1_DN<15>!U2D1!K19!@baseboard_fab2_lib.baseboard_fab2(sch_1):page68_i125@chpset_lib.skx_ext_b(chips)!SKX_EXT_B_BGA1-IC,TBD!!!F118!UPI1_TX_DN(15)!!!!
S!UPI_CPU1_CPU0_P1P1_DN<16>!U2D1!G18!@baseboard_fab2_lib.baseboard_fab2(sch_1):page68_i125@chpset_lib.skx_ext_b(chips)!SKX_EXT_B_BGA1-IC,TBD!!!F118!UPI1_TX_DN(16)!!!!
S!UPI_CPU1_CPU0_P1P1_DN<17>!U2D1!J20!@baseboard_fab2_lib.baseboard_fab2(sch_1):page68_i125@chpset_lib.skx_ext_b(chips)!SKX_EXT_B_BGA1-IC,TBD!!!F118!UPI1_TX_DN(17)!!!!
S!UPI_CPU1_CPU0_P1P1_DP<18>!U2D1!F21!@baseboard_fab2_lib.baseboard_fab2(sch_1):page68_i125@chpset_lib.skx_ext_b(chips)!SKX_EXT_B_BGA1-IC,TBD!!!F118!UPI1_TX_DN(18)!!!!
S!UPI_CPU1_CPU0_P1P1_DP<19>!U2D1!H21!@baseboard_fab2_lib.baseboard_fab2(sch_1):page68_i125@chpset_lib.skx_ext_b(chips)!SKX_EXT_B_BGA1-IC,TBD!!!F118!UPI1_TX_DN(19)!!!!
S!UPI_CPU1_CPU0_P1P1_DP<1>!U2D1!L4!@baseboard_fab2_lib.baseboard_fab2(sch_1):page68_i125@chpset_lib.skx_ext_b(chips)!SKX_EXT_B_BGA1-IC,TBD!!!F118!UPI1_TX_DN(1)!!!!
S!UPI_CPU1_CPU0_P1P1_DN<2>!U2D1!K5!@baseboard_fab2_lib.baseboard_fab2(sch_1):page68_i125@chpset_lib.skx_ext_b(chips)!SKX_EXT_B_BGA1-IC,TBD!!!F118!UPI1_TX_DN(2)!!!!
S!UPI_CPU1_CPU0_P1P1_DN<3>!U2D1!J6!@baseboard_fab2_lib.baseboard_fab2(sch_1):page68_i125@chpset_lib.skx_ext_b(chips)!SKX_EXT_B_BGA1-IC,TBD!!!F118!UPI1_TX_DN(3)!!!!
S!UPI_CPU1_CPU0_P1P1_DN<4>!U2D1!G6!@baseboard_fab2_lib.baseboard_fab2(sch_1):page68_i125@chpset_lib.skx_ext_b(chips)!SKX_EXT_B_BGA1-IC,TBD!!!F118!UPI1_TX_DN(4)!!!!
S!UPI_CPU1_CPU0_P1P1_DN<5>!U2D1!H7!@baseboard_fab2_lib.baseboard_fab2(sch_1):page68_i125@chpset_lib.skx_ext_b(chips)!SKX_EXT_B_BGA1-IC,TBD!!!F118!UPI1_TX_DN(5)!!!!
S!UPI_CPU1_CPU0_P1P1_DP<6>!U2D1!K9!@baseboard_fab2_lib.baseboard_fab2(sch_1):page68_i125@chpset_lib.skx_ext_b(chips)!SKX_EXT_B_BGA1-IC,TBD!!!F118!UPI1_TX_DN(6)!!!!
S!UPI_CPU1_CPU0_P1P1_DP<7>!U2D1!D9!@baseboard_fab2_lib.baseboard_fab2(sch_1):page68_i125@chpset_lib.skx_ext_b(chips)!SKX_EXT_B_BGA1-IC,TBD!!!F118!UPI1_TX_DN(7)!!!!
S!UPI_CPU1_CPU0_P1P1_DP<8>!U2D1!F11!@baseboard_fab2_lib.baseboard_fab2(sch_1):page68_i125@chpset_lib.skx_ext_b(chips)!SKX_EXT_B_BGA1-IC,TBD!!!F118!UPI1_TX_DN(8)!!!!
S!UPI_CPU1_CPU0_P1P1_DN<9>!U2D1!G10!@baseboard_fab2_lib.baseboard_fab2(sch_1):page68_i125@chpset_lib.skx_ext_b(chips)!SKX_EXT_B_BGA1-IC,TBD!!!F118!UPI1_TX_DN(9)!!!!
S!UPI_CPU1_CPU0_P1P1_DN<0>!U2D1!P3!@baseboard_fab2_lib.baseboard_fab2(sch_1):page68_i125@chpset_lib.skx_ext_b(chips)!SKX_EXT_B_BGA1-IC,TBD!!!F118!UPI1_TX_DP(0)!!!!
S!UPI_CPU1_CPU0_P1P1_DP<10>!U2D1!G12!@baseboard_fab2_lib.baseboard_fab2(sch_1):page68_i125@chpset_lib.skx_ext_b(chips)!SKX_EXT_B_BGA1-IC,TBD!!!F118!UPI1_TX_DP(10)!!!!
S!UPI_CPU1_CPU0_P1P1_DN<11>!U2D1!F13!@baseboard_fab2_lib.baseboard_fab2(sch_1):page68_i125@chpset_lib.skx_ext_b(chips)!SKX_EXT_B_BGA1-IC,TBD!!!F118!UPI1_TX_DP(11)!!!!
S!UPI_CPU1_CPU0_P1P1_DP<12>!U2D1!E14!@baseboard_fab2_lib.baseboard_fab2(sch_1):page68_i125@chpset_lib.skx_ext_b(chips)!SKX_EXT_B_BGA1-IC,TBD!!!F118!UPI1_TX_DP(12)!!!!
S!UPI_CPU1_CPU0_P1P1_DP<13>!U2D1!H15!@baseboard_fab2_lib.baseboard_fab2(sch_1):page68_i125@chpset_lib.skx_ext_b(chips)!SKX_EXT_B_BGA1-IC,TBD!!!F118!UPI1_TX_DP(13)!!!!
S!UPI_CPU1_CPU0_P1P1_DP<14>!U2D1!G16!@baseboard_fab2_lib.baseboard_fab2(sch_1):page68_i125@chpset_lib.skx_ext_b(chips)!SKX_EXT_B_BGA1-IC,TBD!!!F118!UPI1_TX_DP(14)!!!!
S!UPI_CPU1_CPU0_P1P1_DP<15>!U2D1!L18!@baseboard_fab2_lib.baseboard_fab2(sch_1):page68_i125@chpset_lib.skx_ext_b(chips)!SKX_EXT_B_BGA1-IC,TBD!!!F118!UPI1_TX_DP(15)!!!!
S!UPI_CPU1_CPU0_P1P1_DP<16>!U2D1!J18!@baseboard_fab2_lib.baseboard_fab2(sch_1):page68_i125@chpset_lib.skx_ext_b(chips)!SKX_EXT_B_BGA1-IC,TBD!!!F118!UPI1_TX_DP(16)!!!!
S!UPI_CPU1_CPU0_P1P1_DP<17>!U2D1!H19!@baseboard_fab2_lib.baseboard_fab2(sch_1):page68_i125@chpset_lib.skx_ext_b(chips)!SKX_EXT_B_BGA1-IC,TBD!!!F118!UPI1_TX_DP(17)!!!!
S!UPI_CPU1_CPU0_P1P1_DN<18>!U2D1!G20!@baseboard_fab2_lib.baseboard_fab2(sch_1):page68_i125@chpset_lib.skx_ext_b(chips)!SKX_EXT_B_BGA1-IC,TBD!!!F118!UPI1_TX_DP(18)!!!!
S!UPI_CPU1_CPU0_P1P1_DN<19>!U2D1!K21!@baseboard_fab2_lib.baseboard_fab2(sch_1):page68_i125@chpset_lib.skx_ext_b(chips)!SKX_EXT_B_BGA1-IC,TBD!!!F118!UPI1_TX_DP(19)!!!!
S!UPI_CPU1_CPU0_P1P1_DN<1>!U2D1!K3!@baseboard_fab2_lib.baseboard_fab2(sch_1):page68_i125@chpset_lib.skx_ext_b(chips)!SKX_EXT_B_BGA1-IC,TBD!!!F118!UPI1_TX_DP(1)!!!!
S!UPI_CPU1_CPU0_P1P1_DP<2>!U2D1!M5!@baseboard_fab2_lib.baseboard_fab2(sch_1):page68_i125@chpset_lib.skx_ext_b(chips)!SKX_EXT_B_BGA1-IC,TBD!!!F118!UPI1_TX_DP(2)!!!!
S!UPI_CPU1_CPU0_P1P1_DP<3>!U2D1!H5!@baseboard_fab2_lib.baseboard_fab2(sch_1):page68_i125@chpset_lib.skx_ext_b(chips)!SKX_EXT_B_BGA1-IC,TBD!!!F118!UPI1_TX_DP(3)!!!!
S!UPI_CPU1_CPU0_P1P1_DP<4>!U2D1!F7!@baseboard_fab2_lib.baseboard_fab2(sch_1):page68_i125@chpset_lib.skx_ext_b(chips)!SKX_EXT_B_BGA1-IC,TBD!!!F118!UPI1_TX_DP(4)!!!!
S!UPI_CPU1_CPU0_P1P1_DP<5>!U2D1!K7!@baseboard_fab2_lib.baseboard_fab2(sch_1):page68_i125@chpset_lib.skx_ext_b(chips)!SKX_EXT_B_BGA1-IC,TBD!!!F118!UPI1_TX_DP(5)!!!!
S!UPI_CPU1_CPU0_P1P1_DN<6>!U2D1!J8!@baseboard_fab2_lib.baseboard_fab2(sch_1):page68_i125@chpset_lib.skx_ext_b(chips)!SKX_EXT_B_BGA1-IC,TBD!!!F118!UPI1_TX_DP(6)!!!!
S!UPI_CPU1_CPU0_P1P1_DN<7>!U2D1!F9!@baseboard_fab2_lib.baseboard_fab2(sch_1):page68_i125@chpset_lib.skx_ext_b(chips)!SKX_EXT_B_BGA1-IC,TBD!!!F118!UPI1_TX_DP(7)!!!!
S!UPI_CPU1_CPU0_P1P1_DN<8>!U2D1!E10!@baseboard_fab2_lib.baseboard_fab2(sch_1):page68_i125@chpset_lib.skx_ext_b(chips)!SKX_EXT_B_BGA1-IC,TBD!!!F118!UPI1_TX_DP(8)!!!!
S!UPI_CPU1_CPU0_P1P1_DP<9>!U2D1!H9!@baseboard_fab2_lib.baseboard_fab2(sch_1):page68_i125@chpset_lib.skx_ext_b(chips)!SKX_EXT_B_BGA1-IC,TBD!!!F118!UPI1_TX_DP(9)!!!!
S!GND!U2D1!BY17!@baseboard_fab2_lib.baseboard_fab2(sch_1):page69_i1@chpset_lib.skx_ext_b(chips)!SKX_EXT_B_BGA1-IC,TBD!!!F117!UPI2_RX_DN(19)!!!!
S!GND!U2D1!CR18!@baseboard_fab2_lib.baseboard_fab2(sch_1):page69_i1@chpset_lib.skx_ext_b(chips)!SKX_EXT_B_BGA1-IC,TBD!!!F117!UPI2_RX_DN(9)!!!!
S!GND!U2D1!CT21!@baseboard_fab2_lib.baseboard_fab2(sch_1):page69_i1@chpset_lib.skx_ext_b(chips)!SKX_EXT_B_BGA1-IC,TBD!!!F117!UPI2_RX_DN(8)!!!!
S!GND!U2D1!CV19!@baseboard_fab2_lib.baseboard_fab2(sch_1):page69_i1@chpset_lib.skx_ext_b(chips)!SKX_EXT_B_BGA1-IC,TBD!!!F117!UPI2_RX_DN(7)!!!!
S!GND!U2D1!CW20!@baseboard_fab2_lib.baseboard_fab2(sch_1):page69_i1@chpset_lib.skx_ext_b(chips)!SKX_EXT_B_BGA1-IC,TBD!!!F117!UPI2_RX_DN(6)!!!!
S!GND!U2D1!DA20!@baseboard_fab2_lib.baseboard_fab2(sch_1):page69_i1@chpset_lib.skx_ext_b(chips)!SKX_EXT_B_BGA1-IC,TBD!!!F117!UPI2_RX_DN(5)!!!!
S!GND!U2D1!DD19!@baseboard_fab2_lib.baseboard_fab2(sch_1):page69_i1@chpset_lib.skx_ext_b(chips)!SKX_EXT_B_BGA1-IC,TBD!!!F117!UPI2_RX_DN(4)!!!!
S!GND!U2D1!DB21!@baseboard_fab2_lib.baseboard_fab2(sch_1):page69_i1@chpset_lib.skx_ext_b(chips)!SKX_EXT_B_BGA1-IC,TBD!!!F117!UPI2_RX_DN(3)!!!!
S!GND!U2D1!DC22!@baseboard_fab2_lib.baseboard_fab2(sch_1):page69_i1@chpset_lib.skx_ext_b(chips)!SKX_EXT_B_BGA1-IC,TBD!!!F117!UPI2_RX_DN(2)!!!!
S!GND!U2D1!DE22!@baseboard_fab2_lib.baseboard_fab2(sch_1):page69_i1@chpset_lib.skx_ext_b(chips)!SKX_EXT_B_BGA1-IC,TBD!!!F117!UPI2_RX_DN(1)!!!!
S!GND!U2D1!DF23!@baseboard_fab2_lib.baseboard_fab2(sch_1):page69_i1@chpset_lib.skx_ext_b(chips)!SKX_EXT_B_BGA1-IC,TBD!!!F117!UPI2_RX_DN(0)!!!!
S!GND!U2D1!CB15!@baseboard_fab2_lib.baseboard_fab2(sch_1):page69_i1@chpset_lib.skx_ext_b(chips)!SKX_EXT_B_BGA1-IC,TBD!!!F117!UPI2_RX_DN(18)!!!!
S!GND!U2D1!CF17!@baseboard_fab2_lib.baseboard_fab2(sch_1):page69_i1@chpset_lib.skx_ext_b(chips)!SKX_EXT_B_BGA1-IC,TBD!!!F117!UPI2_RX_DN(17)!!!!
S!GND!U2D1!CD15!@baseboard_fab2_lib.baseboard_fab2(sch_1):page69_i1@chpset_lib.skx_ext_b(chips)!SKX_EXT_B_BGA1-IC,TBD!!!F117!UPI2_RX_DN(16)!!!!
S!GND!U2D1!CE16!@baseboard_fab2_lib.baseboard_fab2(sch_1):page69_i1@chpset_lib.skx_ext_b(chips)!SKX_EXT_B_BGA1-IC,TBD!!!F117!UPI2_RX_DN(15)!!!!
S!GND!U2D1!CH17!@baseboard_fab2_lib.baseboard_fab2(sch_1):page69_i1@chpset_lib.skx_ext_b(chips)!SKX_EXT_B_BGA1-IC,TBD!!!F117!UPI2_RX_DN(14)!!!!
S!GND!U2D1!CJ18!@baseboard_fab2_lib.baseboard_fab2(sch_1):page69_i1@chpset_lib.skx_ext_b(chips)!SKX_EXT_B_BGA1-IC,TBD!!!F117!UPI2_RX_DN(13)!!!!
S!GND!U2D1!CL16!@baseboard_fab2_lib.baseboard_fab2(sch_1):page69_i1@chpset_lib.skx_ext_b(chips)!SKX_EXT_B_BGA1-IC,TBD!!!F117!UPI2_RX_DN(12)!!!!
S!GND!U2D1!CP21!@baseboard_fab2_lib.baseboard_fab2(sch_1):page69_i1@chpset_lib.skx_ext_b(chips)!SKX_EXT_B_BGA1-IC,TBD!!!F117!UPI2_RX_DN(11)!!!!
S!GND!U2D1!CN20!@baseboard_fab2_lib.baseboard_fab2(sch_1):page69_i1@chpset_lib.skx_ext_b(chips)!SKX_EXT_B_BGA1-IC,TBD!!!F117!UPI2_RX_DN(10)!!!!
S!GND!U2D1!CA16!@baseboard_fab2_lib.baseboard_fab2(sch_1):page69_i1@chpset_lib.skx_ext_b(chips)!SKX_EXT_B_BGA1-IC,TBD!!!F117!UPI2_RX_DP(19)!!!!
S!GND!U2D1!CN18!@baseboard_fab2_lib.baseboard_fab2(sch_1):page69_i1@chpset_lib.skx_ext_b(chips)!SKX_EXT_B_BGA1-IC,TBD!!!F117!UPI2_RX_DP(9)!!!!
S!GND!U2D1!CR20!@baseboard_fab2_lib.baseboard_fab2(sch_1):page69_i1@chpset_lib.skx_ext_b(chips)!SKX_EXT_B_BGA1-IC,TBD!!!F117!UPI2_RX_DP(8)!!!!
S!GND!U2D1!CW18!@baseboard_fab2_lib.baseboard_fab2(sch_1):page69_i1@chpset_lib.skx_ext_b(chips)!SKX_EXT_B_BGA1-IC,TBD!!!F117!UPI2_RX_DP(7)!!!!
S!GND!U2D1!CU20!@baseboard_fab2_lib.baseboard_fab2(sch_1):page69_i1@chpset_lib.skx_ext_b(chips)!SKX_EXT_B_BGA1-IC,TBD!!!F117!UPI2_RX_DP(6)!!!!
S!GND!U2D1!CY19!@baseboard_fab2_lib.baseboard_fab2(sch_1):page69_i1@chpset_lib.skx_ext_b(chips)!SKX_EXT_B_BGA1-IC,TBD!!!F117!UPI2_RX_DP(5)!!!!
S!GND!U2D1!DB19!@baseboard_fab2_lib.baseboard_fab2(sch_1):page69_i1@chpset_lib.skx_ext_b(chips)!SKX_EXT_B_BGA1-IC,TBD!!!F117!UPI2_RX_DP(4)!!!!
S!GND!U2D1!DC20!@baseboard_fab2_lib.baseboard_fab2(sch_1):page69_i1@chpset_lib.skx_ext_b(chips)!SKX_EXT_B_BGA1-IC,TBD!!!F117!UPI2_RX_DP(3)!!!!
S!GND!U2D1!DA22!@baseboard_fab2_lib.baseboard_fab2(sch_1):page69_i1@chpset_lib.skx_ext_b(chips)!SKX_EXT_B_BGA1-IC,TBD!!!F117!UPI2_RX_DP(2)!!!!
S!GND!U2D1!DD21!@baseboard_fab2_lib.baseboard_fab2(sch_1):page69_i1@chpset_lib.skx_ext_b(chips)!SKX_EXT_B_BGA1-IC,TBD!!!F117!UPI2_RX_DP(1)!!!!
S!GND!U2D1!DG22!@baseboard_fab2_lib.baseboard_fab2(sch_1):page69_i1@chpset_lib.skx_ext_b(chips)!SKX_EXT_B_BGA1-IC,TBD!!!F117!UPI2_RX_DP(0)!!!!
S!GND!U2D1!BY15!@baseboard_fab2_lib.baseboard_fab2(sch_1):page69_i1@chpset_lib.skx_ext_b(chips)!SKX_EXT_B_BGA1-IC,TBD!!!F117!UPI2_RX_DP(18)!!!!
S!GND!U2D1!CD17!@baseboard_fab2_lib.baseboard_fab2(sch_1):page69_i1@chpset_lib.skx_ext_b(chips)!SKX_EXT_B_BGA1-IC,TBD!!!F117!UPI2_RX_DP(17)!!!!
S!GND!U2D1!CC14!@baseboard_fab2_lib.baseboard_fab2(sch_1):page69_i1@chpset_lib.skx_ext_b(chips)!SKX_EXT_B_BGA1-IC,TBD!!!F117!UPI2_RX_DP(16)!!!!
S!GND!U2D1!CF15!@baseboard_fab2_lib.baseboard_fab2(sch_1):page69_i1@chpset_lib.skx_ext_b(chips)!SKX_EXT_B_BGA1-IC,TBD!!!F117!UPI2_RX_DP(15)!!!!
S!GND!U2D1!CG16!@baseboard_fab2_lib.baseboard_fab2(sch_1):page69_i1@chpset_lib.skx_ext_b(chips)!SKX_EXT_B_BGA1-IC,TBD!!!F117!UPI2_RX_DP(14)!!!!
S!GND!U2D1!CK17!@baseboard_fab2_lib.baseboard_fab2(sch_1):page69_i1@chpset_lib.skx_ext_b(chips)!SKX_EXT_B_BGA1-IC,TBD!!!F117!UPI2_RX_DP(13)!!!!
S!GND!U2D1!CJ16!@baseboard_fab2_lib.baseboard_fab2(sch_1):page69_i1@chpset_lib.skx_ext_b(chips)!SKX_EXT_B_BGA1-IC,TBD!!!F117!UPI2_RX_DP(12)!!!!
S!GND!U2D1!CM21!@baseboard_fab2_lib.baseboard_fab2(sch_1):page69_i1@chpset_lib.skx_ext_b(chips)!SKX_EXT_B_BGA1-IC,TBD!!!F117!UPI2_RX_DP(11)!!!!
S!GND!U2D1!CP19!@baseboard_fab2_lib.baseboard_fab2(sch_1):page69_i1@chpset_lib.skx_ext_b(chips)!SKX_EXT_B_BGA1-IC,TBD!!!F117!UPI2_RX_DP(10)!!!!
S!TP_CPU1_UPI2_RSVD_DT21!U2D1!CC12!@baseboard_fab2_lib.baseboard_fab2(sch_1):page69_i1@chpset_lib.skx_ext_b(chips)!SKX_EXT_B_BGA1-IC,TBD!!!F117!UPI2_TX_DN(19)!!!!
S!TP_CPU1_UPI2_RSVD_DA16!U2D1!DC16!@baseboard_fab2_lib.baseboard_fab2(sch_1):page69_i1@chpset_lib.skx_ext_b(chips)!SKX_EXT_B_BGA1-IC,TBD!!!F117!UPI2_TX_DN(9)!!!!
S!TP_CPU1_UPI2_RSVD_CW14!U2D1!DF15!@baseboard_fab2_lib.baseboard_fab2(sch_1):page69_i1@chpset_lib.skx_ext_b(chips)!SKX_EXT_B_BGA1-IC,TBD!!!F117!UPI2_TX_DN(8)!!!!
S!TP_CPU1_UPI2_RSVD_CU14!U2D1!DD17!@baseboard_fab2_lib.baseboard_fab2(sch_1):page69_i1@chpset_lib.skx_ext_b(chips)!SKX_EXT_B_BGA1-IC,TBD!!!F117!UPI2_TX_DN(7)!!!!
S!TP_CPU1_UPI2_RSVD_CM13!U2D1!DG18!@baseboard_fab2_lib.baseboard_fab2(sch_1):page69_i1@chpset_lib.skx_ext_b(chips)!SKX_EXT_B_BGA1-IC,TBD!!!F117!UPI2_TX_DN(6)!!!!
S!TP_CPU1_UPI2_RSVD_CJ14!U2D1!DK17!@baseboard_fab2_lib.baseboard_fab2(sch_1):page69_i1@chpset_lib.skx_ext_b(chips)!SKX_EXT_B_BGA1-IC,TBD!!!F117!UPI2_TX_DN(5)!!!!
S!TP_CPU1_UPI2_RSVD_CF13!U2D1!DH19!@baseboard_fab2_lib.baseboard_fab2(sch_1):page69_i1@chpset_lib.skx_ext_b(chips)!SKX_EXT_B_BGA1-IC,TBD!!!F117!UPI2_TX_DN(4)!!!!
S!TP_CPU1_UPI2_RSVD_CH11!U2D1!DG20!@baseboard_fab2_lib.baseboard_fab2(sch_1):page69_i1@chpset_lib.skx_ext_b(chips)!SKX_EXT_B_BGA1-IC,TBD!!!F117!UPI2_TX_DN(3)!!!!
S!TP_CPU1_UPI2_RSVD_CE12!U2D1!DL20!@baseboard_fab2_lib.baseboard_fab2(sch_1):page69_i1@chpset_lib.skx_ext_b(chips)!SKX_EXT_B_BGA1-IC,TBD!!!F117!UPI2_TX_DN(2)!!!!
S!TP_CPU1_UPI2_RSVD_CC10!U2D1!DM21!@baseboard_fab2_lib.baseboard_fab2(sch_1):page69_i1@chpset_lib.skx_ext_b(chips)!SKX_EXT_B_BGA1-IC,TBD!!!F117!UPI2_TX_DN(1)!!!!
S!TP_CPU1_UPI2_RSVD_CC12!U2D1!DT21!@baseboard_fab2_lib.baseboard_fab2(sch_1):page69_i1@chpset_lib.skx_ext_b(chips)!SKX_EXT_B_BGA1-IC,TBD!!!F117!UPI2_TX_DN(0)!!!!
S!TP_CPU1_UPI2_RSVD_DM21!U2D1!CC10!@baseboard_fab2_lib.baseboard_fab2(sch_1):page69_i1@chpset_lib.skx_ext_b(chips)!SKX_EXT_B_BGA1-IC,TBD!!!F117!UPI2_TX_DN(18)!!!!
S!TP_CPU1_UPI2_RSVD_DL20!U2D1!CE12!@baseboard_fab2_lib.baseboard_fab2(sch_1):page69_i1@chpset_lib.skx_ext_b(chips)!SKX_EXT_B_BGA1-IC,TBD!!!F117!UPI2_TX_DN(17)!!!!
S!TP_CPU1_UPI2_RSVD_DG20!U2D1!CH11!@baseboard_fab2_lib.baseboard_fab2(sch_1):page69_i1@chpset_lib.skx_ext_b(chips)!SKX_EXT_B_BGA1-IC,TBD!!!F117!UPI2_TX_DN(16)!!!!
S!TP_CPU1_UPI2_RSVD_DH19!U2D1!CF13!@baseboard_fab2_lib.baseboard_fab2(sch_1):page69_i1@chpset_lib.skx_ext_b(chips)!SKX_EXT_B_BGA1-IC,TBD!!!F117!UPI2_TX_DN(15)!!!!
S!TP_CPU1_UPI2_RSVD_DK17!U2D1!CJ14!@baseboard_fab2_lib.baseboard_fab2(sch_1):page69_i1@chpset_lib.skx_ext_b(chips)!SKX_EXT_B_BGA1-IC,TBD!!!F117!UPI2_TX_DN(14)!!!!
S!TP_CPU1_UPI2_RSVD_DG18!U2D1!CM13!@baseboard_fab2_lib.baseboard_fab2(sch_1):page69_i1@chpset_lib.skx_ext_b(chips)!SKX_EXT_B_BGA1-IC,TBD!!!F117!UPI2_TX_DN(13)!!!!
S!TP_CPU1_UPI2_RSVD_DD17!U2D1!CU14!@baseboard_fab2_lib.baseboard_fab2(sch_1):page69_i1@chpset_lib.skx_ext_b(chips)!SKX_EXT_B_BGA1-IC,TBD!!!F117!UPI2_TX_DN(12)!!!!
S!TP_CPU1_UPI2_RSVD_DF15!U2D1!CW14!@baseboard_fab2_lib.baseboard_fab2(sch_1):page69_i1@chpset_lib.skx_ext_b(chips)!SKX_EXT_B_BGA1-IC,TBD!!!F117!UPI2_TX_DN(11)!!!!
S!TP_CPU1_UPI2_RSVD_DC16!U2D1!DA16!@baseboard_fab2_lib.baseboard_fab2(sch_1):page69_i1@chpset_lib.skx_ext_b(chips)!SKX_EXT_B_BGA1-IC,TBD!!!F117!UPI2_TX_DN(10)!!!!
S!TP_CPU1_UPI2_RSVD_DP21!U2D1!CA12!@baseboard_fab2_lib.baseboard_fab2(sch_1):page69_i1@chpset_lib.skx_ext_b(chips)!SKX_EXT_B_BGA1-IC,TBD!!!F117!UPI2_TX_DP(19)!!!!
S!TP_CPU1_UPI2_RSVD_CW16!U2D1!DB15!@baseboard_fab2_lib.baseboard_fab2(sch_1):page69_i1@chpset_lib.skx_ext_b(chips)!SKX_EXT_B_BGA1-IC,TBD!!!F117!UPI2_TX_DP(9)!!!!
S!TP_CPU1_UPI2_RSVD_CV13!U2D1!DD15!@baseboard_fab2_lib.baseboard_fab2(sch_1):page69_i1@chpset_lib.skx_ext_b(chips)!SKX_EXT_B_BGA1-IC,TBD!!!F117!UPI2_TX_DP(8)!!!!
S!TP_CPU1_UPI2_RSVD_CR14!U2D1!DE16!@baseboard_fab2_lib.baseboard_fab2(sch_1):page69_i1@chpset_lib.skx_ext_b(chips)!SKX_EXT_B_BGA1-IC,TBD!!!F117!UPI2_TX_DP(7)!!!!
S!TP_CPU1_UPI2_RSVD_CK13!U2D1!DF17!@baseboard_fab2_lib.baseboard_fab2(sch_1):page69_i1@chpset_lib.skx_ext_b(chips)!SKX_EXT_B_BGA1-IC,TBD!!!F117!UPI2_TX_DP(6)!!!!
S!TP_CPU1_UPI2_RSVD_CH13!U2D1!DH17!@baseboard_fab2_lib.baseboard_fab2(sch_1):page69_i1@chpset_lib.skx_ext_b(chips)!SKX_EXT_B_BGA1-IC,TBD!!!F117!UPI2_TX_DP(5)!!!!
S!TP_CPU1_UPI2_RSVD_CG12!U2D1!DJ18!@baseboard_fab2_lib.baseboard_fab2(sch_1):page69_i1@chpset_lib.skx_ext_b(chips)!SKX_EXT_B_BGA1-IC,TBD!!!F117!UPI2_TX_DP(4)!!!!
S!TP_CPU1_UPI2_RSVD_CF11!U2D1!DJ20!@baseboard_fab2_lib.baseboard_fab2(sch_1):page69_i1@chpset_lib.skx_ext_b(chips)!SKX_EXT_B_BGA1-IC,TBD!!!F117!UPI2_TX_DP(3)!!!!
S!TP_CPU1_UPI2_RSVD_CD11!U2D1!DK19!@baseboard_fab2_lib.baseboard_fab2(sch_1):page69_i1@chpset_lib.skx_ext_b(chips)!SKX_EXT_B_BGA1-IC,TBD!!!F117!UPI2_TX_DP(2)!!!!
S!TP_CPU1_UPI2_RSVD_CB11!U2D1!DN20!@baseboard_fab2_lib.baseboard_fab2(sch_1):page69_i1@chpset_lib.skx_ext_b(chips)!SKX_EXT_B_BGA1-IC,TBD!!!F117!UPI2_TX_DP(1)!!!!
S!TP_CPU1_UPI2_RSVD_CA12!U2D1!DP21!@baseboard_fab2_lib.baseboard_fab2(sch_1):page69_i1@chpset_lib.skx_ext_b(chips)!SKX_EXT_B_BGA1-IC,TBD!!!F117!UPI2_TX_DP(0)!!!!
S!TP_CPU1_UPI2_RSVD_DN20!U2D1!CB11!@baseboard_fab2_lib.baseboard_fab2(sch_1):page69_i1@chpset_lib.skx_ext_b(chips)!SKX_EXT_B_BGA1-IC,TBD!!!F117!UPI2_TX_DP(18)!!!!
S!TP_CPU1_UPI2_RSVD_DK19!U2D1!CD11!@baseboard_fab2_lib.baseboard_fab2(sch_1):page69_i1@chpset_lib.skx_ext_b(chips)!SKX_EXT_B_BGA1-IC,TBD!!!F117!UPI2_TX_DP(17)!!!!
S!TP_CPU1_UPI2_RSVD_DJ20!U2D1!CF11!@baseboard_fab2_lib.baseboard_fab2(sch_1):page69_i1@chpset_lib.skx_ext_b(chips)!SKX_EXT_B_BGA1-IC,TBD!!!F117!UPI2_TX_DP(16)!!!!
S!TP_CPU1_UPI2_RSVD_DJ18!U2D1!CG12!@baseboard_fab2_lib.baseboard_fab2(sch_1):page69_i1@chpset_lib.skx_ext_b(chips)!SKX_EXT_B_BGA1-IC,TBD!!!F117!UPI2_TX_DP(15)!!!!
S!TP_CPU1_UPI2_RSVD_DH17!U2D1!CH13!@baseboard_fab2_lib.baseboard_fab2(sch_1):page69_i1@chpset_lib.skx_ext_b(chips)!SKX_EXT_B_BGA1-IC,TBD!!!F117!UPI2_TX_DP(14)!!!!
S!TP_CPU1_UPI2_RSVD_DF17!U2D1!CK13!@baseboard_fab2_lib.baseboard_fab2(sch_1):page69_i1@chpset_lib.skx_ext_b(chips)!SKX_EXT_B_BGA1-IC,TBD!!!F117!UPI2_TX_DP(13)!!!!
S!TP_CPU1_UPI2_RSVD_DE16!U2D1!CR14!@baseboard_fab2_lib.baseboard_fab2(sch_1):page69_i1@chpset_lib.skx_ext_b(chips)!SKX_EXT_B_BGA1-IC,TBD!!!F117!UPI2_TX_DP(12)!!!!
S!TP_CPU1_UPI2_RSVD_DD15!U2D1!CV13!@baseboard_fab2_lib.baseboard_fab2(sch_1):page69_i1@chpset_lib.skx_ext_b(chips)!SKX_EXT_B_BGA1-IC,TBD!!!F117!UPI2_TX_DP(11)!!!!
S!TP_CPU1_UPI2_RSVD_DB15!U2D1!CW16!@baseboard_fab2_lib.baseboard_fab2(sch_1):page69_i1@chpset_lib.skx_ext_b(chips)!SKX_EXT_B_BGA1-IC,TBD!!!F117!UPI2_TX_DP(10)!!!!
S!TP_CPU1_RSVD_2!U2D1!EF77!@baseboard_fab2_lib.baseboard_fab2(sch_1):page73_i107@chpset_lib.skx_ext_b(chips)!SKX_EXT_B_BGA1-IC,TBD!!!F110!RSVD(2)!!!!
S!TP_CPU1_RSVD_267!U2D1!K61!@baseboard_fab2_lib.baseboard_fab2(sch_1):page56_i169@chpset_lib.skx_ext_b(chips)!SKX_EXT_B_BGA1-IC,TBD!!!F130!RSVD(267)!!!!
S!TP_CPU1_RSVD_268!U2D1!J62!@baseboard_fab2_lib.baseboard_fab2(sch_1):page56_i169@chpset_lib.skx_ext_b(chips)!SKX_EXT_B_BGA1-IC,TBD!!!F130!RSVD(268)!!!!
S!TP_CPU1_RSVD_269!U2D1!J46!@baseboard_fab2_lib.baseboard_fab2(sch_1):page56_i169@chpset_lib.skx_ext_b(chips)!SKX_EXT_B_BGA1-IC,TBD!!!F130!RSVD(269)!!!!
S!TP_CPU1_RSVD_271!U2D1!H83!@baseboard_fab2_lib.baseboard_fab2(sch_1):page56_i169@chpset_lib.skx_ext_b(chips)!SKX_EXT_B_BGA1-IC,TBD!!!F130!RSVD(271)!!!!
S!TP_CPU1_RSVD_274!U2D1!G64!@baseboard_fab2_lib.baseboard_fab2(sch_1):page56_i169@chpset_lib.skx_ext_b(chips)!SKX_EXT_B_BGA1-IC,TBD!!!F130!RSVD(274)!!!!
S!TP_CPU1_RSVD_277!U2D1!F65!@baseboard_fab2_lib.baseboard_fab2(sch_1):page56_i169@chpset_lib.skx_ext_b(chips)!SKX_EXT_B_BGA1-IC,TBD!!!F130!RSVD(277)!!!!
S!GND!U2D1!E66!@baseboard_fab2_lib.baseboard_fab2(sch_1):page74_i20@chpset_lib.skx_ext_b(chips)!SKX_EXT_B_BGA1-IC,TBD!!!F109!VSS(1228)!!!!
S!TP_CPU1_RSVD_285!U2D1!D65!@baseboard_fab2_lib.baseboard_fab2(sch_1):page56_i169@chpset_lib.skx_ext_b(chips)!SKX_EXT_B_BGA1-IC,TBD!!!F130!RSVD(285)!!!!
S!TP_CPU1_RSVD_293!U2D1!B77!@baseboard_fab2_lib.baseboard_fab2(sch_1):page56_i169@chpset_lib.skx_ext_b(chips)!SKX_EXT_B_BGA1-IC,TBD!!!F130!RSVD(293)!!!!
S!GND!U2D1!B9!@baseboard_fab2_lib.baseboard_fab2(sch_1):page74_i20@chpset_lib.skx_ext_b(chips)!SKX_EXT_B_BGA1-IC,TBD!!!F109!VSS(1253)!!!!
S!TP_CPU1_RSVD_26!U2D1!DU44!@baseboard_fab2_lib.baseboard_fab2(sch_1):page73_i107@chpset_lib.skx_ext_b(chips)!SKX_EXT_B_BGA1-IC,TBD!!!F110!RSVD(26)!!!!
S!TP_CPU1_RSVD_28!U2D1!DR44!@baseboard_fab2_lib.baseboard_fab2(sch_1):page73_i107@chpset_lib.skx_ext_b(chips)!SKX_EXT_B_BGA1-IC,TBD!!!F110!RSVD(28)!!!!
S!TP_CPU1_RSVD_29!U2D1!DP65!@baseboard_fab2_lib.baseboard_fab2(sch_1):page73_i107@chpset_lib.skx_ext_b(chips)!SKX_EXT_B_BGA1-IC,TBD!!!F110!RSVD(29)!!!!
S!TP_CPU1_RSVD_32!U2D1!DN62!@baseboard_fab2_lib.baseboard_fab2(sch_1):page73_i107@chpset_lib.skx_ext_b(chips)!SKX_EXT_B_BGA1-IC,TBD!!!F110!RSVD(32)!!!!
S!TP_CPU1_RSVD_34!U2D1!DL66!@baseboard_fab2_lib.baseboard_fab2(sch_1):page73_i107@chpset_lib.skx_ext_b(chips)!SKX_EXT_B_BGA1-IC,TBD!!!F110!RSVD(34)!!!!
S!TP_CPU1_RSVD_36!U2D1!DK67!@baseboard_fab2_lib.baseboard_fab2(sch_1):page73_i107@chpset_lib.skx_ext_b(chips)!SKX_EXT_B_BGA1-IC,TBD!!!F110!RSVD(36)!!!!
S!TP_CPU1_RSVD_37!U2D1!DK65!@baseboard_fab2_lib.baseboard_fab2(sch_1):page73_i107@chpset_lib.skx_ext_b(chips)!SKX_EXT_B_BGA1-IC,TBD!!!F110!RSVD(37)!!!!
S!TP_CPU1_RSVD_40!U2D1!DJ66!@baseboard_fab2_lib.baseboard_fab2(sch_1):page73_i107@chpset_lib.skx_ext_b(chips)!SKX_EXT_B_BGA1-IC,TBD!!!F110!RSVD(40)!!!!
S!TP_CPU1_RSVD_42!U2D1!DH65!@baseboard_fab2_lib.baseboard_fab2(sch_1):page73_i107@chpset_lib.skx_ext_b(chips)!SKX_EXT_B_BGA1-IC,TBD!!!F110!RSVD(42)!!!!
S!TP_CPU1_RSVD_43!U2D1!DG64!@baseboard_fab2_lib.baseboard_fab2(sch_1):page73_i107@chpset_lib.skx_ext_b(chips)!SKX_EXT_B_BGA1-IC,TBD!!!F110!RSVD(43)!!!!
S!TP_CPU1_RSVD_3!U2D1!EF47!@baseboard_fab2_lib.baseboard_fab2(sch_1):page73_i107@chpset_lib.skx_ext_b(chips)!SKX_EXT_B_BGA1-IC,TBD!!!F110!RSVD(3)!!!!
S!TP_CPU1_RSVD_45!U2D1!DD51!@baseboard_fab2_lib.baseboard_fab2(sch_1):page73_i107@chpset_lib.skx_ext_b(chips)!SKX_EXT_B_BGA1-IC,TBD!!!F110!RSVD(45)!!!!
S!TP_CPU1_RSVD_46!U2D1!DC52!@baseboard_fab2_lib.baseboard_fab2(sch_1):page73_i107@chpset_lib.skx_ext_b(chips)!SKX_EXT_B_BGA1-IC,TBD!!!F110!RSVD(46)!!!!
S!TP_CPU1_RSVD_47!U2D1!DC46!@baseboard_fab2_lib.baseboard_fab2(sch_1):page73_i107@chpset_lib.skx_ext_b(chips)!SKX_EXT_B_BGA1-IC,TBD!!!F110!RSVD(47)!!!!
S!TP_CPU1_RSVD_48!U2D1!DA56!@baseboard_fab2_lib.baseboard_fab2(sch_1):page73_i107@chpset_lib.skx_ext_b(chips)!SKX_EXT_B_BGA1-IC,TBD!!!F110!RSVD(48)!!!!
S!TP_CPU1_RSVD_49!U2D1!DA54!@baseboard_fab2_lib.baseboard_fab2(sch_1):page73_i107@chpset_lib.skx_ext_b(chips)!SKX_EXT_B_BGA1-IC,TBD!!!F110!RSVD(49)!!!!
S!TP_CPU1_RSVD_53!U2D1!CY73!@baseboard_fab2_lib.baseboard_fab2(sch_1):page73_i107@chpset_lib.skx_ext_b(chips)!SKX_EXT_B_BGA1-IC,TBD!!!F110!RSVD(53)!!!!
S!TP_CPU1_RSVD_54!U2D1!CY63!@baseboard_fab2_lib.baseboard_fab2(sch_1):page73_i107@chpset_lib.skx_ext_b(chips)!SKX_EXT_B_BGA1-IC,TBD!!!F110!RSVD(54)!!!!
S!TP_CPU1_RSVD_55!U2D1!CY57!@baseboard_fab2_lib.baseboard_fab2(sch_1):page73_i107@chpset_lib.skx_ext_b(chips)!SKX_EXT_B_BGA1-IC,TBD!!!F110!RSVD(55)!!!!
S!TP_CPU1_RSVD_60!U2D1!CW62!@baseboard_fab2_lib.baseboard_fab2(sch_1):page73_i107@chpset_lib.skx_ext_b(chips)!SKX_EXT_B_BGA1-IC,TBD!!!F110!RSVD(60)!!!!
S!TP_CPU1_RSVD_61!U2D1!CW60!@baseboard_fab2_lib.baseboard_fab2(sch_1):page73_i107@chpset_lib.skx_ext_b(chips)!SKX_EXT_B_BGA1-IC,TBD!!!F110!RSVD(61)!!!!
S!TP_CPU1_RSVD_7!U2D1!EE46!@baseboard_fab2_lib.baseboard_fab2(sch_1):page73_i107@chpset_lib.skx_ext_b(chips)!SKX_EXT_B_BGA1-IC,TBD!!!F110!RSVD(7)!!!!
S!TP_CPU1_RSVD_64!U2D1!CV69!@baseboard_fab2_lib.baseboard_fab2(sch_1):page73_i107@chpset_lib.skx_ext_b(chips)!SKX_EXT_B_BGA1-IC,TBD!!!F110!RSVD(64)!!!!
S!TP_CPU1_RSVD_66!U2D1!CU60!@baseboard_fab2_lib.baseboard_fab2(sch_1):page73_i107@chpset_lib.skx_ext_b(chips)!SKX_EXT_B_BGA1-IC,TBD!!!F110!RSVD(66)!!!!
S!TP_CPU1_RSVD_69!U2D1!CT69!@baseboard_fab2_lib.baseboard_fab2(sch_1):page73_i107@chpset_lib.skx_ext_b(chips)!SKX_EXT_B_BGA1-IC,TBD!!!F110!RSVD(69)!!!!
S!TP_CPU1_RSVD_72!U2D1!CR60!@baseboard_fab2_lib.baseboard_fab2(sch_1):page73_i107@chpset_lib.skx_ext_b(chips)!SKX_EXT_B_BGA1-IC,TBD!!!F110!RSVD(72)!!!!
S!TP_CPU1_RSVD_73!U2D1!CP31!@baseboard_fab2_lib.baseboard_fab2(sch_1):page73_i107@chpset_lib.skx_ext_b(chips)!SKX_EXT_B_BGA1-IC,TBD!!!F110!RSVD(73)!!!!
S!TP_CPU1_RSVD_82!U2D1!CK77!@baseboard_fab2_lib.baseboard_fab2(sch_1):page70_i10@chpset_lib.skx_ext_b(chips)!SKX_EXT_B_BGA1-IC,TBD!!!F115!RSVD(82)!!!!
S!TP_CPU1_RSVD_90!U2D1!CH77!@baseboard_fab2_lib.baseboard_fab2(sch_1):page70_i10@chpset_lib.skx_ext_b(chips)!SKX_EXT_B_BGA1-IC,TBD!!!F115!RSVD(90)!!!!
S!TP_CPU1_RSVD_94!U2D1!CG82!@baseboard_fab2_lib.baseboard_fab2(sch_1):page70_i9@chpset_lib.skx_ext_b(chips)!SKX_EXT_B_BGA1-IC,TBD!!!F116!RSVD(94)!!!!
S!TP_CPU1_RSVD_95!U2D1!CG78!@baseboard_fab2_lib.baseboard_fab2(sch_1):page70_i9@chpset_lib.skx_ext_b(chips)!SKX_EXT_B_BGA1-IC,TBD!!!F116!RSVD(95)!!!!
S!TP_CPU1_RSVD_100!U2D1!CF81!@baseboard_fab2_lib.baseboard_fab2(sch_1):page70_i9@chpset_lib.skx_ext_b(chips)!SKX_EXT_B_BGA1-IC,TBD!!!F116!RSVD(100)!!!!
S!GND!U2D1!ED69!@baseboard_fab2_lib.baseboard_fab2(sch_1):page74_i20@chpset_lib.skx_ext_b(chips)!SKX_EXT_B_BGA1-IC,TBD!!!F109!VSS(1229)!!!!
S!TP_CPU1_RSVD_101!U2D1!CF79!@baseboard_fab2_lib.baseboard_fab2(sch_1):page70_i9@chpset_lib.skx_ext_b(chips)!SKX_EXT_B_BGA1-IC,TBD!!!F116!RSVD(101)!!!!
S!TP_CPU1_RSVD_105!U2D1!CE80!@baseboard_fab2_lib.baseboard_fab2(sch_1):page70_i9@chpset_lib.skx_ext_b(chips)!SKX_EXT_B_BGA1-IC,TBD!!!F116!RSVD(105)!!!!
S!TP_CPU1_RSVD_106!U2D1!CE78!@baseboard_fab2_lib.baseboard_fab2(sch_1):page70_i9@chpset_lib.skx_ext_b(chips)!SKX_EXT_B_BGA1-IC,TBD!!!F116!RSVD(106)!!!!
S!TP_CPU1_RSVD_150!U2D1!BD69!@baseboard_fab2_lib.baseboard_fab2(sch_1):page70_i9@chpset_lib.skx_ext_b(chips)!SKX_EXT_B_BGA1-IC,TBD!!!F116!RSVD(150)!!!!
S!TP_CPU1_RSVD_151!U2D1!BD67!@baseboard_fab2_lib.baseboard_fab2(sch_1):page70_i9@chpset_lib.skx_ext_b(chips)!SKX_EXT_B_BGA1-IC,TBD!!!F116!RSVD(151)!!!!
S!TP_CPU1_RSVD_152!U2D1!BD65!@baseboard_fab2_lib.baseboard_fab2(sch_1):page70_i9@chpset_lib.skx_ext_b(chips)!SKX_EXT_B_BGA1-IC,TBD!!!F116!RSVD(152)!!!!
S!CLK_100M_CPU1_RC_REFCLK1_DP!U2D1!BD25!@baseboard_fab2_lib.baseboard_fab2(sch_1):page70_i9@chpset_lib.skx_ext_b(chips)!SKX_EXT_B_BGA1-IC,TBD!!!F116!RSVD(153)!!!!
S!TP_CPU1_RSVD_156!U2D1!BC68!@baseboard_fab2_lib.baseboard_fab2(sch_1):page70_i9@chpset_lib.skx_ext_b(chips)!SKX_EXT_B_BGA1-IC,TBD!!!F116!RSVD(156)!!!!
S!TP_CPU1_RSVD_157!U2D1!BC66!@baseboard_fab2_lib.baseboard_fab2(sch_1):page70_i9@chpset_lib.skx_ext_b(chips)!SKX_EXT_B_BGA1-IC,TBD!!!F116!RSVD(157)!!!!
S!TP_CPU1_RSVD_158!U2D1!BC64!@baseboard_fab2_lib.baseboard_fab2(sch_1):page70_i9@chpset_lib.skx_ext_b(chips)!SKX_EXT_B_BGA1-IC,TBD!!!F116!RSVD(158)!!!!
S!TP_CPU1_RSVD_11!U2D1!ED45!@baseboard_fab2_lib.baseboard_fab2(sch_1):page73_i107@chpset_lib.skx_ext_b(chips)!SKX_EXT_B_BGA1-IC,TBD!!!F110!RSVD(11)!!!!
S!TP_CPU1_RSVD_163!U2D1!BB67!@baseboard_fab2_lib.baseboard_fab2(sch_1):page70_i9@chpset_lib.skx_ext_b(chips)!SKX_EXT_B_BGA1-IC,TBD!!!F116!RSVD(163)!!!!
S!TP_CPU1_RSVD_164!U2D1!BB65!@baseboard_fab2_lib.baseboard_fab2(sch_1):page70_i9@chpset_lib.skx_ext_b(chips)!SKX_EXT_B_BGA1-IC,TBD!!!F116!RSVD(164)!!!!
S!CLK_100M_CPU1_RC_REFCLK1_DN!U2D1!BB25!@baseboard_fab2_lib.baseboard_fab2(sch_1):page70_i9@chpset_lib.skx_ext_b(chips)!SKX_EXT_B_BGA1-IC,TBD!!!F116!RSVD(165)!!!!
S!TP_CPU1_RSVD_170!U2D1!BA82!@baseboard_fab2_lib.baseboard_fab2(sch_1):page70_i9@chpset_lib.skx_ext_b(chips)!SKX_EXT_B_BGA1-IC,TBD!!!F116!RSVD(170)!!!!
S!TP_CPU1_RSVD_171!U2D1!BA78!@baseboard_fab2_lib.baseboard_fab2(sch_1):page70_i9@chpset_lib.skx_ext_b(chips)!SKX_EXT_B_BGA1-IC,TBD!!!F116!RSVD(171)!!!!
S!TP_CPU1_RSVD_172!U2D1!BA76!@baseboard_fab2_lib.baseboard_fab2(sch_1):page63_i23@chpset_lib.skx_ext_b(chips)!SKX_EXT_B_BGA1-IC,TBD!!!F123!RSVD(172)!!!!
S!TP_CPU1_RSVD_173!U2D1!BA66!@baseboard_fab2_lib.baseboard_fab2(sch_1):page63_i23@chpset_lib.skx_ext_b(chips)!SKX_EXT_B_BGA1-IC,TBD!!!F123!RSVD(173)!!!!
S!TP_CPU1_RSVD_174!U2D1!BA64!@baseboard_fab2_lib.baseboard_fab2(sch_1):page63_i23@chpset_lib.skx_ext_b(chips)!SKX_EXT_B_BGA1-IC,TBD!!!F123!RSVD(174)!!!!
S!TP_CPU1_RSVD_179!U2D1!AY77!@baseboard_fab2_lib.baseboard_fab2(sch_1):page63_i23@chpset_lib.skx_ext_b(chips)!SKX_EXT_B_BGA1-IC,TBD!!!F123!RSVD(179)!!!!
S!TP_CPU1_RSVD_180!U2D1!AY75!@baseboard_fab2_lib.baseboard_fab2(sch_1):page63_i23@chpset_lib.skx_ext_b(chips)!SKX_EXT_B_BGA1-IC,TBD!!!F123!RSVD(180)!!!!
S!TP_CPU1_RSVD_13!U2D1!EC44!@baseboard_fab2_lib.baseboard_fab2(sch_1):page73_i107@chpset_lib.skx_ext_b(chips)!SKX_EXT_B_BGA1-IC,TBD!!!F110!RSVD(13)!!!!
S!TP_CPU1_RSVD_181!U2D1!AY67!@baseboard_fab2_lib.baseboard_fab2(sch_1):page63_i23@chpset_lib.skx_ext_b(chips)!SKX_EXT_B_BGA1-IC,TBD!!!F123!RSVD(181)!!!!
S!TP_CPU1_RSVD_182!U2D1!AY65!@baseboard_fab2_lib.baseboard_fab2(sch_1):page63_i23@chpset_lib.skx_ext_b(chips)!SKX_EXT_B_BGA1-IC,TBD!!!F123!RSVD(182)!!!!
S!TP_CPU1_RSVD_183!U2D1!AW76!@baseboard_fab2_lib.baseboard_fab2(sch_1):page63_i23@chpset_lib.skx_ext_b(chips)!SKX_EXT_B_BGA1-IC,TBD!!!F123!RSVD(183)!!!!
S!TP_CPU1_RSVD_184!U2D1!AW64!@baseboard_fab2_lib.baseboard_fab2(sch_1):page63_i23@chpset_lib.skx_ext_b(chips)!SKX_EXT_B_BGA1-IC,TBD!!!F123!RSVD(184)!!!!
S!TP_CPU1_RSVD_186!U2D1!AV77!@baseboard_fab2_lib.baseboard_fab2(sch_1):page63_i23@chpset_lib.skx_ext_b(chips)!SKX_EXT_B_BGA1-IC,TBD!!!F123!RSVD(186)!!!!
S!TP_CPU1_RSVD_190!U2D1!AR62!@baseboard_fab2_lib.baseboard_fab2(sch_1):page63_i23@chpset_lib.skx_ext_b(chips)!SKX_EXT_B_BGA1-IC,TBD!!!F123!RSVD(190)!!!!
S!TP_CPU1_RSVD_194!U2D1!AP61!@baseboard_fab2_lib.baseboard_fab2(sch_1):page56_i169@chpset_lib.skx_ext_b(chips)!SKX_EXT_B_BGA1-IC,TBD!!!F130!RSVD(194)!!!!
S!TP_CPU1_RSVD_198!U2D1!AN62!@baseboard_fab2_lib.baseboard_fab2(sch_1):page56_i169@chpset_lib.skx_ext_b(chips)!SKX_EXT_B_BGA1-IC,TBD!!!F130!RSVD(198)!!!!
S!TP_CPU1_RSVD_199!U2D1!AN60!@baseboard_fab2_lib.baseboard_fab2(sch_1):page56_i169@chpset_lib.skx_ext_b(chips)!SKX_EXT_B_BGA1-IC,TBD!!!F130!RSVD(199)!!!!
S!TP_CPU1_RSVD_204!U2D1!AM61!@baseboard_fab2_lib.baseboard_fab2(sch_1):page56_i169@chpset_lib.skx_ext_b(chips)!SKX_EXT_B_BGA1-IC,TBD!!!F130!RSVD(204)!!!!
S!TP_CPU1_RSVD_19!U2D1!EA44!@baseboard_fab2_lib.baseboard_fab2(sch_1):page73_i107@chpset_lib.skx_ext_b(chips)!SKX_EXT_B_BGA1-IC,TBD!!!F110!RSVD(19)!!!!
S!TP_CPU1_RSVD_205!U2D1!AM59!@baseboard_fab2_lib.baseboard_fab2(sch_1):page56_i169@chpset_lib.skx_ext_b(chips)!SKX_EXT_B_BGA1-IC,TBD!!!F130!RSVD(205)!!!!
S!TP_CPU1_RSVD_210!U2D1!AL62!@baseboard_fab2_lib.baseboard_fab2(sch_1):page56_i169@chpset_lib.skx_ext_b(chips)!SKX_EXT_B_BGA1-IC,TBD!!!F130!RSVD(210)!!!!
S!TP_CPU1_RSVD_211!U2D1!AL60!@baseboard_fab2_lib.baseboard_fab2(sch_1):page56_i169@chpset_lib.skx_ext_b(chips)!SKX_EXT_B_BGA1-IC,TBD!!!F130!RSVD(211)!!!!
S!TP_CPU1_RSVD_212!U2D1!AL58!@baseboard_fab2_lib.baseboard_fab2(sch_1):page56_i169@chpset_lib.skx_ext_b(chips)!SKX_EXT_B_BGA1-IC,TBD!!!F130!RSVD(212)!!!!
S!TP_CPU1_RSVD_216!U2D1!AK69!@baseboard_fab2_lib.baseboard_fab2(sch_1):page56_i169@chpset_lib.skx_ext_b(chips)!SKX_EXT_B_BGA1-IC,TBD!!!F130!RSVD(216)!!!!
S!TP_CPU1_RSVD_217!U2D1!AK61!@baseboard_fab2_lib.baseboard_fab2(sch_1):page56_i169@chpset_lib.skx_ext_b(chips)!SKX_EXT_B_BGA1-IC,TBD!!!F130!RSVD(217)!!!!
S!TP_CPU1_RSVD_218!U2D1!AK59!@baseboard_fab2_lib.baseboard_fab2(sch_1):page56_i169@chpset_lib.skx_ext_b(chips)!SKX_EXT_B_BGA1-IC,TBD!!!F130!RSVD(218)!!!!
S!TP_CPU1_RSVD_222!U2D1!AJ70!@baseboard_fab2_lib.baseboard_fab2(sch_1):page56_i169@chpset_lib.skx_ext_b(chips)!SKX_EXT_B_BGA1-IC,TBD!!!F130!RSVD(222)!!!!
S!TP_CPU1_RSVD_223!U2D1!AJ62!@baseboard_fab2_lib.baseboard_fab2(sch_1):page56_i169@chpset_lib.skx_ext_b(chips)!SKX_EXT_B_BGA1-IC,TBD!!!F130!RSVD(223)!!!!
S!TP_CPU1_RSVD_224!U2D1!AJ60!@baseboard_fab2_lib.baseboard_fab2(sch_1):page56_i169@chpset_lib.skx_ext_b(chips)!SKX_EXT_B_BGA1-IC,TBD!!!F130!RSVD(224)!!!!
S!TP_CPU1_RSVD_22!U2D1!DW46!@baseboard_fab2_lib.baseboard_fab2(sch_1):page73_i107@chpset_lib.skx_ext_b(chips)!SKX_EXT_B_BGA1-IC,TBD!!!F110!RSVD(22)!!!!
S!TP_CPU1_RSVD_225!U2D1!AJ58!@baseboard_fab2_lib.baseboard_fab2(sch_1):page56_i169@chpset_lib.skx_ext_b(chips)!SKX_EXT_B_BGA1-IC,TBD!!!F130!RSVD(225)!!!!
S!TP_CPU1_RSVD_228!U2D1!AH73!@baseboard_fab2_lib.baseboard_fab2(sch_1):page56_i169@chpset_lib.skx_ext_b(chips)!SKX_EXT_B_BGA1-IC,TBD!!!F130!RSVD(228)!!!!
S!TP_CPU1_RSVD_229!U2D1!AH71!@baseboard_fab2_lib.baseboard_fab2(sch_1):page56_i169@chpset_lib.skx_ext_b(chips)!SKX_EXT_B_BGA1-IC,TBD!!!F130!RSVD(229)!!!!
S!TP_CPU1_RSVD_230!U2D1!AH57!@baseboard_fab2_lib.baseboard_fab2(sch_1):page56_i169@chpset_lib.skx_ext_b(chips)!SKX_EXT_B_BGA1-IC,TBD!!!F130!RSVD(230)!!!!
S!TP_CPU1_RSVD_234!U2D1!AG72!@baseboard_fab2_lib.baseboard_fab2(sch_1):page56_i169@chpset_lib.skx_ext_b(chips)!SKX_EXT_B_BGA1-IC,TBD!!!F130!RSVD(234)!!!!
S!TP_CPU1_RSVD_241!U2D1!AF71!@baseboard_fab2_lib.baseboard_fab2(sch_1):page56_i169@chpset_lib.skx_ext_b(chips)!SKX_EXT_B_BGA1-IC,TBD!!!F130!RSVD(241)!!!!
S!TP_CPU1_RSVD_247!U2D1!AE72!@baseboard_fab2_lib.baseboard_fab2(sch_1):page56_i169@chpset_lib.skx_ext_b(chips)!SKX_EXT_B_BGA1-IC,TBD!!!F130!RSVD(247)!!!!
S!TP_CPU1_RSVD_251!U2D1!AE46!@baseboard_fab2_lib.baseboard_fab2(sch_1):page56_i169@chpset_lib.skx_ext_b(chips)!SKX_EXT_B_BGA1-IC,TBD!!!F130!RSVD(251)!!!!
S!VSENSE_PMAX_CPU1!U2D1!AD41!@baseboard_fab2_lib.baseboard_fab2(sch_1):page71_i51@chpset_lib.skx_ext_b(chips)!SKX_EXT_B_BGA1-IC,TBD!!!F113!VSENSEPMAX!!!!
S!TP_CPU1_RSVD_256!U2D1!Y65!@baseboard_fab2_lib.baseboard_fab2(sch_1):page56_i169@chpset_lib.skx_ext_b(chips)!SKX_EXT_B_BGA1-IC,TBD!!!F130!RSVD(256)!!!!
S!TP_CPU1_RSVD_23!U2D1!DW44!@baseboard_fab2_lib.baseboard_fab2(sch_1):page73_i107@chpset_lib.skx_ext_b(chips)!SKX_EXT_B_BGA1-IC,TBD!!!F110!RSVD(23)!!!!
S!FM_CPU1_RC_ERROR_N!U2D1!Y23!@baseboard_fab2_lib.baseboard_fab2(sch_1):page56_i169@chpset_lib.skx_ext_b(chips)!SKX_EXT_B_BGA1-IC,TBD!!!F130!RSVD(257)!!!!
S!TP_CPU1_RSVD_258!U2D1!W66!@baseboard_fab2_lib.baseboard_fab2(sch_1):page56_i169@chpset_lib.skx_ext_b(chips)!SKX_EXT_B_BGA1-IC,TBD!!!F130!RSVD(258)!!!!
S!TP_CPU1_RSVD_259!U2D1!V67!@baseboard_fab2_lib.baseboard_fab2(sch_1):page56_i169@chpset_lib.skx_ext_b(chips)!SKX_EXT_B_BGA1-IC,TBD!!!F130!RSVD(259)!!!!
S!TP_CPU1_RSVD_260!U2D1!V65!@baseboard_fab2_lib.baseboard_fab2(sch_1):page56_i169@chpset_lib.skx_ext_b(chips)!SKX_EXT_B_BGA1-IC,TBD!!!F130!RSVD(260)!!!!
S!TP_CPU1_RSVD_261!U2D1!U66!@baseboard_fab2_lib.baseboard_fab2(sch_1):page56_i169@chpset_lib.skx_ext_b(chips)!SKX_EXT_B_BGA1-IC,TBD!!!F130!RSVD(261)!!!!
S!TP_CPU1_RSVD_262!U2D1!T67!@baseboard_fab2_lib.baseboard_fab2(sch_1):page56_i169@chpset_lib.skx_ext_b(chips)!SKX_EXT_B_BGA1-IC,TBD!!!F130!RSVD(262)!!!!
S!TP_CPU1_RSVD_263!U2D1!R66!@baseboard_fab2_lib.baseboard_fab2(sch_1):page56_i169@chpset_lib.skx_ext_b(chips)!SKX_EXT_B_BGA1-IC,TBD!!!F130!RSVD(263)!!!!
S!TP_CPU1_RSVD_264!U2D1!R62!@baseboard_fab2_lib.baseboard_fab2(sch_1):page56_i169@chpset_lib.skx_ext_b(chips)!SKX_EXT_B_BGA1-IC,TBD!!!F130!RSVD(264)!!!!
S!TP_CPU1_RSVD_265!U2D1!P65!@baseboard_fab2_lib.baseboard_fab2(sch_1):page56_i169@chpset_lib.skx_ext_b(chips)!SKX_EXT_B_BGA1-IC,TBD!!!F130!RSVD(265)!!!!
S!TP_CPU1_RSVD_266!U2D1!M63!@baseboard_fab2_lib.baseboard_fab2(sch_1):page56_i169@chpset_lib.skx_ext_b(chips)!SKX_EXT_B_BGA1-IC,TBD!!!F130!RSVD(266)!!!!
S!TP_CPU1_RSVD_25!U2D1!DV61!@baseboard_fab2_lib.baseboard_fab2(sch_1):page73_i107@chpset_lib.skx_ext_b(chips)!SKX_EXT_B_BGA1-IC,TBD!!!F110!RSVD(25)!!!!
S!TP_CPU1_RSVD_227!U2D1!AJ20!@baseboard_fab2_lib.baseboard_fab2(sch_1):page56_i169@chpset_lib.skx_ext_b(chips)!SKX_EXT_B_BGA1-IC,TBD!!!F130!RSVD(227)!!!!
S!TP_CPU1_RSVD_240!U2D1!AG20!@baseboard_fab2_lib.baseboard_fab2(sch_1):page56_i169@chpset_lib.skx_ext_b(chips)!SKX_EXT_B_BGA1-IC,TBD!!!F130!RSVD(240)!!!!
S!TP_CPU1_TEST_7!U2D1!AU18!@baseboard_fab2_lib.baseboard_fab2(sch_1):page70_i10@chpset_lib.skx_ext_b(chips)!SKX_EXT_B_BGA1-IC,TBD!!!F115!TEST_7!!!!
S!TP_CPU1_TEST_8!U2D1!AW16!@baseboard_fab2_lib.baseboard_fab2(sch_1):page70_i10@chpset_lib.skx_ext_b(chips)!SKX_EXT_B_BGA1-IC,TBD!!!F115!TEST_8!!!!
S!TP_CPU1_TEST_10!U2D1!AW22!@baseboard_fab2_lib.baseboard_fab2(sch_1):page70_i10@chpset_lib.skx_ext_b(chips)!SKX_EXT_B_BGA1-IC,TBD!!!F115!TEST_10!!!!
S!TP_CPU1_TEST_9!U2D1!AW20!@baseboard_fab2_lib.baseboard_fab2(sch_1):page70_i10@chpset_lib.skx_ext_b(chips)!SKX_EXT_B_BGA1-IC,TBD!!!F115!TEST_9!!!!
S!TP_CPU1_RSVD_TEST_11!U2D1!AY13!@baseboard_fab2_lib.baseboard_fab2(sch_1):page56_i169@chpset_lib.skx_ext_b(chips)!SKX_EXT_B_BGA1-IC,TBD!!!F130!TEST_11!!!!
S!TP_CPU1_RSVD_280!U2D1!E84!@baseboard_fab2_lib.baseboard_fab2(sch_1):page56_i169@chpset_lib.skx_ext_b(chips)!SKX_EXT_B_BGA1-IC,TBD!!!F130!RSVD(280)!!!!
S!TP_CPU1_RSVD_284!U2D1!D83!@baseboard_fab2_lib.baseboard_fab2(sch_1):page56_i169@chpset_lib.skx_ext_b(chips)!SKX_EXT_B_BGA1-IC,TBD!!!F130!RSVD(284)!!!!
S!TP_CPU1_RSVD_288!U2D1!C82!@baseboard_fab2_lib.baseboard_fab2(sch_1):page56_i169@chpset_lib.skx_ext_b(chips)!SKX_EXT_B_BGA1-IC,TBD!!!F130!RSVD(288)!!!!
S!TP_CPU1_RSVD_292!U2D1!B81!@baseboard_fab2_lib.baseboard_fab2(sch_1):page56_i169@chpset_lib.skx_ext_b(chips)!SKX_EXT_B_BGA1-IC,TBD!!!F130!RSVD(292)!!!!
S!TP_CPU1_RSVD_1!U2D1!EF81!@baseboard_fab2_lib.baseboard_fab2(sch_1):page73_i107@chpset_lib.skx_ext_b(chips)!SKX_EXT_B_BGA1-IC,TBD!!!F110!RSVD(1)!!!!
S!TP_CPU1_RSVD_5!U2D1!EE82!@baseboard_fab2_lib.baseboard_fab2(sch_1):page73_i107@chpset_lib.skx_ext_b(chips)!SKX_EXT_B_BGA1-IC,TBD!!!F110!RSVD(5)!!!!
S!TP_CPU1_RSVD_0!U2D1!EF83!@baseboard_fab2_lib.baseboard_fab2(sch_1):page73_i107@chpset_lib.skx_ext_b(chips)!SKX_EXT_B_BGA1-IC,TBD!!!F110!RSVD(0)!!!!
S!TP_CPU1_RSVD_4!U2D1!EE84!@baseboard_fab2_lib.baseboard_fab2(sch_1):page73_i107@chpset_lib.skx_ext_b(chips)!SKX_EXT_B_BGA1-IC,TBD!!!F110!RSVD(4)!!!!
S!TP_CPU1_RSVD_270!U2D1!H85!@baseboard_fab2_lib.baseboard_fab2(sch_1):page56_i169@chpset_lib.skx_ext_b(chips)!SKX_EXT_B_BGA1-IC,TBD!!!F130!RSVD(270)!!!!
S!PVCCIN_CPU1!U2D1!BN78!@baseboard_fab2_lib.baseboard_fab2(sch_1):page71_i50@chpset_lib.skx_ext_b(chips)!SKX_EXT_B_BGA1-IC,TBD!!!F114!VCCIN(130)!!!!
S!PVCCIN_CPU1!U2D1!BN76!@baseboard_fab2_lib.baseboard_fab2(sch_1):page71_i50@chpset_lib.skx_ext_b(chips)!SKX_EXT_B_BGA1-IC,TBD!!!F114!VCCIN(131)!!!!
S!PVCCIN_CPU1!U2D1!BN74!@baseboard_fab2_lib.baseboard_fab2(sch_1):page71_i50@chpset_lib.skx_ext_b(chips)!SKX_EXT_B_BGA1-IC,TBD!!!F114!VCCIN(132)!!!!
S!PVCCIN_CPU1!U2D1!BN72!@baseboard_fab2_lib.baseboard_fab2(sch_1):page71_i50@chpset_lib.skx_ext_b(chips)!SKX_EXT_B_BGA1-IC,TBD!!!F114!VCCIN(133)!!!!
S!PVCCIN_CPU1!U2D1!BN70!@baseboard_fab2_lib.baseboard_fab2(sch_1):page71_i50@chpset_lib.skx_ext_b(chips)!SKX_EXT_B_BGA1-IC,TBD!!!F114!VCCIN(134)!!!!
S!PVCCIN_CPU1!U2D1!BN68!@baseboard_fab2_lib.baseboard_fab2(sch_1):page71_i50@chpset_lib.skx_ext_b(chips)!SKX_EXT_B_BGA1-IC,TBD!!!F114!VCCIN(135)!!!!
S!PVCCIN_CPU1!U2D1!BN66!@baseboard_fab2_lib.baseboard_fab2(sch_1):page71_i50@chpset_lib.skx_ext_b(chips)!SKX_EXT_B_BGA1-IC,TBD!!!F114!VCCIN(136)!!!!
S!PVCCIN_CPU1!U2D1!BN64!@baseboard_fab2_lib.baseboard_fab2(sch_1):page71_i50@chpset_lib.skx_ext_b(chips)!SKX_EXT_B_BGA1-IC,TBD!!!F114!VCCIN(137)!!!!
S!PVCCIN_CPU1!U2D1!BN62!@baseboard_fab2_lib.baseboard_fab2(sch_1):page71_i50@chpset_lib.skx_ext_b(chips)!SKX_EXT_B_BGA1-IC,TBD!!!F114!VCCIN(138)!!!!
S!PVCCIN_CPU1!U2D1!BN60!@baseboard_fab2_lib.baseboard_fab2(sch_1):page71_i50@chpset_lib.skx_ext_b(chips)!SKX_EXT_B_BGA1-IC,TBD!!!F114!VCCIN(139)!!!!
S!PVCCIN_CPU1!U2D1!BM83!@baseboard_fab2_lib.baseboard_fab2(sch_1):page71_i50@chpset_lib.skx_ext_b(chips)!SKX_EXT_B_BGA1-IC,TBD!!!F114!VCCIN(140)!!!!
S!PVCCIN_CPU1!U2D1!BM81!@baseboard_fab2_lib.baseboard_fab2(sch_1):page71_i50@chpset_lib.skx_ext_b(chips)!SKX_EXT_B_BGA1-IC,TBD!!!F114!VCCIN(141)!!!!
S!PVCCIN_CPU1!U2D1!BM79!@baseboard_fab2_lib.baseboard_fab2(sch_1):page71_i50@chpset_lib.skx_ext_b(chips)!SKX_EXT_B_BGA1-IC,TBD!!!F114!VCCIN(142)!!!!
S!PVCCIN_CPU1!U2D1!BM77!@baseboard_fab2_lib.baseboard_fab2(sch_1):page71_i50@chpset_lib.skx_ext_b(chips)!SKX_EXT_B_BGA1-IC,TBD!!!F114!VCCIN(143)!!!!
S!PVCCIN_CPU1!U2D1!BM75!@baseboard_fab2_lib.baseboard_fab2(sch_1):page71_i50@chpset_lib.skx_ext_b(chips)!SKX_EXT_B_BGA1-IC,TBD!!!F114!VCCIN(144)!!!!
S!PVCCIN_CPU1!U2D1!BM73!@baseboard_fab2_lib.baseboard_fab2(sch_1):page71_i50@chpset_lib.skx_ext_b(chips)!SKX_EXT_B_BGA1-IC,TBD!!!F114!VCCIN(145)!!!!
S!PVCCIN_CPU1!U2D1!BM71!@baseboard_fab2_lib.baseboard_fab2(sch_1):page71_i50@chpset_lib.skx_ext_b(chips)!SKX_EXT_B_BGA1-IC,TBD!!!F114!VCCIN(146)!!!!
S!PVCCIN_CPU1!U2D1!BM69!@baseboard_fab2_lib.baseboard_fab2(sch_1):page71_i50@chpset_lib.skx_ext_b(chips)!SKX_EXT_B_BGA1-IC,TBD!!!F114!VCCIN(147)!!!!
S!PVCCIN_CPU1!U2D1!BM67!@baseboard_fab2_lib.baseboard_fab2(sch_1):page71_i50@chpset_lib.skx_ext_b(chips)!SKX_EXT_B_BGA1-IC,TBD!!!F114!VCCIN(148)!!!!
S!PVCCIN_CPU1!U2D1!BM65!@baseboard_fab2_lib.baseboard_fab2(sch_1):page71_i50@chpset_lib.skx_ext_b(chips)!SKX_EXT_B_BGA1-IC,TBD!!!F114!VCCIN(149)!!!!
S!PVCCIN_CPU1!U2D1!BM63!@baseboard_fab2_lib.baseboard_fab2(sch_1):page71_i50@chpset_lib.skx_ext_b(chips)!SKX_EXT_B_BGA1-IC,TBD!!!F114!VCCIN(150)!!!!
S!PVCCIN_CPU1!U2D1!BM61!@baseboard_fab2_lib.baseboard_fab2(sch_1):page71_i50@chpset_lib.skx_ext_b(chips)!SKX_EXT_B_BGA1-IC,TBD!!!F114!VCCIN(151)!!!!
S!PVCCIN_CPU1!U2D1!BL84!@baseboard_fab2_lib.baseboard_fab2(sch_1):page71_i50@chpset_lib.skx_ext_b(chips)!SKX_EXT_B_BGA1-IC,TBD!!!F114!VCCIN(152)!!!!
S!PVCCIN_CPU1!U2D1!BL62!@baseboard_fab2_lib.baseboard_fab2(sch_1):page71_i50@chpset_lib.skx_ext_b(chips)!SKX_EXT_B_BGA1-IC,TBD!!!F114!VCCIN(153)!!!!
S!PVCCIN_CPU1!U2D1!BL60!@baseboard_fab2_lib.baseboard_fab2(sch_1):page71_i50@chpset_lib.skx_ext_b(chips)!SKX_EXT_B_BGA1-IC,TBD!!!F114!VCCIN(154)!!!!
S!PVCCIN_CPU1!U2D1!BK83!@baseboard_fab2_lib.baseboard_fab2(sch_1):page71_i50@chpset_lib.skx_ext_b(chips)!SKX_EXT_B_BGA1-IC,TBD!!!F114!VCCIN(155)!!!!
S!PVCCIN_CPU1!U2D1!BK81!@baseboard_fab2_lib.baseboard_fab2(sch_1):page71_i50@chpset_lib.skx_ext_b(chips)!SKX_EXT_B_BGA1-IC,TBD!!!F114!VCCIN(156)!!!!
S!PVCCIN_CPU1!U2D1!BK79!@baseboard_fab2_lib.baseboard_fab2(sch_1):page71_i50@chpset_lib.skx_ext_b(chips)!SKX_EXT_B_BGA1-IC,TBD!!!F114!VCCIN(157)!!!!
S!PVCCIN_CPU1!U2D1!BK77!@baseboard_fab2_lib.baseboard_fab2(sch_1):page71_i50@chpset_lib.skx_ext_b(chips)!SKX_EXT_B_BGA1-IC,TBD!!!F114!VCCIN(158)!!!!
S!PVCCIN_CPU1!U2D1!BK75!@baseboard_fab2_lib.baseboard_fab2(sch_1):page71_i50@chpset_lib.skx_ext_b(chips)!SKX_EXT_B_BGA1-IC,TBD!!!F114!VCCIN(159)!!!!
S!PVCCIN_CPU1!U2D1!BK73!@baseboard_fab2_lib.baseboard_fab2(sch_1):page71_i50@chpset_lib.skx_ext_b(chips)!SKX_EXT_B_BGA1-IC,TBD!!!F114!VCCIN(160)!!!!
S!PVCCIN_CPU1!U2D1!BK71!@baseboard_fab2_lib.baseboard_fab2(sch_1):page71_i50@chpset_lib.skx_ext_b(chips)!SKX_EXT_B_BGA1-IC,TBD!!!F114!VCCIN(161)!!!!
S!PVCCIN_CPU1!U2D1!BK69!@baseboard_fab2_lib.baseboard_fab2(sch_1):page71_i50@chpset_lib.skx_ext_b(chips)!SKX_EXT_B_BGA1-IC,TBD!!!F114!VCCIN(162)!!!!
S!PVCCIN_CPU1!U2D1!BK67!@baseboard_fab2_lib.baseboard_fab2(sch_1):page71_i50@chpset_lib.skx_ext_b(chips)!SKX_EXT_B_BGA1-IC,TBD!!!F114!VCCIN(163)!!!!
S!PVCCIN_CPU1!U2D1!BK65!@baseboard_fab2_lib.baseboard_fab2(sch_1):page71_i50@chpset_lib.skx_ext_b(chips)!SKX_EXT_B_BGA1-IC,TBD!!!F114!VCCIN(164)!!!!
S!PVCCIN_CPU1!U2D1!BK63!@baseboard_fab2_lib.baseboard_fab2(sch_1):page71_i50@chpset_lib.skx_ext_b(chips)!SKX_EXT_B_BGA1-IC,TBD!!!F114!VCCIN(165)!!!!
S!PVCCIN_CPU1!U2D1!BK61!@baseboard_fab2_lib.baseboard_fab2(sch_1):page71_i50@chpset_lib.skx_ext_b(chips)!SKX_EXT_B_BGA1-IC,TBD!!!F114!VCCIN(166)!!!!
S!PVCCIN_CPU1!U2D1!BJ84!@baseboard_fab2_lib.baseboard_fab2(sch_1):page71_i50@chpset_lib.skx_ext_b(chips)!SKX_EXT_B_BGA1-IC,TBD!!!F114!VCCIN(167)!!!!
S!PVCCIN_CPU1!U2D1!BJ82!@baseboard_fab2_lib.baseboard_fab2(sch_1):page71_i50@chpset_lib.skx_ext_b(chips)!SKX_EXT_B_BGA1-IC,TBD!!!F114!VCCIN(168)!!!!
S!PVCCIN_CPU1!U2D1!BJ80!@baseboard_fab2_lib.baseboard_fab2(sch_1):page71_i50@chpset_lib.skx_ext_b(chips)!SKX_EXT_B_BGA1-IC,TBD!!!F114!VCCIN(169)!!!!
S!PVCCIN_CPU1!U2D1!BJ78!@baseboard_fab2_lib.baseboard_fab2(sch_1):page71_i50@chpset_lib.skx_ext_b(chips)!SKX_EXT_B_BGA1-IC,TBD!!!F114!VCCIN(170)!!!!
S!PVCCIN_CPU1!U2D1!BJ76!@baseboard_fab2_lib.baseboard_fab2(sch_1):page71_i50@chpset_lib.skx_ext_b(chips)!SKX_EXT_B_BGA1-IC,TBD!!!F114!VCCIN(171)!!!!
S!PVCCIN_CPU1!U2D1!BJ74!@baseboard_fab2_lib.baseboard_fab2(sch_1):page71_i50@chpset_lib.skx_ext_b(chips)!SKX_EXT_B_BGA1-IC,TBD!!!F114!VCCIN(172)!!!!
S!PVCCIN_CPU1!U2D1!BJ72!@baseboard_fab2_lib.baseboard_fab2(sch_1):page71_i50@chpset_lib.skx_ext_b(chips)!SKX_EXT_B_BGA1-IC,TBD!!!F114!VCCIN(173)!!!!
S!PVCCIN_CPU1!U2D1!BJ70!@baseboard_fab2_lib.baseboard_fab2(sch_1):page71_i50@chpset_lib.skx_ext_b(chips)!SKX_EXT_B_BGA1-IC,TBD!!!F114!VCCIN(174)!!!!
S!PVCCIN_CPU1!U2D1!BJ68!@baseboard_fab2_lib.baseboard_fab2(sch_1):page71_i50@chpset_lib.skx_ext_b(chips)!SKX_EXT_B_BGA1-IC,TBD!!!F114!VCCIN(175)!!!!
S!PVCCIN_CPU1!U2D1!BJ66!@baseboard_fab2_lib.baseboard_fab2(sch_1):page71_i50@chpset_lib.skx_ext_b(chips)!SKX_EXT_B_BGA1-IC,TBD!!!F114!VCCIN(176)!!!!
S!PVCCIN_CPU1!U2D1!BJ64!@baseboard_fab2_lib.baseboard_fab2(sch_1):page71_i50@chpset_lib.skx_ext_b(chips)!SKX_EXT_B_BGA1-IC,TBD!!!F114!VCCIN(177)!!!!
S!PVCCIN_CPU1!U2D1!BJ62!@baseboard_fab2_lib.baseboard_fab2(sch_1):page71_i50@chpset_lib.skx_ext_b(chips)!SKX_EXT_B_BGA1-IC,TBD!!!F114!VCCIN(178)!!!!
S!PVCCIN_CPU1!U2D1!BJ60!@baseboard_fab2_lib.baseboard_fab2(sch_1):page71_i50@chpset_lib.skx_ext_b(chips)!SKX_EXT_B_BGA1-IC,TBD!!!F114!VCCIN(179)!!!!
S!PVCCIN_CPU1!U2D1!BH83!@baseboard_fab2_lib.baseboard_fab2(sch_1):page71_i50@chpset_lib.skx_ext_b(chips)!SKX_EXT_B_BGA1-IC,TBD!!!F114!VCCIN(180)!!!!
S!PVCCIN_CPU1!U2D1!BH81!@baseboard_fab2_lib.baseboard_fab2(sch_1):page71_i50@chpset_lib.skx_ext_b(chips)!SKX_EXT_B_BGA1-IC,TBD!!!F114!VCCIN(181)!!!!
S!PVCCIN_CPU1!U2D1!BH79!@baseboard_fab2_lib.baseboard_fab2(sch_1):page71_i50@chpset_lib.skx_ext_b(chips)!SKX_EXT_B_BGA1-IC,TBD!!!F114!VCCIN(182)!!!!
S!PVCCIN_CPU1!U2D1!BH77!@baseboard_fab2_lib.baseboard_fab2(sch_1):page71_i50@chpset_lib.skx_ext_b(chips)!SKX_EXT_B_BGA1-IC,TBD!!!F114!VCCIN(183)!!!!
S!PVCCIN_CPU1!U2D1!BH75!@baseboard_fab2_lib.baseboard_fab2(sch_1):page71_i50@chpset_lib.skx_ext_b(chips)!SKX_EXT_B_BGA1-IC,TBD!!!F114!VCCIN(184)!!!!
S!PVCCIN_CPU1!U2D1!BH73!@baseboard_fab2_lib.baseboard_fab2(sch_1):page71_i50@chpset_lib.skx_ext_b(chips)!SKX_EXT_B_BGA1-IC,TBD!!!F114!VCCIN(185)!!!!
S!PVCCIN_CPU1!U2D1!BH71!@baseboard_fab2_lib.baseboard_fab2(sch_1):page71_i50@chpset_lib.skx_ext_b(chips)!SKX_EXT_B_BGA1-IC,TBD!!!F114!VCCIN(186)!!!!
S!PVCCIN_CPU1!U2D1!BH69!@baseboard_fab2_lib.baseboard_fab2(sch_1):page71_i50@chpset_lib.skx_ext_b(chips)!SKX_EXT_B_BGA1-IC,TBD!!!F114!VCCIN(187)!!!!
S!PVCCIN_CPU1!U2D1!BH67!@baseboard_fab2_lib.baseboard_fab2(sch_1):page71_i50@chpset_lib.skx_ext_b(chips)!SKX_EXT_B_BGA1-IC,TBD!!!F114!VCCIN(188)!!!!
S!PVCCIN_CPU1!U2D1!BH65!@baseboard_fab2_lib.baseboard_fab2(sch_1):page71_i50@chpset_lib.skx_ext_b(chips)!SKX_EXT_B_BGA1-IC,TBD!!!F114!VCCIN(189)!!!!
S!PVCCIN_CPU1!U2D1!BH63!@baseboard_fab2_lib.baseboard_fab2(sch_1):page71_i50@chpset_lib.skx_ext_b(chips)!SKX_EXT_B_BGA1-IC,TBD!!!F114!VCCIN(190)!!!!
S!PVCCIN_CPU1!U2D1!BH61!@baseboard_fab2_lib.baseboard_fab2(sch_1):page71_i50@chpset_lib.skx_ext_b(chips)!SKX_EXT_B_BGA1-IC,TBD!!!F114!VCCIN(191)!!!!
S!PVCCIN_CPU1!U2D1!BG84!@baseboard_fab2_lib.baseboard_fab2(sch_1):page71_i50@chpset_lib.skx_ext_b(chips)!SKX_EXT_B_BGA1-IC,TBD!!!F114!VCCIN(192)!!!!
S!PVCCIN_CPU1!U2D1!BG70!@baseboard_fab2_lib.baseboard_fab2(sch_1):page71_i50@chpset_lib.skx_ext_b(chips)!SKX_EXT_B_BGA1-IC,TBD!!!F114!VCCIN(193)!!!!
S!PVCCIN_CPU1!U2D1!BG68!@baseboard_fab2_lib.baseboard_fab2(sch_1):page71_i50@chpset_lib.skx_ext_b(chips)!SKX_EXT_B_BGA1-IC,TBD!!!F114!VCCIN(194)!!!!
S!PVCCIN_CPU1!U2D1!BG66!@baseboard_fab2_lib.baseboard_fab2(sch_1):page71_i50@chpset_lib.skx_ext_b(chips)!SKX_EXT_B_BGA1-IC,TBD!!!F114!VCCIN(195)!!!!
S!PVCCIN_CPU1!U2D1!BG64!@baseboard_fab2_lib.baseboard_fab2(sch_1):page71_i50@chpset_lib.skx_ext_b(chips)!SKX_EXT_B_BGA1-IC,TBD!!!F114!VCCIN(196)!!!!
S!PVCCIN_CPU1!U2D1!BG62!@baseboard_fab2_lib.baseboard_fab2(sch_1):page71_i50@chpset_lib.skx_ext_b(chips)!SKX_EXT_B_BGA1-IC,TBD!!!F114!VCCIN(197)!!!!
S!PVCCIN_CPU1!U2D1!BG60!@baseboard_fab2_lib.baseboard_fab2(sch_1):page71_i50@chpset_lib.skx_ext_b(chips)!SKX_EXT_B_BGA1-IC,TBD!!!F114!VCCIN(198)!!!!
S!PVCCIN_CPU1!U2D1!BF85!@baseboard_fab2_lib.baseboard_fab2(sch_1):page71_i50@chpset_lib.skx_ext_b(chips)!SKX_EXT_B_BGA1-IC,TBD!!!F114!VCCIN(199)!!!!
S!PVCCIN_CPU1!U2D1!BF83!@baseboard_fab2_lib.baseboard_fab2(sch_1):page71_i50@chpset_lib.skx_ext_b(chips)!SKX_EXT_B_BGA1-IC,TBD!!!F114!VCCIN(200)!!!!
S!PVCCIN_CPU1!U2D1!BF81!@baseboard_fab2_lib.baseboard_fab2(sch_1):page71_i50@chpset_lib.skx_ext_b(chips)!SKX_EXT_B_BGA1-IC,TBD!!!F114!VCCIN(201)!!!!
S!PVCCIN_CPU1!U2D1!BF79!@baseboard_fab2_lib.baseboard_fab2(sch_1):page71_i50@chpset_lib.skx_ext_b(chips)!SKX_EXT_B_BGA1-IC,TBD!!!F114!VCCIN(202)!!!!
S!PVCCIN_CPU1!U2D1!BF77!@baseboard_fab2_lib.baseboard_fab2(sch_1):page71_i50@chpset_lib.skx_ext_b(chips)!SKX_EXT_B_BGA1-IC,TBD!!!F114!VCCIN(203)!!!!
S!PVCCIN_CPU1!U2D1!BF75!@baseboard_fab2_lib.baseboard_fab2(sch_1):page71_i50@chpset_lib.skx_ext_b(chips)!SKX_EXT_B_BGA1-IC,TBD!!!F114!VCCIN(204)!!!!
S!PVCCIN_CPU1!U2D1!BF73!@baseboard_fab2_lib.baseboard_fab2(sch_1):page71_i50@chpset_lib.skx_ext_b(chips)!SKX_EXT_B_BGA1-IC,TBD!!!F114!VCCIN(205)!!!!
S!PVCCIN_CPU1!U2D1!BF61!@baseboard_fab2_lib.baseboard_fab2(sch_1):page71_i50@chpset_lib.skx_ext_b(chips)!SKX_EXT_B_BGA1-IC,TBD!!!F114!VCCIN(206)!!!!
S!PVCCIN_CPU1!U2D1!BE84!@baseboard_fab2_lib.baseboard_fab2(sch_1):page71_i50@chpset_lib.skx_ext_b(chips)!SKX_EXT_B_BGA1-IC,TBD!!!F114!VCCIN(207)!!!!
S!PVCCIN_CPU1!U2D1!BE82!@baseboard_fab2_lib.baseboard_fab2(sch_1):page71_i50@chpset_lib.skx_ext_b(chips)!SKX_EXT_B_BGA1-IC,TBD!!!F114!VCCIN(208)!!!!
S!PVCCIN_CPU1!U2D1!BE80!@baseboard_fab2_lib.baseboard_fab2(sch_1):page71_i50@chpset_lib.skx_ext_b(chips)!SKX_EXT_B_BGA1-IC,TBD!!!F114!VCCIN(209)!!!!
S!PVCCIN_CPU1!U2D1!BE78!@baseboard_fab2_lib.baseboard_fab2(sch_1):page71_i50@chpset_lib.skx_ext_b(chips)!SKX_EXT_B_BGA1-IC,TBD!!!F114!VCCIN(210)!!!!
S!PVCCIN_CPU1!U2D1!BE76!@baseboard_fab2_lib.baseboard_fab2(sch_1):page71_i50@chpset_lib.skx_ext_b(chips)!SKX_EXT_B_BGA1-IC,TBD!!!F114!VCCIN(211)!!!!
S!PVCCIN_CPU1!U2D1!BE74!@baseboard_fab2_lib.baseboard_fab2(sch_1):page71_i50@chpset_lib.skx_ext_b(chips)!SKX_EXT_B_BGA1-IC,TBD!!!F114!VCCIN(212)!!!!
S!PVCCIN_CPU1!U2D1!BE72!@baseboard_fab2_lib.baseboard_fab2(sch_1):page71_i50@chpset_lib.skx_ext_b(chips)!SKX_EXT_B_BGA1-IC,TBD!!!F114!VCCIN(213)!!!!
S!PVCCIN_CPU1!U2D1!BE62!@baseboard_fab2_lib.baseboard_fab2(sch_1):page71_i50@chpset_lib.skx_ext_b(chips)!SKX_EXT_B_BGA1-IC,TBD!!!F114!VCCIN(214)!!!!
S!PVCCIN_CPU1!U2D1!BE60!@baseboard_fab2_lib.baseboard_fab2(sch_1):page71_i50@chpset_lib.skx_ext_b(chips)!SKX_EXT_B_BGA1-IC,TBD!!!F114!VCCIN(215)!!!!
S!PVCCIN_CPU1!U2D1!BD85!@baseboard_fab2_lib.baseboard_fab2(sch_1):page71_i50@chpset_lib.skx_ext_b(chips)!SKX_EXT_B_BGA1-IC,TBD!!!F114!VCCIN(216)!!!!
S!PVCCIN_CPU1!U2D1!BD83!@baseboard_fab2_lib.baseboard_fab2(sch_1):page71_i50@chpset_lib.skx_ext_b(chips)!SKX_EXT_B_BGA1-IC,TBD!!!F114!VCCIN(217)!!!!
S!PVCCIN_CPU1!U2D1!BD81!@baseboard_fab2_lib.baseboard_fab2(sch_1):page71_i50@chpset_lib.skx_ext_b(chips)!SKX_EXT_B_BGA1-IC,TBD!!!F114!VCCIN(218)!!!!
S!PVCCIN_CPU1!U2D1!BD79!@baseboard_fab2_lib.baseboard_fab2(sch_1):page71_i50@chpset_lib.skx_ext_b(chips)!SKX_EXT_B_BGA1-IC,TBD!!!F114!VCCIN(219)!!!!
S!PVCCIN_CPU1!U2D1!BD77!@baseboard_fab2_lib.baseboard_fab2(sch_1):page71_i50@chpset_lib.skx_ext_b(chips)!SKX_EXT_B_BGA1-IC,TBD!!!F114!VCCIN(220)!!!!
S!PVCCIN_CPU1!U2D1!BD75!@baseboard_fab2_lib.baseboard_fab2(sch_1):page71_i50@chpset_lib.skx_ext_b(chips)!SKX_EXT_B_BGA1-IC,TBD!!!F114!VCCIN(221)!!!!
S!PVCCIN_CPU1!U2D1!BD73!@baseboard_fab2_lib.baseboard_fab2(sch_1):page71_i50@chpset_lib.skx_ext_b(chips)!SKX_EXT_B_BGA1-IC,TBD!!!F114!VCCIN(222)!!!!
S!PVCCIN_CPU1!U2D1!BD61!@baseboard_fab2_lib.baseboard_fab2(sch_1):page71_i50@chpset_lib.skx_ext_b(chips)!SKX_EXT_B_BGA1-IC,TBD!!!F114!VCCIN(223)!!!!
S!PVCCIN_CPU1!U2D1!BC84!@baseboard_fab2_lib.baseboard_fab2(sch_1):page71_i50@chpset_lib.skx_ext_b(chips)!SKX_EXT_B_BGA1-IC,TBD!!!F114!VCCIN(224)!!!!
S!PVCCIN_CPU1!U2D1!BC62!@baseboard_fab2_lib.baseboard_fab2(sch_1):page71_i50@chpset_lib.skx_ext_b(chips)!SKX_EXT_B_BGA1-IC,TBD!!!F114!VCCIN(225)!!!!
S!PVCCIN_CPU1!U2D1!BC60!@baseboard_fab2_lib.baseboard_fab2(sch_1):page71_i50@chpset_lib.skx_ext_b(chips)!SKX_EXT_B_BGA1-IC,TBD!!!F114!VCCIN(226)!!!!
S!PVCCIN_CPU1!U2D1!BB85!@baseboard_fab2_lib.baseboard_fab2(sch_1):page71_i50@chpset_lib.skx_ext_b(chips)!SKX_EXT_B_BGA1-IC,TBD!!!F114!VCCIN(227)!!!!
S!PVCCIN_CPU1!U2D1!BB61!@baseboard_fab2_lib.baseboard_fab2(sch_1):page71_i50@chpset_lib.skx_ext_b(chips)!SKX_EXT_B_BGA1-IC,TBD!!!F114!VCCIN(228)!!!!
S!PVCCIN_CPU1!U2D1!BA60!@baseboard_fab2_lib.baseboard_fab2(sch_1):page71_i50@chpset_lib.skx_ext_b(chips)!SKX_EXT_B_BGA1-IC,TBD!!!F114!VCCIN(229)!!!!
S!PVCCIN_CPU1!U2D1!AY61!@baseboard_fab2_lib.baseboard_fab2(sch_1):page71_i50@chpset_lib.skx_ext_b(chips)!SKX_EXT_B_BGA1-IC,TBD!!!F114!VCCIN(230)!!!!
S!PVCCIN_CPU1!U2D1!AW60!@baseboard_fab2_lib.baseboard_fab2(sch_1):page71_i50@chpset_lib.skx_ext_b(chips)!SKX_EXT_B_BGA1-IC,TBD!!!F114!VCCIN(231)!!!!
S!PVCCIN_CPU1!U2D1!AV61!@baseboard_fab2_lib.baseboard_fab2(sch_1):page71_i50@chpset_lib.skx_ext_b(chips)!SKX_EXT_B_BGA1-IC,TBD!!!F114!VCCIN(232)!!!!
S!PVCCIN_CPU1!U2D1!AV59!@baseboard_fab2_lib.baseboard_fab2(sch_1):page71_i50@chpset_lib.skx_ext_b(chips)!SKX_EXT_B_BGA1-IC,TBD!!!F114!VCCIN(233)!!!!
S!PVCCIN_CPU1!U2D1!AU60!@baseboard_fab2_lib.baseboard_fab2(sch_1):page71_i50@chpset_lib.skx_ext_b(chips)!SKX_EXT_B_BGA1-IC,TBD!!!F114!VCCIN(234)!!!!
S!PVCCIN_CPU1!U2D1!AU58!@baseboard_fab2_lib.baseboard_fab2(sch_1):page71_i50@chpset_lib.skx_ext_b(chips)!SKX_EXT_B_BGA1-IC,TBD!!!F114!VCCIN(235)!!!!
S!PVCCIN_CPU1!U2D1!AT59!@baseboard_fab2_lib.baseboard_fab2(sch_1):page71_i50@chpset_lib.skx_ext_b(chips)!SKX_EXT_B_BGA1-IC,TBD!!!F114!VCCIN(236)!!!!
S!PVCCIN_CPU1!U2D1!AT57!@baseboard_fab2_lib.baseboard_fab2(sch_1):page71_i50@chpset_lib.skx_ext_b(chips)!SKX_EXT_B_BGA1-IC,TBD!!!F114!VCCIN(237)!!!!
S!PVCCIN_CPU1!U2D1!AR58!@baseboard_fab2_lib.baseboard_fab2(sch_1):page71_i50@chpset_lib.skx_ext_b(chips)!SKX_EXT_B_BGA1-IC,TBD!!!F114!VCCIN(238)!!!!
S!PVCCIN_CPU1!U2D1!AR56!@baseboard_fab2_lib.baseboard_fab2(sch_1):page71_i50@chpset_lib.skx_ext_b(chips)!SKX_EXT_B_BGA1-IC,TBD!!!F114!VCCIN(239)!!!!
S!PVCCIN_CPU1!U2D1!AP57!@baseboard_fab2_lib.baseboard_fab2(sch_1):page71_i50@chpset_lib.skx_ext_b(chips)!SKX_EXT_B_BGA1-IC,TBD!!!F114!VCCIN(240)!!!!
S!PVCCIN_CPU1!U2D1!AP55!@baseboard_fab2_lib.baseboard_fab2(sch_1):page71_i50@chpset_lib.skx_ext_b(chips)!SKX_EXT_B_BGA1-IC,TBD!!!F114!VCCIN(241)!!!!
S!PVCCIN_CPU1!U2D1!AN56!@baseboard_fab2_lib.baseboard_fab2(sch_1):page71_i50@chpset_lib.skx_ext_b(chips)!SKX_EXT_B_BGA1-IC,TBD!!!F114!VCCIN(242)!!!!
S!PVCCIN_CPU1!U2D1!AN54!@baseboard_fab2_lib.baseboard_fab2(sch_1):page71_i50@chpset_lib.skx_ext_b(chips)!SKX_EXT_B_BGA1-IC,TBD!!!F114!VCCIN(243)!!!!
S!PVCCIN_CPU1!U2D1!AN32!@baseboard_fab2_lib.baseboard_fab2(sch_1):page71_i50@chpset_lib.skx_ext_b(chips)!SKX_EXT_B_BGA1-IC,TBD!!!F114!VCCIN(244)!!!!
S!PVCCIN_CPU1!U2D1!AM55!@baseboard_fab2_lib.baseboard_fab2(sch_1):page71_i50@chpset_lib.skx_ext_b(chips)!SKX_EXT_B_BGA1-IC,TBD!!!F114!VCCIN(245)!!!!
S!PVCCIN_CPU1!U2D1!AM53!@baseboard_fab2_lib.baseboard_fab2(sch_1):page71_i50@chpset_lib.skx_ext_b(chips)!SKX_EXT_B_BGA1-IC,TBD!!!F114!VCCIN(246)!!!!
S!PVCCIN_CPU1!U2D1!AM33!@baseboard_fab2_lib.baseboard_fab2(sch_1):page71_i50@chpset_lib.skx_ext_b(chips)!SKX_EXT_B_BGA1-IC,TBD!!!F114!VCCIN(247)!!!!
S!PVCCIN_CPU1!U2D1!AL54!@baseboard_fab2_lib.baseboard_fab2(sch_1):page71_i50@chpset_lib.skx_ext_b(chips)!SKX_EXT_B_BGA1-IC,TBD!!!F114!VCCIN(248)!!!!
S!PVCCIN_CPU1!U2D1!AL52!@baseboard_fab2_lib.baseboard_fab2(sch_1):page71_i50@chpset_lib.skx_ext_b(chips)!SKX_EXT_B_BGA1-IC,TBD!!!F114!VCCIN(249)!!!!
S!PVCCIN_CPU1!U2D1!AL50!@baseboard_fab2_lib.baseboard_fab2(sch_1):page71_i50@chpset_lib.skx_ext_b(chips)!SKX_EXT_B_BGA1-IC,TBD!!!F114!VCCIN(250)!!!!
S!PVCCIN_CPU1!U2D1!AL48!@baseboard_fab2_lib.baseboard_fab2(sch_1):page71_i50@chpset_lib.skx_ext_b(chips)!SKX_EXT_B_BGA1-IC,TBD!!!F114!VCCIN(251)!!!!
S!PVCCIN_CPU1!U2D1!AL46!@baseboard_fab2_lib.baseboard_fab2(sch_1):page71_i50@chpset_lib.skx_ext_b(chips)!SKX_EXT_B_BGA1-IC,TBD!!!F114!VCCIN(252)!!!!
S!PVCCIN_CPU1!U2D1!AL34!@baseboard_fab2_lib.baseboard_fab2(sch_1):page71_i50@chpset_lib.skx_ext_b(chips)!SKX_EXT_B_BGA1-IC,TBD!!!F114!VCCIN(253)!!!!
S!PVCCIN_CPU1!U2D1!AK53!@baseboard_fab2_lib.baseboard_fab2(sch_1):page71_i50@chpset_lib.skx_ext_b(chips)!SKX_EXT_B_BGA1-IC,TBD!!!F114!VCCIN(254)!!!!
S!PVCCIN_CPU1!U2D1!AK51!@baseboard_fab2_lib.baseboard_fab2(sch_1):page71_i50@chpset_lib.skx_ext_b(chips)!SKX_EXT_B_BGA1-IC,TBD!!!F114!VCCIN(255)!!!!
S!PVCCIN_CPU1!U2D1!AK49!@baseboard_fab2_lib.baseboard_fab2(sch_1):page71_i50@chpset_lib.skx_ext_b(chips)!SKX_EXT_B_BGA1-IC,TBD!!!F114!VCCIN(256)!!!!
S!PVCCIN_CPU1!U2D1!AK47!@baseboard_fab2_lib.baseboard_fab2(sch_1):page71_i50@chpset_lib.skx_ext_b(chips)!SKX_EXT_B_BGA1-IC,TBD!!!F114!VCCIN(257)!!!!
S!PVCCIN_CPU1!U2D1!AK45!@baseboard_fab2_lib.baseboard_fab2(sch_1):page71_i50@chpset_lib.skx_ext_b(chips)!SKX_EXT_B_BGA1-IC,TBD!!!F114!VCCIN(258)!!!!
S!PVCCIN_CPU1!U2D1!AK35!@baseboard_fab2_lib.baseboard_fab2(sch_1):page71_i50@chpset_lib.skx_ext_b(chips)!SKX_EXT_B_BGA1-IC,TBD!!!F114!VCCIN(259)!!!!
S!PVCCIN_CPU1!U2D1!AJ36!@baseboard_fab2_lib.baseboard_fab2(sch_1):page71_i50@chpset_lib.skx_ext_b(chips)!SKX_EXT_B_BGA1-IC,TBD!!!F114!VCCIN(260)!!!!
S!PVCCIN_CPU1!U2D1!AH41!@baseboard_fab2_lib.baseboard_fab2(sch_1):page71_i50@chpset_lib.skx_ext_b(chips)!SKX_EXT_B_BGA1-IC,TBD!!!F114!VCCIN(261)!!!!
S!PVCCIN_CPU1!U2D1!AH39!@baseboard_fab2_lib.baseboard_fab2(sch_1):page71_i50@chpset_lib.skx_ext_b(chips)!SKX_EXT_B_BGA1-IC,TBD!!!F114!VCCIN(262)!!!!
S!PVCCIN_CPU1!U2D1!AH37!@baseboard_fab2_lib.baseboard_fab2(sch_1):page71_i50@chpset_lib.skx_ext_b(chips)!SKX_EXT_B_BGA1-IC,TBD!!!F114!VCCIN(263)!!!!
S!PVCCIN_CPU1!U2D1!AG42!@baseboard_fab2_lib.baseboard_fab2(sch_1):page71_i50@chpset_lib.skx_ext_b(chips)!SKX_EXT_B_BGA1-IC,TBD!!!F114!VCCIN(264)!!!!
S!PVCCIN_CPU1!U2D1!AG40!@baseboard_fab2_lib.baseboard_fab2(sch_1):page71_i50@chpset_lib.skx_ext_b(chips)!SKX_EXT_B_BGA1-IC,TBD!!!F114!VCCIN(265)!!!!
S!PVCCIN_CPU1!U2D1!AG38!@baseboard_fab2_lib.baseboard_fab2(sch_1):page71_i50@chpset_lib.skx_ext_b(chips)!SKX_EXT_B_BGA1-IC,TBD!!!F114!VCCIN(266)!!!!
S!PVCCIN_CPU1!U2D1!AF43!@baseboard_fab2_lib.baseboard_fab2(sch_1):page71_i50@chpset_lib.skx_ext_b(chips)!SKX_EXT_B_BGA1-IC,TBD!!!F114!VCCIN(267)!!!!
S!PVCCIN_CPU1!U2D1!CY49!@baseboard_fab2_lib.baseboard_fab2(sch_1):page71_i51@chpset_lib.skx_ext_b(chips)!SKX_EXT_B_BGA1-IC,TBD!!!F113!VCCIN(0)!!!!
S!PVCCIN_CPU1!U2D1!BT83!@baseboard_fab2_lib.baseboard_fab2(sch_1):page71_i51@chpset_lib.skx_ext_b(chips)!SKX_EXT_B_BGA1-IC,TBD!!!F113!VCCIN(100)!!!!
S!PVCCIN_CPU1!U2D1!BT81!@baseboard_fab2_lib.baseboard_fab2(sch_1):page71_i51@chpset_lib.skx_ext_b(chips)!SKX_EXT_B_BGA1-IC,TBD!!!F113!VCCIN(101)!!!!
S!PVCCIN_CPU1!U2D1!BT79!@baseboard_fab2_lib.baseboard_fab2(sch_1):page71_i51@chpset_lib.skx_ext_b(chips)!SKX_EXT_B_BGA1-IC,TBD!!!F113!VCCIN(102)!!!!
S!PVCCIN_CPU1!U2D1!BT77!@baseboard_fab2_lib.baseboard_fab2(sch_1):page71_i51@chpset_lib.skx_ext_b(chips)!SKX_EXT_B_BGA1-IC,TBD!!!F113!VCCIN(103)!!!!
S!PVCCIN_CPU1!U2D1!BT75!@baseboard_fab2_lib.baseboard_fab2(sch_1):page71_i51@chpset_lib.skx_ext_b(chips)!SKX_EXT_B_BGA1-IC,TBD!!!F113!VCCIN(104)!!!!
S!PVCCIN_CPU1!U2D1!BT73!@baseboard_fab2_lib.baseboard_fab2(sch_1):page71_i51@chpset_lib.skx_ext_b(chips)!SKX_EXT_B_BGA1-IC,TBD!!!F113!VCCIN(105)!!!!
S!PVCCIN_CPU1!U2D1!BT71!@baseboard_fab2_lib.baseboard_fab2(sch_1):page71_i51@chpset_lib.skx_ext_b(chips)!SKX_EXT_B_BGA1-IC,TBD!!!F113!VCCIN(106)!!!!
S!PVCCIN_CPU1!U2D1!BT69!@baseboard_fab2_lib.baseboard_fab2(sch_1):page71_i51@chpset_lib.skx_ext_b(chips)!SKX_EXT_B_BGA1-IC,TBD!!!F113!VCCIN(107)!!!!
S!PVCCIN_CPU1!U2D1!BT67!@baseboard_fab2_lib.baseboard_fab2(sch_1):page71_i51@chpset_lib.skx_ext_b(chips)!SKX_EXT_B_BGA1-IC,TBD!!!F113!VCCIN(108)!!!!
S!PVCCIN_CPU1!U2D1!BT65!@baseboard_fab2_lib.baseboard_fab2(sch_1):page71_i51@chpset_lib.skx_ext_b(chips)!SKX_EXT_B_BGA1-IC,TBD!!!F113!VCCIN(109)!!!!
S!PVCCIN_CPU1!U2D1!CU38!@baseboard_fab2_lib.baseboard_fab2(sch_1):page71_i51@chpset_lib.skx_ext_b(chips)!SKX_EXT_B_BGA1-IC,TBD!!!F113!VCCIN(10)!!!!
S!PVCCIN_CPU1!U2D1!BT63!@baseboard_fab2_lib.baseboard_fab2(sch_1):page71_i51@chpset_lib.skx_ext_b(chips)!SKX_EXT_B_BGA1-IC,TBD!!!F113!VCCIN(110)!!!!
S!PVCCIN_CPU1!U2D1!BT61!@baseboard_fab2_lib.baseboard_fab2(sch_1):page71_i51@chpset_lib.skx_ext_b(chips)!SKX_EXT_B_BGA1-IC,TBD!!!F113!VCCIN(111)!!!!
S!PVCCIN_CPU1!U2D1!BR84!@baseboard_fab2_lib.baseboard_fab2(sch_1):page71_i51@chpset_lib.skx_ext_b(chips)!SKX_EXT_B_BGA1-IC,TBD!!!F113!VCCIN(112)!!!!
S!PVCCIN_CPU1!U2D1!BR62!@baseboard_fab2_lib.baseboard_fab2(sch_1):page71_i51@chpset_lib.skx_ext_b(chips)!SKX_EXT_B_BGA1-IC,TBD!!!F113!VCCIN(113)!!!!
S!PVCCIN_CPU1!U2D1!BR60!@baseboard_fab2_lib.baseboard_fab2(sch_1):page71_i51@chpset_lib.skx_ext_b(chips)!SKX_EXT_B_BGA1-IC,TBD!!!F113!VCCIN(114)!!!!
S!PVCCIN_CPU1!U2D1!BP83!@baseboard_fab2_lib.baseboard_fab2(sch_1):page71_i51@chpset_lib.skx_ext_b(chips)!SKX_EXT_B_BGA1-IC,TBD!!!F113!VCCIN(115)!!!!
S!PVCCIN_CPU1!U2D1!BP81!@baseboard_fab2_lib.baseboard_fab2(sch_1):page71_i51@chpset_lib.skx_ext_b(chips)!SKX_EXT_B_BGA1-IC,TBD!!!F113!VCCIN(116)!!!!
S!PVCCIN_CPU1!U2D1!BP79!@baseboard_fab2_lib.baseboard_fab2(sch_1):page71_i51@chpset_lib.skx_ext_b(chips)!SKX_EXT_B_BGA1-IC,TBD!!!F113!VCCIN(117)!!!!
S!PVCCIN_CPU1!U2D1!BP77!@baseboard_fab2_lib.baseboard_fab2(sch_1):page71_i51@chpset_lib.skx_ext_b(chips)!SKX_EXT_B_BGA1-IC,TBD!!!F113!VCCIN(118)!!!!
S!PVCCIN_CPU1!U2D1!BP75!@baseboard_fab2_lib.baseboard_fab2(sch_1):page71_i51@chpset_lib.skx_ext_b(chips)!SKX_EXT_B_BGA1-IC,TBD!!!F113!VCCIN(119)!!!!
S!PVCCIN_CPU1!U2D1!CT55!@baseboard_fab2_lib.baseboard_fab2(sch_1):page71_i51@chpset_lib.skx_ext_b(chips)!SKX_EXT_B_BGA1-IC,TBD!!!F113!VCCIN(11)!!!!
S!PVCCIN_CPU1!U2D1!BP73!@baseboard_fab2_lib.baseboard_fab2(sch_1):page71_i51@chpset_lib.skx_ext_b(chips)!SKX_EXT_B_BGA1-IC,TBD!!!F113!VCCIN(120)!!!!
S!PVCCIN_CPU1!U2D1!BP71!@baseboard_fab2_lib.baseboard_fab2(sch_1):page71_i51@chpset_lib.skx_ext_b(chips)!SKX_EXT_B_BGA1-IC,TBD!!!F113!VCCIN(121)!!!!
S!PVCCIN_CPU1!U2D1!BP69!@baseboard_fab2_lib.baseboard_fab2(sch_1):page71_i51@chpset_lib.skx_ext_b(chips)!SKX_EXT_B_BGA1-IC,TBD!!!F113!VCCIN(122)!!!!
S!PVCCIN_CPU1!U2D1!BP67!@baseboard_fab2_lib.baseboard_fab2(sch_1):page71_i51@chpset_lib.skx_ext_b(chips)!SKX_EXT_B_BGA1-IC,TBD!!!F113!VCCIN(123)!!!!
S!PVCCIN_CPU1!U2D1!BP65!@baseboard_fab2_lib.baseboard_fab2(sch_1):page71_i51@chpset_lib.skx_ext_b(chips)!SKX_EXT_B_BGA1-IC,TBD!!!F113!VCCIN(124)!!!!
S!PVCCIN_CPU1!U2D1!BP63!@baseboard_fab2_lib.baseboard_fab2(sch_1):page71_i51@chpset_lib.skx_ext_b(chips)!SKX_EXT_B_BGA1-IC,TBD!!!F113!VCCIN(125)!!!!
S!PVCCIN_CPU1!U2D1!BP61!@baseboard_fab2_lib.baseboard_fab2(sch_1):page71_i51@chpset_lib.skx_ext_b(chips)!SKX_EXT_B_BGA1-IC,TBD!!!F113!VCCIN(126)!!!!
S!PVCCIN_CPU1!U2D1!BN84!@baseboard_fab2_lib.baseboard_fab2(sch_1):page71_i51@chpset_lib.skx_ext_b(chips)!SKX_EXT_B_BGA1-IC,TBD!!!F113!VCCIN(127)!!!!
S!PVCCIN_CPU1!U2D1!BN82!@baseboard_fab2_lib.baseboard_fab2(sch_1):page71_i51@chpset_lib.skx_ext_b(chips)!SKX_EXT_B_BGA1-IC,TBD!!!F113!VCCIN(128)!!!!
S!PVCCIN_CPU1!U2D1!BN80!@baseboard_fab2_lib.baseboard_fab2(sch_1):page71_i51@chpset_lib.skx_ext_b(chips)!SKX_EXT_B_BGA1-IC,TBD!!!F113!VCCIN(129)!!!!
S!PVCCIN_CPU1!U2D1!CT53!@baseboard_fab2_lib.baseboard_fab2(sch_1):page71_i51@chpset_lib.skx_ext_b(chips)!SKX_EXT_B_BGA1-IC,TBD!!!F113!VCCIN(12)!!!!
S!PVCCIN_CPU1!U2D1!CT41!@baseboard_fab2_lib.baseboard_fab2(sch_1):page71_i51@chpset_lib.skx_ext_b(chips)!SKX_EXT_B_BGA1-IC,TBD!!!F113!VCCIN(13)!!!!
S!PVCCIN_CPU1!U2D1!CT39!@baseboard_fab2_lib.baseboard_fab2(sch_1):page71_i51@chpset_lib.skx_ext_b(chips)!SKX_EXT_B_BGA1-IC,TBD!!!F113!VCCIN(14)!!!!
S!PVCCIN_CPU1!U2D1!CT37!@baseboard_fab2_lib.baseboard_fab2(sch_1):page71_i51@chpset_lib.skx_ext_b(chips)!SKX_EXT_B_BGA1-IC,TBD!!!F113!VCCIN(15)!!!!
S!PVCCIN_CPU1!U2D1!CR56!@baseboard_fab2_lib.baseboard_fab2(sch_1):page71_i51@chpset_lib.skx_ext_b(chips)!SKX_EXT_B_BGA1-IC,TBD!!!F113!VCCIN(16)!!!!
S!PVCCIN_CPU1!U2D1!CR54!@baseboard_fab2_lib.baseboard_fab2(sch_1):page71_i51@chpset_lib.skx_ext_b(chips)!SKX_EXT_B_BGA1-IC,TBD!!!F113!VCCIN(17)!!!!
S!PVCCIN_CPU1!U2D1!CR34!@baseboard_fab2_lib.baseboard_fab2(sch_1):page71_i51@chpset_lib.skx_ext_b(chips)!SKX_EXT_B_BGA1-IC,TBD!!!F113!VCCIN(18)!!!!
S!PVCCIN_CPU1!U2D1!CP57!@baseboard_fab2_lib.baseboard_fab2(sch_1):page71_i51@chpset_lib.skx_ext_b(chips)!SKX_EXT_B_BGA1-IC,TBD!!!F113!VCCIN(19)!!!!
S!PVCCIN_CPU1!U2D1!CY47!@baseboard_fab2_lib.baseboard_fab2(sch_1):page71_i51@chpset_lib.skx_ext_b(chips)!SKX_EXT_B_BGA1-IC,TBD!!!F113!VCCIN(1)!!!!
S!PVCCIN_CPU1!U2D1!CP55!@baseboard_fab2_lib.baseboard_fab2(sch_1):page71_i51@chpset_lib.skx_ext_b(chips)!SKX_EXT_B_BGA1-IC,TBD!!!F113!VCCIN(20)!!!!
S!PVCCIN_CPU1!U2D1!CP33!@baseboard_fab2_lib.baseboard_fab2(sch_1):page71_i51@chpset_lib.skx_ext_b(chips)!SKX_EXT_B_BGA1-IC,TBD!!!F113!VCCIN(21)!!!!
S!PVCCIN_CPU1!U2D1!CN58!@baseboard_fab2_lib.baseboard_fab2(sch_1):page71_i51@chpset_lib.skx_ext_b(chips)!SKX_EXT_B_BGA1-IC,TBD!!!F113!VCCIN(22)!!!!
S!PVCCIN_CPU1!U2D1!CN56!@baseboard_fab2_lib.baseboard_fab2(sch_1):page71_i51@chpset_lib.skx_ext_b(chips)!SKX_EXT_B_BGA1-IC,TBD!!!F113!VCCIN(23)!!!!
S!PVCCIN_CPU1!U2D1!CM59!@baseboard_fab2_lib.baseboard_fab2(sch_1):page71_i51@chpset_lib.skx_ext_b(chips)!SKX_EXT_B_BGA1-IC,TBD!!!F113!VCCIN(24)!!!!
S!PVCCIN_CPU1!U2D1!CM57!@baseboard_fab2_lib.baseboard_fab2(sch_1):page71_i51@chpset_lib.skx_ext_b(chips)!SKX_EXT_B_BGA1-IC,TBD!!!F113!VCCIN(25)!!!!
S!PVCCIN_CPU1!U2D1!CL60!@baseboard_fab2_lib.baseboard_fab2(sch_1):page71_i51@chpset_lib.skx_ext_b(chips)!SKX_EXT_B_BGA1-IC,TBD!!!F113!VCCIN(26)!!!!
S!PVCCIN_CPU1!U2D1!CL58!@baseboard_fab2_lib.baseboard_fab2(sch_1):page71_i51@chpset_lib.skx_ext_b(chips)!SKX_EXT_B_BGA1-IC,TBD!!!F113!VCCIN(27)!!!!
S!PVCCIN_CPU1!U2D1!CK61!@baseboard_fab2_lib.baseboard_fab2(sch_1):page71_i51@chpset_lib.skx_ext_b(chips)!SKX_EXT_B_BGA1-IC,TBD!!!F113!VCCIN(28)!!!!
S!PVCCIN_CPU1!U2D1!CK59!@baseboard_fab2_lib.baseboard_fab2(sch_1):page71_i51@chpset_lib.skx_ext_b(chips)!SKX_EXT_B_BGA1-IC,TBD!!!F113!VCCIN(29)!!!!
S!PVCCIN_CPU1!U2D1!CW50!@baseboard_fab2_lib.baseboard_fab2(sch_1):page71_i51@chpset_lib.skx_ext_b(chips)!SKX_EXT_B_BGA1-IC,TBD!!!F113!VCCIN(2)!!!!
S!PVCCIN_CPU1!U2D1!CJ60!@baseboard_fab2_lib.baseboard_fab2(sch_1):page71_i51@chpset_lib.skx_ext_b(chips)!SKX_EXT_B_BGA1-IC,TBD!!!F113!VCCIN(30)!!!!
S!PVCCIN_CPU1!U2D1!CH85!@baseboard_fab2_lib.baseboard_fab2(sch_1):page71_i51@chpset_lib.skx_ext_b(chips)!SKX_EXT_B_BGA1-IC,TBD!!!F113!VCCIN(31)!!!!
S!PVCCIN_CPU1!U2D1!CH61!@baseboard_fab2_lib.baseboard_fab2(sch_1):page71_i51@chpset_lib.skx_ext_b(chips)!SKX_EXT_B_BGA1-IC,TBD!!!F113!VCCIN(32)!!!!
S!PVCCIN_CPU1!U2D1!CG84!@baseboard_fab2_lib.baseboard_fab2(sch_1):page71_i51@chpset_lib.skx_ext_b(chips)!SKX_EXT_B_BGA1-IC,TBD!!!F113!VCCIN(33)!!!!
S!PVCCIN_CPU1!U2D1!CG60!@baseboard_fab2_lib.baseboard_fab2(sch_1):page71_i51@chpset_lib.skx_ext_b(chips)!SKX_EXT_B_BGA1-IC,TBD!!!F113!VCCIN(34)!!!!
S!PVCCIN_CPU1!U2D1!CF85!@baseboard_fab2_lib.baseboard_fab2(sch_1):page71_i51@chpset_lib.skx_ext_b(chips)!SKX_EXT_B_BGA1-IC,TBD!!!F113!VCCIN(35)!!!!
S!PVCCIN_CPU1!U2D1!CF61!@baseboard_fab2_lib.baseboard_fab2(sch_1):page71_i51@chpset_lib.skx_ext_b(chips)!SKX_EXT_B_BGA1-IC,TBD!!!F113!VCCIN(36)!!!!
S!PVCCIN_CPU1!U2D1!CE84!@baseboard_fab2_lib.baseboard_fab2(sch_1):page71_i51@chpset_lib.skx_ext_b(chips)!SKX_EXT_B_BGA1-IC,TBD!!!F113!VCCIN(37)!!!!
S!PVCCIN_CPU1!U2D1!CE60!@baseboard_fab2_lib.baseboard_fab2(sch_1):page71_i51@chpset_lib.skx_ext_b(chips)!SKX_EXT_B_BGA1-IC,TBD!!!F113!VCCIN(38)!!!!
S!PVCCIN_CPU1!U2D1!CD85!@baseboard_fab2_lib.baseboard_fab2(sch_1):page71_i51@chpset_lib.skx_ext_b(chips)!SKX_EXT_B_BGA1-IC,TBD!!!F113!VCCIN(39)!!!!
S!PVCCIN_CPU1!U2D1!CW48!@baseboard_fab2_lib.baseboard_fab2(sch_1):page71_i51@chpset_lib.skx_ext_b(chips)!SKX_EXT_B_BGA1-IC,TBD!!!F113!VCCIN(3)!!!!
S!PVCCIN_CPU1!U2D1!CD83!@baseboard_fab2_lib.baseboard_fab2(sch_1):page71_i51@chpset_lib.skx_ext_b(chips)!SKX_EXT_B_BGA1-IC,TBD!!!F113!VCCIN(40)!!!!
S!PVCCIN_CPU1!U2D1!CD61!@baseboard_fab2_lib.baseboard_fab2(sch_1):page71_i51@chpset_lib.skx_ext_b(chips)!SKX_EXT_B_BGA1-IC,TBD!!!F113!VCCIN(41)!!!!
S!PVCCIN_CPU1!U2D1!CC84!@baseboard_fab2_lib.baseboard_fab2(sch_1):page71_i51@chpset_lib.skx_ext_b(chips)!SKX_EXT_B_BGA1-IC,TBD!!!F113!VCCIN(42)!!!!
S!PVCCIN_CPU1!U2D1!CC62!@baseboard_fab2_lib.baseboard_fab2(sch_1):page71_i51@chpset_lib.skx_ext_b(chips)!SKX_EXT_B_BGA1-IC,TBD!!!F113!VCCIN(43)!!!!
S!PVCCIN_CPU1!U2D1!CC60!@baseboard_fab2_lib.baseboard_fab2(sch_1):page71_i51@chpset_lib.skx_ext_b(chips)!SKX_EXT_B_BGA1-IC,TBD!!!F113!VCCIN(44)!!!!
S!PVCCIN_CPU1!U2D1!CB83!@baseboard_fab2_lib.baseboard_fab2(sch_1):page71_i51@chpset_lib.skx_ext_b(chips)!SKX_EXT_B_BGA1-IC,TBD!!!F113!VCCIN(45)!!!!
S!PVCCIN_CPU1!U2D1!CB81!@baseboard_fab2_lib.baseboard_fab2(sch_1):page71_i51@chpset_lib.skx_ext_b(chips)!SKX_EXT_B_BGA1-IC,TBD!!!F113!VCCIN(46)!!!!
S!PVCCIN_CPU1!U2D1!CB79!@baseboard_fab2_lib.baseboard_fab2(sch_1):page71_i51@chpset_lib.skx_ext_b(chips)!SKX_EXT_B_BGA1-IC,TBD!!!F113!VCCIN(47)!!!!
S!PVCCIN_CPU1!U2D1!CB77!@baseboard_fab2_lib.baseboard_fab2(sch_1):page71_i51@chpset_lib.skx_ext_b(chips)!SKX_EXT_B_BGA1-IC,TBD!!!F113!VCCIN(48)!!!!
S!PVCCIN_CPU1!U2D1!CB75!@baseboard_fab2_lib.baseboard_fab2(sch_1):page71_i51@chpset_lib.skx_ext_b(chips)!SKX_EXT_B_BGA1-IC,TBD!!!F113!VCCIN(49)!!!!
S!PVCCIN_CPU1!U2D1!CW46!@baseboard_fab2_lib.baseboard_fab2(sch_1):page71_i51@chpset_lib.skx_ext_b(chips)!SKX_EXT_B_BGA1-IC,TBD!!!F113!VCCIN(4)!!!!
S!PVCCIN_CPU1!U2D1!CB73!@baseboard_fab2_lib.baseboard_fab2(sch_1):page71_i51@chpset_lib.skx_ext_b(chips)!SKX_EXT_B_BGA1-IC,TBD!!!F113!VCCIN(50)!!!!
S!PVCCIN_CPU1!U2D1!CB61!@baseboard_fab2_lib.baseboard_fab2(sch_1):page71_i51@chpset_lib.skx_ext_b(chips)!SKX_EXT_B_BGA1-IC,TBD!!!F113!VCCIN(51)!!!!
S!PVCCIN_CPU1!U2D1!CA84!@baseboard_fab2_lib.baseboard_fab2(sch_1):page71_i51@chpset_lib.skx_ext_b(chips)!SKX_EXT_B_BGA1-IC,TBD!!!F113!VCCIN(52)!!!!
S!PVCCIN_CPU1!U2D1!CA82!@baseboard_fab2_lib.baseboard_fab2(sch_1):page71_i51@chpset_lib.skx_ext_b(chips)!SKX_EXT_B_BGA1-IC,TBD!!!F113!VCCIN(53)!!!!
S!PVCCIN_CPU1!U2D1!CA80!@baseboard_fab2_lib.baseboard_fab2(sch_1):page71_i51@chpset_lib.skx_ext_b(chips)!SKX_EXT_B_BGA1-IC,TBD!!!F113!VCCIN(54)!!!!
S!PVCCIN_CPU1!U2D1!CA78!@baseboard_fab2_lib.baseboard_fab2(sch_1):page71_i51@chpset_lib.skx_ext_b(chips)!SKX_EXT_B_BGA1-IC,TBD!!!F113!VCCIN(55)!!!!
S!PVCCIN_CPU1!U2D1!CA76!@baseboard_fab2_lib.baseboard_fab2(sch_1):page71_i51@chpset_lib.skx_ext_b(chips)!SKX_EXT_B_BGA1-IC,TBD!!!F113!VCCIN(56)!!!!
S!PVCCIN_CPU1!U2D1!CA74!@baseboard_fab2_lib.baseboard_fab2(sch_1):page71_i51@chpset_lib.skx_ext_b(chips)!SKX_EXT_B_BGA1-IC,TBD!!!F113!VCCIN(57)!!!!
S!PVCCIN_CPU1!U2D1!CA72!@baseboard_fab2_lib.baseboard_fab2(sch_1):page71_i51@chpset_lib.skx_ext_b(chips)!SKX_EXT_B_BGA1-IC,TBD!!!F113!VCCIN(58)!!!!
S!PVCCIN_CPU1!U2D1!CA62!@baseboard_fab2_lib.baseboard_fab2(sch_1):page71_i51@chpset_lib.skx_ext_b(chips)!SKX_EXT_B_BGA1-IC,TBD!!!F113!VCCIN(59)!!!!
S!PVCCIN_CPU1!U2D1!CV51!@baseboard_fab2_lib.baseboard_fab2(sch_1):page71_i51@chpset_lib.skx_ext_b(chips)!SKX_EXT_B_BGA1-IC,TBD!!!F113!VCCIN(5)!!!!
S!PVCCIN_CPU1!U2D1!CA60!@baseboard_fab2_lib.baseboard_fab2(sch_1):page71_i51@chpset_lib.skx_ext_b(chips)!SKX_EXT_B_BGA1-IC,TBD!!!F113!VCCIN(60)!!!!
S!PVCCIN_CPU1!U2D1!BY83!@baseboard_fab2_lib.baseboard_fab2(sch_1):page71_i51@chpset_lib.skx_ext_b(chips)!SKX_EXT_B_BGA1-IC,TBD!!!F113!VCCIN(61)!!!!
S!PVCCIN_CPU1!U2D1!BY81!@baseboard_fab2_lib.baseboard_fab2(sch_1):page71_i51@chpset_lib.skx_ext_b(chips)!SKX_EXT_B_BGA1-IC,TBD!!!F113!VCCIN(62)!!!!
S!PVCCIN_CPU1!U2D1!BY79!@baseboard_fab2_lib.baseboard_fab2(sch_1):page71_i51@chpset_lib.skx_ext_b(chips)!SKX_EXT_B_BGA1-IC,TBD!!!F113!VCCIN(63)!!!!
S!PVCCIN_CPU1!U2D1!BY77!@baseboard_fab2_lib.baseboard_fab2(sch_1):page71_i51@chpset_lib.skx_ext_b(chips)!SKX_EXT_B_BGA1-IC,TBD!!!F113!VCCIN(64)!!!!
S!PVCCIN_CPU1!U2D1!BY75!@baseboard_fab2_lib.baseboard_fab2(sch_1):page71_i51@chpset_lib.skx_ext_b(chips)!SKX_EXT_B_BGA1-IC,TBD!!!F113!VCCIN(65)!!!!
S!PVCCIN_CPU1!U2D1!BY73!@baseboard_fab2_lib.baseboard_fab2(sch_1):page71_i51@chpset_lib.skx_ext_b(chips)!SKX_EXT_B_BGA1-IC,TBD!!!F113!VCCIN(66)!!!!
S!PVCCIN_CPU1!U2D1!BY61!@baseboard_fab2_lib.baseboard_fab2(sch_1):page71_i51@chpset_lib.skx_ext_b(chips)!SKX_EXT_B_BGA1-IC,TBD!!!F113!VCCIN(67)!!!!
S!PVCCIN_CPU1!U2D1!BW84!@baseboard_fab2_lib.baseboard_fab2(sch_1):page71_i51@chpset_lib.skx_ext_b(chips)!SKX_EXT_B_BGA1-IC,TBD!!!F113!VCCIN(68)!!!!
S!PVCCIN_CPU1!U2D1!BW70!@baseboard_fab2_lib.baseboard_fab2(sch_1):page71_i51@chpset_lib.skx_ext_b(chips)!SKX_EXT_B_BGA1-IC,TBD!!!F113!VCCIN(69)!!!!
S!PVCCIN_CPU1!U2D1!CU54!@baseboard_fab2_lib.baseboard_fab2(sch_1):page71_i51@chpset_lib.skx_ext_b(chips)!SKX_EXT_B_BGA1-IC,TBD!!!F113!VCCIN(6)!!!!
S!PVCCIN_CPU1!U2D1!BW68!@baseboard_fab2_lib.baseboard_fab2(sch_1):page71_i51@chpset_lib.skx_ext_b(chips)!SKX_EXT_B_BGA1-IC,TBD!!!F113!VCCIN(70)!!!!
S!PVCCIN_CPU1!U2D1!BW66!@baseboard_fab2_lib.baseboard_fab2(sch_1):page71_i51@chpset_lib.skx_ext_b(chips)!SKX_EXT_B_BGA1-IC,TBD!!!F113!VCCIN(71)!!!!
S!PVCCIN_CPU1!U2D1!BW64!@baseboard_fab2_lib.baseboard_fab2(sch_1):page71_i51@chpset_lib.skx_ext_b(chips)!SKX_EXT_B_BGA1-IC,TBD!!!F113!VCCIN(72)!!!!
S!PVCCIN_CPU1!U2D1!BW62!@baseboard_fab2_lib.baseboard_fab2(sch_1):page71_i51@chpset_lib.skx_ext_b(chips)!SKX_EXT_B_BGA1-IC,TBD!!!F113!VCCIN(73)!!!!
S!PVCCIN_CPU1!U2D1!BW60!@baseboard_fab2_lib.baseboard_fab2(sch_1):page71_i51@chpset_lib.skx_ext_b(chips)!SKX_EXT_B_BGA1-IC,TBD!!!F113!VCCIN(74)!!!!
S!PVCCIN_CPU1!U2D1!BV83!@baseboard_fab2_lib.baseboard_fab2(sch_1):page71_i51@chpset_lib.skx_ext_b(chips)!SKX_EXT_B_BGA1-IC,TBD!!!F113!VCCIN(75)!!!!
S!PVCCIN_CPU1!U2D1!BV81!@baseboard_fab2_lib.baseboard_fab2(sch_1):page71_i51@chpset_lib.skx_ext_b(chips)!SKX_EXT_B_BGA1-IC,TBD!!!F113!VCCIN(76)!!!!
S!PVCCIN_CPU1!U2D1!BV79!@baseboard_fab2_lib.baseboard_fab2(sch_1):page71_i51@chpset_lib.skx_ext_b(chips)!SKX_EXT_B_BGA1-IC,TBD!!!F113!VCCIN(77)!!!!
S!PVCCIN_CPU1!U2D1!BV77!@baseboard_fab2_lib.baseboard_fab2(sch_1):page71_i51@chpset_lib.skx_ext_b(chips)!SKX_EXT_B_BGA1-IC,TBD!!!F113!VCCIN(78)!!!!
S!PVCCIN_CPU1!U2D1!BV75!@baseboard_fab2_lib.baseboard_fab2(sch_1):page71_i51@chpset_lib.skx_ext_b(chips)!SKX_EXT_B_BGA1-IC,TBD!!!F113!VCCIN(79)!!!!
S!PVCCIN_CPU1!U2D1!CU52!@baseboard_fab2_lib.baseboard_fab2(sch_1):page71_i51@chpset_lib.skx_ext_b(chips)!SKX_EXT_B_BGA1-IC,TBD!!!F113!VCCIN(7)!!!!
S!PVCCIN_CPU1!U2D1!BV73!@baseboard_fab2_lib.baseboard_fab2(sch_1):page71_i51@chpset_lib.skx_ext_b(chips)!SKX_EXT_B_BGA1-IC,TBD!!!F113!VCCIN(80)!!!!
S!PVCCIN_CPU1!U2D1!BV71!@baseboard_fab2_lib.baseboard_fab2(sch_1):page71_i51@chpset_lib.skx_ext_b(chips)!SKX_EXT_B_BGA1-IC,TBD!!!F113!VCCIN(81)!!!!
S!PVCCIN_CPU1!U2D1!BV69!@baseboard_fab2_lib.baseboard_fab2(sch_1):page71_i51@chpset_lib.skx_ext_b(chips)!SKX_EXT_B_BGA1-IC,TBD!!!F113!VCCIN(82)!!!!
S!PVCCIN_CPU1!U2D1!BV67!@baseboard_fab2_lib.baseboard_fab2(sch_1):page71_i51@chpset_lib.skx_ext_b(chips)!SKX_EXT_B_BGA1-IC,TBD!!!F113!VCCIN(83)!!!!
S!PVCCIN_CPU1!U2D1!BV65!@baseboard_fab2_lib.baseboard_fab2(sch_1):page71_i51@chpset_lib.skx_ext_b(chips)!SKX_EXT_B_BGA1-IC,TBD!!!F113!VCCIN(84)!!!!
S!PVCCIN_CPU1!U2D1!BV63!@baseboard_fab2_lib.baseboard_fab2(sch_1):page71_i51@chpset_lib.skx_ext_b(chips)!SKX_EXT_B_BGA1-IC,TBD!!!F113!VCCIN(85)!!!!
S!PVCCIN_CPU1!U2D1!BV61!@baseboard_fab2_lib.baseboard_fab2(sch_1):page71_i51@chpset_lib.skx_ext_b(chips)!SKX_EXT_B_BGA1-IC,TBD!!!F113!VCCIN(86)!!!!
S!PVCCIN_CPU1!U2D1!BU84!@baseboard_fab2_lib.baseboard_fab2(sch_1):page71_i51@chpset_lib.skx_ext_b(chips)!SKX_EXT_B_BGA1-IC,TBD!!!F113!VCCIN(87)!!!!
S!PVCCIN_CPU1!U2D1!BU82!@baseboard_fab2_lib.baseboard_fab2(sch_1):page71_i51@chpset_lib.skx_ext_b(chips)!SKX_EXT_B_BGA1-IC,TBD!!!F113!VCCIN(88)!!!!
S!PVCCIN_CPU1!U2D1!BU80!@baseboard_fab2_lib.baseboard_fab2(sch_1):page71_i51@chpset_lib.skx_ext_b(chips)!SKX_EXT_B_BGA1-IC,TBD!!!F113!VCCIN(89)!!!!
S!PVCCIN_CPU1!U2D1!CU42!@baseboard_fab2_lib.baseboard_fab2(sch_1):page71_i51@chpset_lib.skx_ext_b(chips)!SKX_EXT_B_BGA1-IC,TBD!!!F113!VCCIN(8)!!!!
S!PVCCIN_CPU1!U2D1!BU78!@baseboard_fab2_lib.baseboard_fab2(sch_1):page71_i51@chpset_lib.skx_ext_b(chips)!SKX_EXT_B_BGA1-IC,TBD!!!F113!VCCIN(90)!!!!
S!PVCCIN_CPU1!U2D1!BU76!@baseboard_fab2_lib.baseboard_fab2(sch_1):page71_i51@chpset_lib.skx_ext_b(chips)!SKX_EXT_B_BGA1-IC,TBD!!!F113!VCCIN(91)!!!!
S!PVCCIN_CPU1!U2D1!BU74!@baseboard_fab2_lib.baseboard_fab2(sch_1):page71_i51@chpset_lib.skx_ext_b(chips)!SKX_EXT_B_BGA1-IC,TBD!!!F113!VCCIN(92)!!!!
S!PVCCIN_CPU1!U2D1!BU72!@baseboard_fab2_lib.baseboard_fab2(sch_1):page71_i51@chpset_lib.skx_ext_b(chips)!SKX_EXT_B_BGA1-IC,TBD!!!F113!VCCIN(93)!!!!
S!PVCCIN_CPU1!U2D1!BU70!@baseboard_fab2_lib.baseboard_fab2(sch_1):page71_i51@chpset_lib.skx_ext_b(chips)!SKX_EXT_B_BGA1-IC,TBD!!!F113!VCCIN(94)!!!!
S!PVCCIN_CPU1!U2D1!BU68!@baseboard_fab2_lib.baseboard_fab2(sch_1):page71_i51@chpset_lib.skx_ext_b(chips)!SKX_EXT_B_BGA1-IC,TBD!!!F113!VCCIN(95)!!!!
S!PVCCIN_CPU1!U2D1!BU66!@baseboard_fab2_lib.baseboard_fab2(sch_1):page71_i51@chpset_lib.skx_ext_b(chips)!SKX_EXT_B_BGA1-IC,TBD!!!F113!VCCIN(96)!!!!
S!PVCCIN_CPU1!U2D1!BU64!@baseboard_fab2_lib.baseboard_fab2(sch_1):page71_i51@chpset_lib.skx_ext_b(chips)!SKX_EXT_B_BGA1-IC,TBD!!!F113!VCCIN(97)!!!!
S!PVCCIN_CPU1!U2D1!BU62!@baseboard_fab2_lib.baseboard_fab2(sch_1):page71_i51@chpset_lib.skx_ext_b(chips)!SKX_EXT_B_BGA1-IC,TBD!!!F113!VCCIN(98)!!!!
S!PVCCIN_CPU1!U2D1!BU60!@baseboard_fab2_lib.baseboard_fab2(sch_1):page71_i51@chpset_lib.skx_ext_b(chips)!SKX_EXT_B_BGA1-IC,TBD!!!F113!VCCIN(99)!!!!
S!PVCCIN_CPU1!U2D1!CU40!@baseboard_fab2_lib.baseboard_fab2(sch_1):page71_i51@chpset_lib.skx_ext_b(chips)!SKX_EXT_B_BGA1-IC,TBD!!!F113!VCCIN(9)!!!!
S!VSENSE_VCCINR2PMAX_CPU1!U2D1!AW86!@baseboard_fab2_lib.baseboard_fab2(sch_1):page71_i51@chpset_lib.skx_ext_b(chips)!SKX_EXT_B_BGA1-IC,TBD!!!F113!VCCINPMAX(0)!!!!
S!VSENSE_VCCINR2PMAX_CPU1!U2D1!AV85!@baseboard_fab2_lib.baseboard_fab2(sch_1):page71_i51@chpset_lib.skx_ext_b(chips)!SKX_EXT_B_BGA1-IC,TBD!!!F113!VCCINPMAX(1)!!!!
S!VSENSE_PVCCIN_CPU1_SKT_VSEN!U2D1!BA86!@baseboard_fab2_lib.baseboard_fab2(sch_1):page71_i51@chpset_lib.skx_ext_b(chips)!SKX_EXT_B_BGA1-IC,TBD!!!F113!VCCIN_SENSE!!!!
S!TP_CPU1_RSVD_255!U2D1!AY83!@baseboard_fab2_lib.baseboard_fab2(sch_1):page70_i9@chpset_lib.skx_ext_b(chips)!SKX_EXT_B_BGA1-IC,TBD!!!F116!RSVD(255)!!!!
S!VSENSE_PVCCIN_CPU1_SKT_VRTN!U2D1!AY85!@baseboard_fab2_lib.baseboard_fab2(sch_1):page71_i51@chpset_lib.skx_ext_b(chips)!SKX_EXT_B_BGA1-IC,TBD!!!F113!VSS_VCCIN_SENSE!!!!
S!PVDDQ_GHJ!U2D1!B49!@baseboard_fab2_lib.baseboard_fab2(sch_1):page72_i32@chpset_lib.skx_ext_b(chips)!SKX_EXT_B_BGA1-IC,TBD!!!F112!VCCD012(0)!!!!
S!PVDDQ_GHJ!U2D1!E60!@baseboard_fab2_lib.baseboard_fab2(sch_1):page72_i32@chpset_lib.skx_ext_b(chips)!SKX_EXT_B_BGA1-IC,TBD!!!F112!VCCD012(10)!!!!
S!PVDDQ_GHJ!U2D1!E62!@baseboard_fab2_lib.baseboard_fab2(sch_1):page72_i32@chpset_lib.skx_ext_b(chips)!SKX_EXT_B_BGA1-IC,TBD!!!F112!VCCD012(11)!!!!
S!PVDDQ_GHJ!U2D1!E64!@baseboard_fab2_lib.baseboard_fab2(sch_1):page72_i32@chpset_lib.skx_ext_b(chips)!SKX_EXT_B_BGA1-IC,TBD!!!F112!VCCD012(12)!!!!
S!PVDDQ_GHJ!U2D1!L46!@baseboard_fab2_lib.baseboard_fab2(sch_1):page72_i32@chpset_lib.skx_ext_b(chips)!SKX_EXT_B_BGA1-IC,TBD!!!F112!VCCD012(13)!!!!
S!PVDDQ_GHJ!U2D1!L48!@baseboard_fab2_lib.baseboard_fab2(sch_1):page72_i32@chpset_lib.skx_ext_b(chips)!SKX_EXT_B_BGA1-IC,TBD!!!F112!VCCD012(14)!!!!
S!PVDDQ_GHJ!U2D1!L50!@baseboard_fab2_lib.baseboard_fab2(sch_1):page72_i32@chpset_lib.skx_ext_b(chips)!SKX_EXT_B_BGA1-IC,TBD!!!F112!VCCD012(15)!!!!
S!PVDDQ_GHJ!U2D1!L52!@baseboard_fab2_lib.baseboard_fab2(sch_1):page72_i32@chpset_lib.skx_ext_b(chips)!SKX_EXT_B_BGA1-IC,TBD!!!F112!VCCD012(16)!!!!
S!PVDDQ_GHJ!U2D1!L54!@baseboard_fab2_lib.baseboard_fab2(sch_1):page72_i32@chpset_lib.skx_ext_b(chips)!SKX_EXT_B_BGA1-IC,TBD!!!F112!VCCD012(17)!!!!
S!PVDDQ_GHJ!U2D1!L56!@baseboard_fab2_lib.baseboard_fab2(sch_1):page72_i32@chpset_lib.skx_ext_b(chips)!SKX_EXT_B_BGA1-IC,TBD!!!F112!VCCD012(18)!!!!
S!PVDDQ_GHJ!U2D1!L58!@baseboard_fab2_lib.baseboard_fab2(sch_1):page72_i32@chpset_lib.skx_ext_b(chips)!SKX_EXT_B_BGA1-IC,TBD!!!F112!VCCD012(19)!!!!
S!PVDDQ_GHJ!U2D1!B53!@baseboard_fab2_lib.baseboard_fab2(sch_1):page72_i32@chpset_lib.skx_ext_b(chips)!SKX_EXT_B_BGA1-IC,TBD!!!F112!VCCD012(1)!!!!
S!PVDDQ_GHJ!U2D1!L60!@baseboard_fab2_lib.baseboard_fab2(sch_1):page72_i32@chpset_lib.skx_ext_b(chips)!SKX_EXT_B_BGA1-IC,TBD!!!F112!VCCD012(20)!!!!
S!PVDDQ_GHJ!U2D1!L62!@baseboard_fab2_lib.baseboard_fab2(sch_1):page72_i32@chpset_lib.skx_ext_b(chips)!SKX_EXT_B_BGA1-IC,TBD!!!F112!VCCD012(21)!!!!
S!PVDDQ_GHJ!U2D1!N64!@baseboard_fab2_lib.baseboard_fab2(sch_1):page72_i32@chpset_lib.skx_ext_b(chips)!SKX_EXT_B_BGA1-IC,TBD!!!F112!VCCD012(22)!!!!
S!PVDDQ_GHJ!U2D1!U46!@baseboard_fab2_lib.baseboard_fab2(sch_1):page72_i32@chpset_lib.skx_ext_b(chips)!SKX_EXT_B_BGA1-IC,TBD!!!F112!VCCD012(23)!!!!
S!PVDDQ_GHJ!U2D1!U48!@baseboard_fab2_lib.baseboard_fab2(sch_1):page72_i32@chpset_lib.skx_ext_b(chips)!SKX_EXT_B_BGA1-IC,TBD!!!F112!VCCD012(24)!!!!
S!PVDDQ_GHJ!U2D1!U50!@baseboard_fab2_lib.baseboard_fab2(sch_1):page72_i32@chpset_lib.skx_ext_b(chips)!SKX_EXT_B_BGA1-IC,TBD!!!F112!VCCD012(25)!!!!
S!PVDDQ_GHJ!U2D1!U52!@baseboard_fab2_lib.baseboard_fab2(sch_1):page72_i32@chpset_lib.skx_ext_b(chips)!SKX_EXT_B_BGA1-IC,TBD!!!F112!VCCD012(26)!!!!
S!PVDDQ_GHJ!U2D1!U54!@baseboard_fab2_lib.baseboard_fab2(sch_1):page72_i32@chpset_lib.skx_ext_b(chips)!SKX_EXT_B_BGA1-IC,TBD!!!F112!VCCD012(27)!!!!
S!PVDDQ_GHJ!U2D1!U56!@baseboard_fab2_lib.baseboard_fab2(sch_1):page72_i32@chpset_lib.skx_ext_b(chips)!SKX_EXT_B_BGA1-IC,TBD!!!F112!VCCD012(28)!!!!
S!PVDDQ_GHJ!U2D1!U58!@baseboard_fab2_lib.baseboard_fab2(sch_1):page72_i32@chpset_lib.skx_ext_b(chips)!SKX_EXT_B_BGA1-IC,TBD!!!F112!VCCD012(29)!!!!
S!PVDDQ_GHJ!U2D1!B59!@baseboard_fab2_lib.baseboard_fab2(sch_1):page72_i32@chpset_lib.skx_ext_b(chips)!SKX_EXT_B_BGA1-IC,TBD!!!F112!VCCD012(2)!!!!
S!PVDDQ_GHJ!U2D1!U60!@baseboard_fab2_lib.baseboard_fab2(sch_1):page72_i32@chpset_lib.skx_ext_b(chips)!SKX_EXT_B_BGA1-IC,TBD!!!F112!VCCD012(30)!!!!
S!PVDDQ_GHJ!U2D1!U62!@baseboard_fab2_lib.baseboard_fab2(sch_1):page72_i32@chpset_lib.skx_ext_b(chips)!SKX_EXT_B_BGA1-IC,TBD!!!F112!VCCD012(31)!!!!
S!PVDDQ_GHJ!U2D1!W64!@baseboard_fab2_lib.baseboard_fab2(sch_1):page72_i32@chpset_lib.skx_ext_b(chips)!SKX_EXT_B_BGA1-IC,TBD!!!F112!VCCD012(32)!!!!
S!PVDDQ_GHJ!U2D1!Y45!@baseboard_fab2_lib.baseboard_fab2(sch_1):page72_i32@chpset_lib.skx_ext_b(chips)!SKX_EXT_B_BGA1-IC,TBD!!!F112!VCCD012(33)!!!!
S!PVDDQ_GHJ!U2D1!Y47!@baseboard_fab2_lib.baseboard_fab2(sch_1):page72_i32@chpset_lib.skx_ext_b(chips)!SKX_EXT_B_BGA1-IC,TBD!!!F112!VCCD012(34)!!!!
S!PVDDQ_GHJ!U2D1!Y49!@baseboard_fab2_lib.baseboard_fab2(sch_1):page72_i32@chpset_lib.skx_ext_b(chips)!SKX_EXT_B_BGA1-IC,TBD!!!F112!VCCD012(35)!!!!
S!PVDDQ_GHJ!U2D1!Y51!@baseboard_fab2_lib.baseboard_fab2(sch_1):page72_i32@chpset_lib.skx_ext_b(chips)!SKX_EXT_B_BGA1-IC,TBD!!!F112!VCCD012(36)!!!!
S!PVDDQ_GHJ!U2D1!Y53!@baseboard_fab2_lib.baseboard_fab2(sch_1):page72_i32@chpset_lib.skx_ext_b(chips)!SKX_EXT_B_BGA1-IC,TBD!!!F112!VCCD012(37)!!!!
S!PVDDQ_GHJ!U2D1!Y55!@baseboard_fab2_lib.baseboard_fab2(sch_1):page72_i32@chpset_lib.skx_ext_b(chips)!SKX_EXT_B_BGA1-IC,TBD!!!F112!VCCD012(38)!!!!
S!PVDDQ_GHJ!U2D1!Y57!@baseboard_fab2_lib.baseboard_fab2(sch_1):page72_i32@chpset_lib.skx_ext_b(chips)!SKX_EXT_B_BGA1-IC,TBD!!!F112!VCCD012(39)!!!!
S!PVDDQ_GHJ!U2D1!E46!@baseboard_fab2_lib.baseboard_fab2(sch_1):page72_i32@chpset_lib.skx_ext_b(chips)!SKX_EXT_B_BGA1-IC,TBD!!!F112!VCCD012(3)!!!!
S!PVDDQ_GHJ!U2D1!Y59!@baseboard_fab2_lib.baseboard_fab2(sch_1):page72_i32@chpset_lib.skx_ext_b(chips)!SKX_EXT_B_BGA1-IC,TBD!!!F112!VCCD012(40)!!!!
S!PVDDQ_GHJ!U2D1!Y61!@baseboard_fab2_lib.baseboard_fab2(sch_1):page72_i32@chpset_lib.skx_ext_b(chips)!SKX_EXT_B_BGA1-IC,TBD!!!F112!VCCD012(41)!!!!
S!PVDDQ_GHJ!U2D1!Y63!@baseboard_fab2_lib.baseboard_fab2(sch_1):page72_i32@chpset_lib.skx_ext_b(chips)!SKX_EXT_B_BGA1-IC,TBD!!!F112!VCCD012(42)!!!!
S!PVDDQ_GHJ!U2D1!AD45!@baseboard_fab2_lib.baseboard_fab2(sch_1):page72_i32@chpset_lib.skx_ext_b(chips)!SKX_EXT_B_BGA1-IC,TBD!!!F112!VCCD012(43)!!!!
S!PVDDQ_GHJ!U2D1!AF55!@baseboard_fab2_lib.baseboard_fab2(sch_1):page72_i32@chpset_lib.skx_ext_b(chips)!SKX_EXT_B_BGA1-IC,TBD!!!F112!VCCD012(44)!!!!
S!PVDDQ_GHJ!U2D1!AF57!@baseboard_fab2_lib.baseboard_fab2(sch_1):page72_i32@chpset_lib.skx_ext_b(chips)!SKX_EXT_B_BGA1-IC,TBD!!!F112!VCCD012(45)!!!!
S!PVDDQ_GHJ!U2D1!AF59!@baseboard_fab2_lib.baseboard_fab2(sch_1):page72_i32@chpset_lib.skx_ext_b(chips)!SKX_EXT_B_BGA1-IC,TBD!!!F112!VCCD012(46)!!!!
S!PVDDQ_GHJ!U2D1!AF61!@baseboard_fab2_lib.baseboard_fab2(sch_1):page72_i32@chpset_lib.skx_ext_b(chips)!SKX_EXT_B_BGA1-IC,TBD!!!F112!VCCD012(47)!!!!
S!PVDDQ_GHJ!U2D1!AF63!@baseboard_fab2_lib.baseboard_fab2(sch_1):page72_i32@chpset_lib.skx_ext_b(chips)!SKX_EXT_B_BGA1-IC,TBD!!!F112!VCCD012(48)!!!!
S!PVDDQ_GHJ!U2D1!E48!@baseboard_fab2_lib.baseboard_fab2(sch_1):page72_i32@chpset_lib.skx_ext_b(chips)!SKX_EXT_B_BGA1-IC,TBD!!!F112!VCCD012(4)!!!!
S!PVDDQ_GHJ!U2D1!E50!@baseboard_fab2_lib.baseboard_fab2(sch_1):page72_i32@chpset_lib.skx_ext_b(chips)!SKX_EXT_B_BGA1-IC,TBD!!!F112!VCCD012(5)!!!!
S!PVDDQ_GHJ!U2D1!E52!@baseboard_fab2_lib.baseboard_fab2(sch_1):page72_i32@chpset_lib.skx_ext_b(chips)!SKX_EXT_B_BGA1-IC,TBD!!!F112!VCCD012(6)!!!!
S!PVDDQ_GHJ!U2D1!E54!@baseboard_fab2_lib.baseboard_fab2(sch_1):page72_i32@chpset_lib.skx_ext_b(chips)!SKX_EXT_B_BGA1-IC,TBD!!!F112!VCCD012(7)!!!!
S!PVDDQ_GHJ!U2D1!E56!@baseboard_fab2_lib.baseboard_fab2(sch_1):page72_i32@chpset_lib.skx_ext_b(chips)!SKX_EXT_B_BGA1-IC,TBD!!!F112!VCCD012(8)!!!!
S!PVDDQ_GHJ!U2D1!E58!@baseboard_fab2_lib.baseboard_fab2(sch_1):page72_i32@chpset_lib.skx_ext_b(chips)!SKX_EXT_B_BGA1-IC,TBD!!!F112!VCCD012(9)!!!!
S!PVDDQ_GHJ!U2D1!D45!@baseboard_fab2_lib.baseboard_fab2(sch_1):page72_i32@chpset_lib.skx_ext_b(chips)!SKX_EXT_B_BGA1-IC,TBD!!!F112!VCCD012(49)!!!!
S!PVDDQ_GHJ!U2D1!C46!@baseboard_fab2_lib.baseboard_fab2(sch_1):page72_i32@chpset_lib.skx_ext_b(chips)!SKX_EXT_B_BGA1-IC,TBD!!!F112!VCCD012(50)!!!!
S!PVDDQ_GHJ!U2D1!B47!@baseboard_fab2_lib.baseboard_fab2(sch_1):page72_i32@chpset_lib.skx_ext_b(chips)!SKX_EXT_B_BGA1-IC,TBD!!!F112!VCCD012(51)!!!!
S!PVDDQ_KLM!U2D1!EF59!@baseboard_fab2_lib.baseboard_fab2(sch_1):page72_i32@chpset_lib.skx_ext_b(chips)!SKX_EXT_B_BGA1-IC,TBD!!!F112!VCCD345(0)!!!!
S!PVDDQ_KLM!U2D1!EC48!@baseboard_fab2_lib.baseboard_fab2(sch_1):page72_i32@chpset_lib.skx_ext_b(chips)!SKX_EXT_B_BGA1-IC,TBD!!!F112!VCCD345(10)!!!!
S!PVDDQ_KLM!U2D1!EC46!@baseboard_fab2_lib.baseboard_fab2(sch_1):page72_i32@chpset_lib.skx_ext_b(chips)!SKX_EXT_B_BGA1-IC,TBD!!!F112!VCCD345(11)!!!!
S!PVDDQ_KLM!U2D1!DU64!@baseboard_fab2_lib.baseboard_fab2(sch_1):page72_i32@chpset_lib.skx_ext_b(chips)!SKX_EXT_B_BGA1-IC,TBD!!!F112!VCCD345(12)!!!!
S!PVDDQ_KLM!U2D1!DU62!@baseboard_fab2_lib.baseboard_fab2(sch_1):page72_i32@chpset_lib.skx_ext_b(chips)!SKX_EXT_B_BGA1-IC,TBD!!!F112!VCCD345(13)!!!!
S!PVDDQ_KLM!U2D1!DU60!@baseboard_fab2_lib.baseboard_fab2(sch_1):page72_i32@chpset_lib.skx_ext_b(chips)!SKX_EXT_B_BGA1-IC,TBD!!!F112!VCCD345(14)!!!!
S!PVDDQ_KLM!U2D1!DU58!@baseboard_fab2_lib.baseboard_fab2(sch_1):page72_i32@chpset_lib.skx_ext_b(chips)!SKX_EXT_B_BGA1-IC,TBD!!!F112!VCCD345(15)!!!!
S!PVDDQ_KLM!U2D1!DU56!@baseboard_fab2_lib.baseboard_fab2(sch_1):page72_i32@chpset_lib.skx_ext_b(chips)!SKX_EXT_B_BGA1-IC,TBD!!!F112!VCCD345(16)!!!!
S!PVDDQ_KLM!U2D1!DU54!@baseboard_fab2_lib.baseboard_fab2(sch_1):page72_i32@chpset_lib.skx_ext_b(chips)!SKX_EXT_B_BGA1-IC,TBD!!!F112!VCCD345(17)!!!!
S!PVDDQ_KLM!U2D1!DU52!@baseboard_fab2_lib.baseboard_fab2(sch_1):page72_i32@chpset_lib.skx_ext_b(chips)!SKX_EXT_B_BGA1-IC,TBD!!!F112!VCCD345(18)!!!!
S!PVDDQ_KLM!U2D1!DU50!@baseboard_fab2_lib.baseboard_fab2(sch_1):page72_i32@chpset_lib.skx_ext_b(chips)!SKX_EXT_B_BGA1-IC,TBD!!!F112!VCCD345(19)!!!!
S!PVDDQ_KLM!U2D1!EF53!@baseboard_fab2_lib.baseboard_fab2(sch_1):page72_i32@chpset_lib.skx_ext_b(chips)!SKX_EXT_B_BGA1-IC,TBD!!!F112!VCCD345(1)!!!!
S!PVDDQ_KLM!U2D1!DU48!@baseboard_fab2_lib.baseboard_fab2(sch_1):page72_i32@chpset_lib.skx_ext_b(chips)!SKX_EXT_B_BGA1-IC,TBD!!!F112!VCCD345(20)!!!!
S!PVDDQ_KLM!U2D1!DU46!@baseboard_fab2_lib.baseboard_fab2(sch_1):page72_i32@chpset_lib.skx_ext_b(chips)!SKX_EXT_B_BGA1-IC,TBD!!!F112!VCCD345(21)!!!!
S!PVDDQ_KLM!U2D1!DL62!@baseboard_fab2_lib.baseboard_fab2(sch_1):page72_i32@chpset_lib.skx_ext_b(chips)!SKX_EXT_B_BGA1-IC,TBD!!!F112!VCCD345(22)!!!!
S!PVDDQ_KLM!U2D1!DL60!@baseboard_fab2_lib.baseboard_fab2(sch_1):page72_i32@chpset_lib.skx_ext_b(chips)!SKX_EXT_B_BGA1-IC,TBD!!!F112!VCCD345(23)!!!!
S!PVDDQ_KLM!U2D1!DL58!@baseboard_fab2_lib.baseboard_fab2(sch_1):page72_i32@chpset_lib.skx_ext_b(chips)!SKX_EXT_B_BGA1-IC,TBD!!!F112!VCCD345(24)!!!!
S!PVDDQ_KLM!U2D1!DL56!@baseboard_fab2_lib.baseboard_fab2(sch_1):page72_i32@chpset_lib.skx_ext_b(chips)!SKX_EXT_B_BGA1-IC,TBD!!!F112!VCCD345(25)!!!!
S!PVDDQ_KLM!U2D1!DL54!@baseboard_fab2_lib.baseboard_fab2(sch_1):page72_i32@chpset_lib.skx_ext_b(chips)!SKX_EXT_B_BGA1-IC,TBD!!!F112!VCCD345(26)!!!!
S!PVDDQ_KLM!U2D1!DL52!@baseboard_fab2_lib.baseboard_fab2(sch_1):page72_i32@chpset_lib.skx_ext_b(chips)!SKX_EXT_B_BGA1-IC,TBD!!!F112!VCCD345(27)!!!!
S!PVDDQ_KLM!U2D1!DL50!@baseboard_fab2_lib.baseboard_fab2(sch_1):page72_i32@chpset_lib.skx_ext_b(chips)!SKX_EXT_B_BGA1-IC,TBD!!!F112!VCCD345(28)!!!!
S!PVDDQ_KLM!U2D1!DL48!@baseboard_fab2_lib.baseboard_fab2(sch_1):page72_i32@chpset_lib.skx_ext_b(chips)!SKX_EXT_B_BGA1-IC,TBD!!!F112!VCCD345(29)!!!!
S!PVDDQ_KLM!U2D1!EF49!@baseboard_fab2_lib.baseboard_fab2(sch_1):page72_i32@chpset_lib.skx_ext_b(chips)!SKX_EXT_B_BGA1-IC,TBD!!!F112!VCCD345(2)!!!!
S!PVDDQ_KLM!U2D1!DL46!@baseboard_fab2_lib.baseboard_fab2(sch_1):page72_i32@chpset_lib.skx_ext_b(chips)!SKX_EXT_B_BGA1-IC,TBD!!!F112!VCCD345(30)!!!!
S!PVDDQ_KLM!U2D1!DJ64!@baseboard_fab2_lib.baseboard_fab2(sch_1):page72_i32@chpset_lib.skx_ext_b(chips)!SKX_EXT_B_BGA1-IC,TBD!!!F112!VCCD345(31)!!!!
S!PVDDQ_KLM!U2D1!DH63!@baseboard_fab2_lib.baseboard_fab2(sch_1):page72_i32@chpset_lib.skx_ext_b(chips)!SKX_EXT_B_BGA1-IC,TBD!!!F112!VCCD345(32)!!!!
S!PVDDQ_KLM!U2D1!DH61!@baseboard_fab2_lib.baseboard_fab2(sch_1):page72_i32@chpset_lib.skx_ext_b(chips)!SKX_EXT_B_BGA1-IC,TBD!!!F112!VCCD345(33)!!!!
S!PVDDQ_KLM!U2D1!DH59!@baseboard_fab2_lib.baseboard_fab2(sch_1):page72_i32@chpset_lib.skx_ext_b(chips)!SKX_EXT_B_BGA1-IC,TBD!!!F112!VCCD345(34)!!!!
S!PVDDQ_KLM!U2D1!DH57!@baseboard_fab2_lib.baseboard_fab2(sch_1):page72_i32@chpset_lib.skx_ext_b(chips)!SKX_EXT_B_BGA1-IC,TBD!!!F112!VCCD345(35)!!!!
S!PVDDQ_KLM!U2D1!DH55!@baseboard_fab2_lib.baseboard_fab2(sch_1):page72_i32@chpset_lib.skx_ext_b(chips)!SKX_EXT_B_BGA1-IC,TBD!!!F112!VCCD345(36)!!!!
S!PVDDQ_KLM!U2D1!DH53!@baseboard_fab2_lib.baseboard_fab2(sch_1):page72_i32@chpset_lib.skx_ext_b(chips)!SKX_EXT_B_BGA1-IC,TBD!!!F112!VCCD345(37)!!!!
S!PVDDQ_KLM!U2D1!DH51!@baseboard_fab2_lib.baseboard_fab2(sch_1):page72_i32@chpset_lib.skx_ext_b(chips)!SKX_EXT_B_BGA1-IC,TBD!!!F112!VCCD345(38)!!!!
S!PVDDQ_KLM!U2D1!DH49!@baseboard_fab2_lib.baseboard_fab2(sch_1):page72_i32@chpset_lib.skx_ext_b(chips)!SKX_EXT_B_BGA1-IC,TBD!!!F112!VCCD345(39)!!!!
S!PVDDQ_KLM!U2D1!EC62!@baseboard_fab2_lib.baseboard_fab2(sch_1):page72_i32@chpset_lib.skx_ext_b(chips)!SKX_EXT_B_BGA1-IC,TBD!!!F112!VCCD345(3)!!!!
S!PVDDQ_KLM!U2D1!DH47!@baseboard_fab2_lib.baseboard_fab2(sch_1):page72_i32@chpset_lib.skx_ext_b(chips)!SKX_EXT_B_BGA1-IC,TBD!!!F112!VCCD345(40)!!!!
S!PVDDQ_KLM!U2D1!DH45!@baseboard_fab2_lib.baseboard_fab2(sch_1):page72_i32@chpset_lib.skx_ext_b(chips)!SKX_EXT_B_BGA1-IC,TBD!!!F112!VCCD345(41)!!!!
S!PVDDQ_KLM!U2D1!DD45!@baseboard_fab2_lib.baseboard_fab2(sch_1):page72_i32@chpset_lib.skx_ext_b(chips)!SKX_EXT_B_BGA1-IC,TBD!!!F112!VCCD345(42)!!!!
S!PVDDQ_KLM!U2D1!DB63!@baseboard_fab2_lib.baseboard_fab2(sch_1):page72_i32@chpset_lib.skx_ext_b(chips)!SKX_EXT_B_BGA1-IC,TBD!!!F112!VCCD345(43)!!!!
S!PVDDQ_KLM!U2D1!DB61!@baseboard_fab2_lib.baseboard_fab2(sch_1):page72_i32@chpset_lib.skx_ext_b(chips)!SKX_EXT_B_BGA1-IC,TBD!!!F112!VCCD345(44)!!!!
S!PVDDQ_KLM!U2D1!DB59!@baseboard_fab2_lib.baseboard_fab2(sch_1):page72_i32@chpset_lib.skx_ext_b(chips)!SKX_EXT_B_BGA1-IC,TBD!!!F112!VCCD345(45)!!!!
S!PVDDQ_KLM!U2D1!DB57!@baseboard_fab2_lib.baseboard_fab2(sch_1):page72_i32@chpset_lib.skx_ext_b(chips)!SKX_EXT_B_BGA1-IC,TBD!!!F112!VCCD345(46)!!!!
S!PVDDQ_KLM!U2D1!DB55!@baseboard_fab2_lib.baseboard_fab2(sch_1):page72_i32@chpset_lib.skx_ext_b(chips)!SKX_EXT_B_BGA1-IC,TBD!!!F112!VCCD345(47)!!!!
S!PVDDQ_KLM!U2D1!DB53!@baseboard_fab2_lib.baseboard_fab2(sch_1):page72_i32@chpset_lib.skx_ext_b(chips)!SKX_EXT_B_BGA1-IC,TBD!!!F112!VCCD345(48)!!!!
S!PVDDQ_KLM!U2D1!EC60!@baseboard_fab2_lib.baseboard_fab2(sch_1):page72_i32@chpset_lib.skx_ext_b(chips)!SKX_EXT_B_BGA1-IC,TBD!!!F112!VCCD345(4)!!!!
S!PVDDQ_KLM!U2D1!EC58!@baseboard_fab2_lib.baseboard_fab2(sch_1):page72_i32@chpset_lib.skx_ext_b(chips)!SKX_EXT_B_BGA1-IC,TBD!!!F112!VCCD345(5)!!!!
S!PVDDQ_KLM!U2D1!EC56!@baseboard_fab2_lib.baseboard_fab2(sch_1):page72_i32@chpset_lib.skx_ext_b(chips)!SKX_EXT_B_BGA1-IC,TBD!!!F112!VCCD345(6)!!!!
S!PVDDQ_KLM!U2D1!EC54!@baseboard_fab2_lib.baseboard_fab2(sch_1):page72_i32@chpset_lib.skx_ext_b(chips)!SKX_EXT_B_BGA1-IC,TBD!!!F112!VCCD345(7)!!!!
S!PVDDQ_KLM!U2D1!EC52!@baseboard_fab2_lib.baseboard_fab2(sch_1):page72_i32@chpset_lib.skx_ext_b(chips)!SKX_EXT_B_BGA1-IC,TBD!!!F112!VCCD345(8)!!!!
S!PVDDQ_KLM!U2D1!EC50!@baseboard_fab2_lib.baseboard_fab2(sch_1):page72_i32@chpset_lib.skx_ext_b(chips)!SKX_EXT_B_BGA1-IC,TBD!!!F112!VCCD345(9)!!!!
S!PVDDQ_KLM!U2D1!EF45!@baseboard_fab2_lib.baseboard_fab2(sch_1):page72_i32@chpset_lib.skx_ext_b(chips)!SKX_EXT_B_BGA1-IC,TBD!!!F112!VCCD345(49)!!!!
S!PVDDQ_KLM!U2D1!EE44!@baseboard_fab2_lib.baseboard_fab2(sch_1):page72_i32@chpset_lib.skx_ext_b(chips)!SKX_EXT_B_BGA1-IC,TBD!!!F112!VCCD345(50)!!!!
S!PVCCIOMCP_CPU1!U2D1!BT11!@baseboard_fab2_lib.baseboard_fab2(sch_1):page72_i33@chpset_lib.skx_ext_b(chips)!SKX_EXT_B_BGA1-IC,TBD!!!F111!CD_VCCP(7)!!!!
S!PVCCIOMCP_CPU1!U2D1!BR12!@baseboard_fab2_lib.baseboard_fab2(sch_1):page72_i33@chpset_lib.skx_ext_b(chips)!SKX_EXT_B_BGA1-IC,TBD!!!F111!CD_VCCP(9)!!!!
S!PVCCIOMCP_CPU1!U2D1!BP13!@baseboard_fab2_lib.baseboard_fab2(sch_1):page72_i33@chpset_lib.skx_ext_b(chips)!SKX_EXT_B_BGA1-IC,TBD!!!F111!CD_VCCP(11)!!!!
S!PVCCIOMCP_CPU1!U2D1!BP11!@baseboard_fab2_lib.baseboard_fab2(sch_1):page72_i33@chpset_lib.skx_ext_b(chips)!SKX_EXT_B_BGA1-IC,TBD!!!F111!CD_VCCP(12)!!!!
S!PVCCIOMCP_CPU1!U2D1!BN12!@baseboard_fab2_lib.baseboard_fab2(sch_1):page72_i33@chpset_lib.skx_ext_b(chips)!SKX_EXT_B_BGA1-IC,TBD!!!F111!CD_VCCP(14)!!!!
S!PVCCIOMCP_CPU1!U2D1!BM11!@baseboard_fab2_lib.baseboard_fab2(sch_1):page72_i33@chpset_lib.skx_ext_b(chips)!SKX_EXT_B_BGA1-IC,TBD!!!F111!CD_VCCP(15)!!!!
S!P1V8_MCP_CPU1!U2D1!BY27!@baseboard_fab2_lib.baseboard_fab2(sch_1):page72_i33@chpset_lib.skx_ext_b(chips)!SKX_EXT_B_BGA1-IC,TBD!!!F111!CD_VCCIN(3)!!!!
S!P1V8_MCP_CPU1!U2D1!BV27!@baseboard_fab2_lib.baseboard_fab2(sch_1):page72_i33@chpset_lib.skx_ext_b(chips)!SKX_EXT_B_BGA1-IC,TBD!!!F111!CD_VCCIN(2)!!!!
S!P1V8_MCP_CPU1!U2D1!BU26!@baseboard_fab2_lib.baseboard_fab2(sch_1):page72_i33@chpset_lib.skx_ext_b(chips)!SKX_EXT_B_BGA1-IC,TBD!!!F111!CD_VCCIN(1)!!!!
S!P1V8_MCP_CPU1!U2D1!BT27!@baseboard_fab2_lib.baseboard_fab2(sch_1):page72_i33@chpset_lib.skx_ext_b(chips)!SKX_EXT_B_BGA1-IC,TBD!!!F111!CD_VCCIN(0)!!!!
S!PVPP_GHJ!U2D1!B11!@baseboard_fab2_lib.baseboard_fab2(sch_1):page72_i33@chpset_lib.skx_ext_b(chips)!SKX_EXT_B_BGA1-IC,TBD!!!F111!CD_VPP(0)!!!!
S!PVPP_GHJ!U2D1!A8!@baseboard_fab2_lib.baseboard_fab2(sch_1):page72_i33@chpset_lib.skx_ext_b(chips)!SKX_EXT_B_BGA1-IC,TBD!!!F111!CD_VPP(3)!!!!
S!PVPP_GHJ!U2D1!A12!@baseboard_fab2_lib.baseboard_fab2(sch_1):page72_i33@chpset_lib.skx_ext_b(chips)!SKX_EXT_B_BGA1-IC,TBD!!!F111!CD_VPP(1)!!!!
S!PVPP_GHJ!U2D1!A10!@baseboard_fab2_lib.baseboard_fab2(sch_1):page72_i33@chpset_lib.skx_ext_b(chips)!SKX_EXT_B_BGA1-IC,TBD!!!F111!CD_VPP(2)!!!!
S!PVCCIOMCP_CPU1!U2D1!BV15!@baseboard_fab2_lib.baseboard_fab2(sch_1):page72_i33@chpset_lib.skx_ext_b(chips)!SKX_EXT_B_BGA1-IC,TBD!!!F111!CD_VCCP(0)!!!!
S!PVCCIOMCP_CPU1!U2D1!BV13!@baseboard_fab2_lib.baseboard_fab2(sch_1):page72_i33@chpset_lib.skx_ext_b(chips)!SKX_EXT_B_BGA1-IC,TBD!!!F111!CD_VCCP(1)!!!!
S!PVCCIOMCP_CPU1!U2D1!BV11!@baseboard_fab2_lib.baseboard_fab2(sch_1):page72_i33@chpset_lib.skx_ext_b(chips)!SKX_EXT_B_BGA1-IC,TBD!!!F111!CD_VCCP(2)!!!!
S!PVCCIOMCP_CPU1!U2D1!BU14!@baseboard_fab2_lib.baseboard_fab2(sch_1):page72_i33@chpset_lib.skx_ext_b(chips)!SKX_EXT_B_BGA1-IC,TBD!!!F111!CD_VCCP(3)!!!!
S!PVCCIOMCP_CPU1!U2D1!BU12!@baseboard_fab2_lib.baseboard_fab2(sch_1):page72_i33@chpset_lib.skx_ext_b(chips)!SKX_EXT_B_BGA1-IC,TBD!!!F111!CD_VCCP(4)!!!!
S!PVCCIOMCP_CPU1!U2D1!BT15!@baseboard_fab2_lib.baseboard_fab2(sch_1):page72_i33@chpset_lib.skx_ext_b(chips)!SKX_EXT_B_BGA1-IC,TBD!!!F111!CD_VCCP(5)!!!!
S!PVCCIOMCP_CPU1!U2D1!BT13!@baseboard_fab2_lib.baseboard_fab2(sch_1):page72_i33@chpset_lib.skx_ext_b(chips)!SKX_EXT_B_BGA1-IC,TBD!!!F111!CD_VCCP(6)!!!!
S!PVCCIOMCP_CPU1!U2D1!BR14!@baseboard_fab2_lib.baseboard_fab2(sch_1):page72_i33@chpset_lib.skx_ext_b(chips)!SKX_EXT_B_BGA1-IC,TBD!!!F111!CD_VCCP(8)!!!!
S!PVCCIOMCP_CPU1!U2D1!BP15!@baseboard_fab2_lib.baseboard_fab2(sch_1):page72_i33@chpset_lib.skx_ext_b(chips)!SKX_EXT_B_BGA1-IC,TBD!!!F111!CD_VCCP(10)!!!!
S!PVCCIOMCP_CPU1!U2D1!BN14!@baseboard_fab2_lib.baseboard_fab2(sch_1):page72_i33@chpset_lib.skx_ext_b(chips)!SKX_EXT_B_BGA1-IC,TBD!!!F111!CD_VCCP(13)!!!!
S!PVCCMCP_CPU1!U2D1!BL14!@baseboard_fab2_lib.baseboard_fab2(sch_1):page72_i33@chpset_lib.skx_ext_b(chips)!SKX_EXT_B_BGA1-IC,TBD!!!F111!CD_VCC_CORE(0)!!!!
S!PVCCMCP_CPU1!U2D1!BE14!@baseboard_fab2_lib.baseboard_fab2(sch_1):page72_i33@chpset_lib.skx_ext_b(chips)!SKX_EXT_B_BGA1-IC,TBD!!!F111!CD_VCC_CORE(10)!!!!
S!PVCCMCP_CPU1!U2D1!BE12!@baseboard_fab2_lib.baseboard_fab2(sch_1):page72_i33@chpset_lib.skx_ext_b(chips)!SKX_EXT_B_BGA1-IC,TBD!!!F111!CD_VCC_CORE(11)!!!!
S!PVCCMCP_CPU1!U2D1!BD13!@baseboard_fab2_lib.baseboard_fab2(sch_1):page72_i33@chpset_lib.skx_ext_b(chips)!SKX_EXT_B_BGA1-IC,TBD!!!F111!CD_VCC_CORE(12)!!!!
S!PVCCMCP_CPU1!U2D1!BK15!@baseboard_fab2_lib.baseboard_fab2(sch_1):page72_i33@chpset_lib.skx_ext_b(chips)!SKX_EXT_B_BGA1-IC,TBD!!!F111!CD_VCC_CORE(1)!!!!
S!PVCCMCP_CPU1!U2D1!BK13!@baseboard_fab2_lib.baseboard_fab2(sch_1):page72_i33@chpset_lib.skx_ext_b(chips)!SKX_EXT_B_BGA1-IC,TBD!!!F111!CD_VCC_CORE(2)!!!!
S!PVCCMCP_CPU1!U2D1!BJ14!@baseboard_fab2_lib.baseboard_fab2(sch_1):page72_i33@chpset_lib.skx_ext_b(chips)!SKX_EXT_B_BGA1-IC,TBD!!!F111!CD_VCC_CORE(3)!!!!
S!PVCCMCP_CPU1!U2D1!BJ12!@baseboard_fab2_lib.baseboard_fab2(sch_1):page72_i33@chpset_lib.skx_ext_b(chips)!SKX_EXT_B_BGA1-IC,TBD!!!F111!CD_VCC_CORE(4)!!!!
S!PVCCMCP_CPU1!U2D1!BH13!@baseboard_fab2_lib.baseboard_fab2(sch_1):page72_i33@chpset_lib.skx_ext_b(chips)!SKX_EXT_B_BGA1-IC,TBD!!!F111!CD_VCC_CORE(5)!!!!
S!PVCCMCP_CPU1!U2D1!BG14!@baseboard_fab2_lib.baseboard_fab2(sch_1):page72_i33@chpset_lib.skx_ext_b(chips)!SKX_EXT_B_BGA1-IC,TBD!!!F111!CD_VCC_CORE(6)!!!!
S!PVCCMCP_CPU1!U2D1!BG12!@baseboard_fab2_lib.baseboard_fab2(sch_1):page72_i33@chpset_lib.skx_ext_b(chips)!SKX_EXT_B_BGA1-IC,TBD!!!F111!CD_VCC_CORE(7)!!!!
S!PVCCMCP_CPU1!U2D1!BF13!@baseboard_fab2_lib.baseboard_fab2(sch_1):page72_i33@chpset_lib.skx_ext_b(chips)!SKX_EXT_B_BGA1-IC,TBD!!!F111!CD_VCC_CORE(8)!!!!
S!PVCCMCP_CPU1!U2D1!BF11!@baseboard_fab2_lib.baseboard_fab2(sch_1):page72_i33@chpset_lib.skx_ext_b(chips)!SKX_EXT_B_BGA1-IC,TBD!!!F111!CD_VCC_CORE(9)!!!!
S!PVCCIO_CPU1!U2D1!BC26!@baseboard_fab2_lib.baseboard_fab2(sch_1):page72_i33@chpset_lib.skx_ext_b(chips)!SKX_EXT_B_BGA1-IC,TBD!!!F111!VCCIO(75)!!!!
S!PVCCIO_CPU1!U2D1!BB27!@baseboard_fab2_lib.baseboard_fab2(sch_1):page72_i33@chpset_lib.skx_ext_b(chips)!SKX_EXT_B_BGA1-IC,TBD!!!F111!VCCIO(76)!!!!
S!PVCCIO_CPU1!U2D1!BA26!@baseboard_fab2_lib.baseboard_fab2(sch_1):page72_i33@chpset_lib.skx_ext_b(chips)!SKX_EXT_B_BGA1-IC,TBD!!!F111!VCCIO(77)!!!!
S!PVCCIO_CPU1!U2D1!AY27!@baseboard_fab2_lib.baseboard_fab2(sch_1):page72_i33@chpset_lib.skx_ext_b(chips)!SKX_EXT_B_BGA1-IC,TBD!!!F111!VCCIO(78)!!!!
S!PVCCIO_CPU1!U2D1!AW26!@baseboard_fab2_lib.baseboard_fab2(sch_1):page72_i33@chpset_lib.skx_ext_b(chips)!SKX_EXT_B_BGA1-IC,TBD!!!F111!VCCIO(79)!!!!
S!PVCCIO_CPU1!U2D1!AV27!@baseboard_fab2_lib.baseboard_fab2(sch_1):page72_i33@chpset_lib.skx_ext_b(chips)!SKX_EXT_B_BGA1-IC,TBD!!!F111!VCCIO(80)!!!!
S!PVCCIO_CPU1!U2D1!CF27!@baseboard_fab2_lib.baseboard_fab2(sch_1):page72_i33@chpset_lib.skx_ext_b(chips)!SKX_EXT_B_BGA1-IC,TBD!!!F111!VCCIO(81)!!!!
S!PVCCIO_CPU1!U2D1!CD27!@baseboard_fab2_lib.baseboard_fab2(sch_1):page72_i33@chpset_lib.skx_ext_b(chips)!SKX_EXT_B_BGA1-IC,TBD!!!F111!VCCIO(82)!!!!
S!PVCCIO_CPU1!U2D1!CC26!@baseboard_fab2_lib.baseboard_fab2(sch_1):page72_i33@chpset_lib.skx_ext_b(chips)!SKX_EXT_B_BGA1-IC,TBD!!!F111!VCCIO(83)!!!!
S!P3V3_STBY!U2D1!CY55!@baseboard_fab2_lib.baseboard_fab2(sch_1):page72_i33@chpset_lib.skx_ext_b(chips)!SKX_EXT_B_BGA1-IC,TBD!!!F111!VCC33!!!!
S!PVCCIO_CPU1!U2D1!EE10!@baseboard_fab2_lib.baseboard_fab2(sch_1):page73_i107@chpset_lib.skx_ext_b(chips)!SKX_EXT_B_BGA1-IC,TBD!!!F110!VCCIO(0)!!!!
S!PVCCIO_CPU1!U2D1!CG14!@baseboard_fab2_lib.baseboard_fab2(sch_1):page73_i107@chpset_lib.skx_ext_b(chips)!SKX_EXT_B_BGA1-IC,TBD!!!F110!VCCIO(10)!!!!
S!PVCCIO_CPU1!U2D1!CL20!@baseboard_fab2_lib.baseboard_fab2(sch_1):page73_i107@chpset_lib.skx_ext_b(chips)!SKX_EXT_B_BGA1-IC,TBD!!!F110!VCCIO(11)!!!!
S!PVCCIO_CPU1!U2D1!CP13!@baseboard_fab2_lib.baseboard_fab2(sch_1):page73_i107@chpset_lib.skx_ext_b(chips)!SKX_EXT_B_BGA1-IC,TBD!!!F110!VCCIO(12)!!!!
S!PVCCIO_CPU1!U2D1!DE14!@baseboard_fab2_lib.baseboard_fab2(sch_1):page73_i107@chpset_lib.skx_ext_b(chips)!SKX_EXT_B_BGA1-IC,TBD!!!F110!VCCIO(13)!!!!
S!PVCCIO_CPU1!U2D1!DC18!@baseboard_fab2_lib.baseboard_fab2(sch_1):page73_i107@chpset_lib.skx_ext_b(chips)!SKX_EXT_B_BGA1-IC,TBD!!!F110!VCCIO(14)!!!!
S!PVCCIO_CPU1!U2D1!CY17!@baseboard_fab2_lib.baseboard_fab2(sch_1):page73_i107@chpset_lib.skx_ext_b(chips)!SKX_EXT_B_BGA1-IC,TBD!!!F110!VCCIO(15)!!!!
S!PVCCIO_CPU1!U2D1!CU18!@baseboard_fab2_lib.baseboard_fab2(sch_1):page73_i107@chpset_lib.skx_ext_b(chips)!SKX_EXT_B_BGA1-IC,TBD!!!F110!VCCIO(16)!!!!
S!PVCCIO_CPU1!U2D1!CV21!@baseboard_fab2_lib.baseboard_fab2(sch_1):page73_i107@chpset_lib.skx_ext_b(chips)!SKX_EXT_B_BGA1-IC,TBD!!!F110!VCCIO(17)!!!!
S!PVCCIO_CPU1!U2D1!CU12!@baseboard_fab2_lib.baseboard_fab2(sch_1):page73_i107@chpset_lib.skx_ext_b(chips)!SKX_EXT_B_BGA1-IC,TBD!!!F110!VCCIO(18)!!!!
S!PVCCIO_CPU1!U2D1!CN6!@baseboard_fab2_lib.baseboard_fab2(sch_1):page73_i107@chpset_lib.skx_ext_b(chips)!SKX_EXT_B_BGA1-IC,TBD!!!F110!VCCIO(19)!!!!
S!PVCCIO_CPU1!U2D1!AE10!@baseboard_fab2_lib.baseboard_fab2(sch_1):page73_i107@chpset_lib.skx_ext_b(chips)!SKX_EXT_B_BGA1-IC,TBD!!!F110!VCCIO(1)!!!!
S!PVCCIO_CPU1!U2D1!CM15!@baseboard_fab2_lib.baseboard_fab2(sch_1):page72_i33@chpset_lib.skx_ext_b(chips)!SKX_EXT_B_BGA1-IC,TBD!!!F111!VCCIO(20)!!!!
S!PVCCIO_CPU1!U2D1!CL12!@baseboard_fab2_lib.baseboard_fab2(sch_1):page72_i33@chpset_lib.skx_ext_b(chips)!SKX_EXT_B_BGA1-IC,TBD!!!F111!VCCIO(21)!!!!
S!PVCCIO_CPU1!U2D1!CK5!@baseboard_fab2_lib.baseboard_fab2(sch_1):page72_i33@chpset_lib.skx_ext_b(chips)!SKX_EXT_B_BGA1-IC,TBD!!!F111!VCCIO(22)!!!!
S!PVCCIO_CPU1!U2D1!CV7!@baseboard_fab2_lib.baseboard_fab2(sch_1):page72_i33@chpset_lib.skx_ext_b(chips)!SKX_EXT_B_BGA1-IC,TBD!!!F111!VCCIO(23)!!!!
S!PVCCIO_CPU1!U2D1!CH9!@baseboard_fab2_lib.baseboard_fab2(sch_1):page72_i33@chpset_lib.skx_ext_b(chips)!SKX_EXT_B_BGA1-IC,TBD!!!F111!VCCIO(24)!!!!
S!PVCCIO_CPU1!U2D1!D7!@baseboard_fab2_lib.baseboard_fab2(sch_1):page72_i33@chpset_lib.skx_ext_b(chips)!SKX_EXT_B_BGA1-IC,TBD!!!F111!VCCIO(25)!!!!
S!PVCCIO_CPU1!U2D1!CE18!@baseboard_fab2_lib.baseboard_fab2(sch_1):page72_i33@chpset_lib.skx_ext_b(chips)!SKX_EXT_B_BGA1-IC,TBD!!!F111!VCCIO(26)!!!!
S!PVCCIO_CPU1!U2D1!CD9!@baseboard_fab2_lib.baseboard_fab2(sch_1):page72_i33@chpset_lib.skx_ext_b(chips)!SKX_EXT_B_BGA1-IC,TBD!!!F111!VCCIO(27)!!!!
S!PVCCIO_CPU1!U2D1!CB17!@baseboard_fab2_lib.baseboard_fab2(sch_1):page72_i33@chpset_lib.skx_ext_b(chips)!SKX_EXT_B_BGA1-IC,TBD!!!F111!VCCIO(28)!!!!
S!PVCCIO_CPU1!U2D1!CB13!@baseboard_fab2_lib.baseboard_fab2(sch_1):page72_i33@chpset_lib.skx_ext_b(chips)!SKX_EXT_B_BGA1-IC,TBD!!!F111!VCCIO(29)!!!!
S!PVCCIO_CPU1!U2D1!AF5!@baseboard_fab2_lib.baseboard_fab2(sch_1):page73_i107@chpset_lib.skx_ext_b(chips)!SKX_EXT_B_BGA1-IC,TBD!!!F110!VCCIO(2)!!!!
S!PVCCIO_CPU1!U2D1!BP25!@baseboard_fab2_lib.baseboard_fab2(sch_1):page72_i33@chpset_lib.skx_ext_b(chips)!SKX_EXT_B_BGA1-IC,TBD!!!F111!VCCIO(30)!!!!
S!PVCCIO_CPU1!U2D1!BJ24!@baseboard_fab2_lib.baseboard_fab2(sch_1):page72_i33@chpset_lib.skx_ext_b(chips)!SKX_EXT_B_BGA1-IC,TBD!!!F111!VCCIO(31)!!!!
S!PVCCIO_CPU1!U2D1!BF23!@baseboard_fab2_lib.baseboard_fab2(sch_1):page72_i33@chpset_lib.skx_ext_b(chips)!SKX_EXT_B_BGA1-IC,TBD!!!F111!VCCIO(32)!!!!
S!PVCCIO_CPU1!U2D1!DA14!@baseboard_fab2_lib.baseboard_fab2(sch_1):page72_i33@chpset_lib.skx_ext_b(chips)!SKX_EXT_B_BGA1-IC,TBD!!!F111!VCCIO(33)!!!!
S!PVCCIO_CPU1!U2D1!BB5!@baseboard_fab2_lib.baseboard_fab2(sch_1):page72_i33@chpset_lib.skx_ext_b(chips)!SKX_EXT_B_BGA1-IC,TBD!!!F111!VCCIO(34)!!!!
S!PVCCIO_CPU1!U2D1!BA24!@baseboard_fab2_lib.baseboard_fab2(sch_1):page72_i33@chpset_lib.skx_ext_b(chips)!SKX_EXT_B_BGA1-IC,TBD!!!F111!VCCIO(35)!!!!
S!PVCCIO_CPU1!U2D1!AY11!@baseboard_fab2_lib.baseboard_fab2(sch_1):page72_i33@chpset_lib.skx_ext_b(chips)!SKX_EXT_B_BGA1-IC,TBD!!!F111!VCCIO(36)!!!!
S!PVCCIO_CPU1!U2D1!AW6!@baseboard_fab2_lib.baseboard_fab2(sch_1):page72_i33@chpset_lib.skx_ext_b(chips)!SKX_EXT_B_BGA1-IC,TBD!!!F111!VCCIO(37)!!!!
S!PVCCIO_CPU1!U2D1!AT11!@baseboard_fab2_lib.baseboard_fab2(sch_1):page72_i33@chpset_lib.skx_ext_b(chips)!SKX_EXT_B_BGA1-IC,TBD!!!F111!VCCIO(38)!!!!
S!PVCCIO_CPU1!U2D1!DD7!@baseboard_fab2_lib.baseboard_fab2(sch_1):page72_i33@chpset_lib.skx_ext_b(chips)!SKX_EXT_B_BGA1-IC,TBD!!!F111!VCCIO(39)!!!!
S!PVCCIO_CPU1!U2D1!DV11!@baseboard_fab2_lib.baseboard_fab2(sch_1):page73_i107@chpset_lib.skx_ext_b(chips)!SKX_EXT_B_BGA1-IC,TBD!!!F110!VCCIO(3)!!!!
S!PVCCIO_CPU1!U2D1!AN10!@baseboard_fab2_lib.baseboard_fab2(sch_1):page72_i33@chpset_lib.skx_ext_b(chips)!SKX_EXT_B_BGA1-IC,TBD!!!F111!VCCIO(40)!!!!
S!PVCCIO_CPU1!U2D1!DF13!@baseboard_fab2_lib.baseboard_fab2(sch_1):page72_i33@chpset_lib.skx_ext_b(chips)!SKX_EXT_B_BGA1-IC,TBD!!!F111!VCCIO(41)!!!!
S!PVCCIO_CPU1!U2D1!AH9!@baseboard_fab2_lib.baseboard_fab2(sch_1):page72_i33@chpset_lib.skx_ext_b(chips)!SKX_EXT_B_BGA1-IC,TBD!!!F111!VCCIO(42)!!!!
S!PVCCIO_CPU1!U2D1!AC4!@baseboard_fab2_lib.baseboard_fab2(sch_1):page72_i33@chpset_lib.skx_ext_b(chips)!SKX_EXT_B_BGA1-IC,TBD!!!F111!VCCIO(43)!!!!
S!PVCCIO_CPU1!U2D1!AC20!@baseboard_fab2_lib.baseboard_fab2(sch_1):page72_i33@chpset_lib.skx_ext_b(chips)!SKX_EXT_B_BGA1-IC,TBD!!!F111!VCCIO(44)!!!!
S!PVCCIO_CPU1!U2D1!AA10!@baseboard_fab2_lib.baseboard_fab2(sch_1):page72_i33@chpset_lib.skx_ext_b(chips)!SKX_EXT_B_BGA1-IC,TBD!!!F111!VCCIO(45)!!!!
S!PVCCIO_CPU1!U2D1!W6!@baseboard_fab2_lib.baseboard_fab2(sch_1):page72_i33@chpset_lib.skx_ext_b(chips)!SKX_EXT_B_BGA1-IC,TBD!!!F111!VCCIO(46)!!!!
S!PVCCIO_CPU1!U2D1!W4!@baseboard_fab2_lib.baseboard_fab2(sch_1):page72_i33@chpset_lib.skx_ext_b(chips)!SKX_EXT_B_BGA1-IC,TBD!!!F111!VCCIO(47)!!!!
S!PVCCIO_CPU1!U2D1!DF21!@baseboard_fab2_lib.baseboard_fab2(sch_1):page72_i33@chpset_lib.skx_ext_b(chips)!SKX_EXT_B_BGA1-IC,TBD!!!F111!VCCIO(48)!!!!
S!PVCCIO_CPU1!U2D1!U14!@baseboard_fab2_lib.baseboard_fab2(sch_1):page72_i33@chpset_lib.skx_ext_b(chips)!SKX_EXT_B_BGA1-IC,TBD!!!F111!VCCIO(49)!!!!
S!PVCCIO_CPU1!U2D1!AM5!@baseboard_fab2_lib.baseboard_fab2(sch_1):page73_i107@chpset_lib.skx_ext_b(chips)!SKX_EXT_B_BGA1-IC,TBD!!!F110!VCCIO(4)!!!!
S!PVCCIO_CPU1!U2D1!T3!@baseboard_fab2_lib.baseboard_fab2(sch_1):page72_i33@chpset_lib.skx_ext_b(chips)!SKX_EXT_B_BGA1-IC,TBD!!!F111!VCCIO(50)!!!!
S!PVCCIO_CPU1!U2D1!P5!@baseboard_fab2_lib.baseboard_fab2(sch_1):page72_i33@chpset_lib.skx_ext_b(chips)!SKX_EXT_B_BGA1-IC,TBD!!!F111!VCCIO(51)!!!!
S!PVCCIO_CPU1!U2D1!M21!@baseboard_fab2_lib.baseboard_fab2(sch_1):page72_i33@chpset_lib.skx_ext_b(chips)!SKX_EXT_B_BGA1-IC,TBD!!!F111!VCCIO(52)!!!!
S!PVCCIO_CPU1!U2D1!M11!@baseboard_fab2_lib.baseboard_fab2(sch_1):page72_i33@chpset_lib.skx_ext_b(chips)!SKX_EXT_B_BGA1-IC,TBD!!!F111!VCCIO(53)!!!!
S!PVCCIO_CPU1!U2D1!DG8!@baseboard_fab2_lib.baseboard_fab2(sch_1):page72_i33@chpset_lib.skx_ext_b(chips)!SKX_EXT_B_BGA1-IC,TBD!!!F111!VCCIO(54)!!!!
S!PVCCIO_CPU1!U2D1!DH7!@baseboard_fab2_lib.baseboard_fab2(sch_1):page72_i33@chpset_lib.skx_ext_b(chips)!SKX_EXT_B_BGA1-IC,TBD!!!F111!VCCIO(55)!!!!
S!PVCCIO_CPU1!U2D1!L16!@baseboard_fab2_lib.baseboard_fab2(sch_1):page72_i33@chpset_lib.skx_ext_b(chips)!SKX_EXT_B_BGA1-IC,TBD!!!F111!VCCIO(56)!!!!
S!PVCCIO_CPU1!U2D1!L14!@baseboard_fab2_lib.baseboard_fab2(sch_1):page72_i33@chpset_lib.skx_ext_b(chips)!SKX_EXT_B_BGA1-IC,TBD!!!F111!VCCIO(57)!!!!
S!PVCCIO_CPU1!U2D1!J10!@baseboard_fab2_lib.baseboard_fab2(sch_1):page72_i33@chpset_lib.skx_ext_b(chips)!SKX_EXT_B_BGA1-IC,TBD!!!F111!VCCIO(58)!!!!
S!PVCCIO_CPU1!U2D1!H13!@baseboard_fab2_lib.baseboard_fab2(sch_1):page72_i33@chpset_lib.skx_ext_b(chips)!SKX_EXT_B_BGA1-IC,TBD!!!F111!VCCIO(59)!!!!
S!PVCCIO_CPU1!U2D1!AT5!@baseboard_fab2_lib.baseboard_fab2(sch_1):page73_i107@chpset_lib.skx_ext_b(chips)!SKX_EXT_B_BGA1-IC,TBD!!!F110!VCCIO(5)!!!!
S!PVCCIO_CPU1!U2D1!DJ16!@baseboard_fab2_lib.baseboard_fab2(sch_1):page72_i33@chpset_lib.skx_ext_b(chips)!SKX_EXT_B_BGA1-IC,TBD!!!F111!VCCIO(60)!!!!
S!PVCCIO_CPU1!U2D1!DM17!@baseboard_fab2_lib.baseboard_fab2(sch_1):page72_i33@chpset_lib.skx_ext_b(chips)!SKX_EXT_B_BGA1-IC,TBD!!!F111!VCCIO(61)!!!!
S!PVCCIO_CPU1!U2D1!DN8!@baseboard_fab2_lib.baseboard_fab2(sch_1):page72_i33@chpset_lib.skx_ext_b(chips)!SKX_EXT_B_BGA1-IC,TBD!!!F111!VCCIO(62)!!!!
S!PVCCIO_CPU1!U2D1!DP19!@baseboard_fab2_lib.baseboard_fab2(sch_1):page72_i33@chpset_lib.skx_ext_b(chips)!SKX_EXT_B_BGA1-IC,TBD!!!F111!VCCIO(63)!!!!
S!PVCCIO_CPU1!U2D1!DR10!@baseboard_fab2_lib.baseboard_fab2(sch_1):page72_i33@chpset_lib.skx_ext_b(chips)!SKX_EXT_B_BGA1-IC,TBD!!!F111!VCCIO(64)!!!!
S!PVCCIO_CPU1!U2D1!DR2!@baseboard_fab2_lib.baseboard_fab2(sch_1):page72_i33@chpset_lib.skx_ext_b(chips)!SKX_EXT_B_BGA1-IC,TBD!!!F111!VCCIO(65)!!!!
S!PVCCIO_CPU1!U2D1!DU20!@baseboard_fab2_lib.baseboard_fab2(sch_1):page72_i33@chpset_lib.skx_ext_b(chips)!SKX_EXT_B_BGA1-IC,TBD!!!F111!VCCIO(66)!!!!
S!PVCCIO_CPU1!U2D1!EA12!@baseboard_fab2_lib.baseboard_fab2(sch_1):page72_i33@chpset_lib.skx_ext_b(chips)!SKX_EXT_B_BGA1-IC,TBD!!!F111!VCCIO(67)!!!!
S!PVCCIO_CPU1!U2D1!EB15!@baseboard_fab2_lib.baseboard_fab2(sch_1):page72_i33@chpset_lib.skx_ext_b(chips)!SKX_EXT_B_BGA1-IC,TBD!!!F111!VCCIO(68)!!!!
S!PVCCIO_CPU1!U2D1!J2!@baseboard_fab2_lib.baseboard_fab2(sch_1):page72_i33@chpset_lib.skx_ext_b(chips)!SKX_EXT_B_BGA1-IC,TBD!!!F111!VCCIO(69)!!!!
S!PVCCIO_CPU1!U2D1!AT7!@baseboard_fab2_lib.baseboard_fab2(sch_1):page73_i107@chpset_lib.skx_ext_b(chips)!SKX_EXT_B_BGA1-IC,TBD!!!F110!VCCIO(6)!!!!
S!PVCCIO_CPU1!U2D1!K15!@baseboard_fab2_lib.baseboard_fab2(sch_1):page72_i33@chpset_lib.skx_ext_b(chips)!SKX_EXT_B_BGA1-IC,TBD!!!F111!VCCIO(70)!!!!
S!PVCCIO_CPU1!U2D1!M7!@baseboard_fab2_lib.baseboard_fab2(sch_1):page72_i33@chpset_lib.skx_ext_b(chips)!SKX_EXT_B_BGA1-IC,TBD!!!F111!VCCIO(71)!!!!
S!PVCCIO_CPU1!U2D1!M9!@baseboard_fab2_lib.baseboard_fab2(sch_1):page72_i33@chpset_lib.skx_ext_b(chips)!SKX_EXT_B_BGA1-IC,TBD!!!F111!VCCIO(72)!!!!
S!PVCCIO_CPU1!U2D1!N18!@baseboard_fab2_lib.baseboard_fab2(sch_1):page72_i33@chpset_lib.skx_ext_b(chips)!SKX_EXT_B_BGA1-IC,TBD!!!F111!VCCIO(73)!!!!
S!PVCCIO_CPU1!U2D1!W10!@baseboard_fab2_lib.baseboard_fab2(sch_1):page72_i33@chpset_lib.skx_ext_b(chips)!SKX_EXT_B_BGA1-IC,TBD!!!F111!VCCIO(74)!!!!
S!PVCCIO_CPU1!U2D1!BE24!@baseboard_fab2_lib.baseboard_fab2(sch_1):page73_i107@chpset_lib.skx_ext_b(chips)!SKX_EXT_B_BGA1-IC,TBD!!!F110!VCCIO(7)!!!!
S!PVCCIO_CPU1!U2D1!DK21!@baseboard_fab2_lib.baseboard_fab2(sch_1):page73_i107@chpset_lib.skx_ext_b(chips)!SKX_EXT_B_BGA1-IC,TBD!!!F110!VCCIO(8)!!!!
S!PVCCIO_CPU1!U2D1!CF5!@baseboard_fab2_lib.baseboard_fab2(sch_1):page73_i107@chpset_lib.skx_ext_b(chips)!SKX_EXT_B_BGA1-IC,TBD!!!F110!VCCIO(9)!!!!
S!PVSA_CPU1!U2D1!CJ66!@baseboard_fab2_lib.baseboard_fab2(sch_1):page72_i33@chpset_lib.skx_ext_b(chips)!SKX_EXT_B_BGA1-IC,TBD!!!F111!VCCSA(0)!!!!
S!PVSA_CPU1!U2D1!CF65!@baseboard_fab2_lib.baseboard_fab2(sch_1):page72_i33@chpset_lib.skx_ext_b(chips)!SKX_EXT_B_BGA1-IC,TBD!!!F111!VCCSA(10)!!!!
S!PVSA_CPU1!U2D1!CE74!@baseboard_fab2_lib.baseboard_fab2(sch_1):page72_i33@chpset_lib.skx_ext_b(chips)!SKX_EXT_B_BGA1-IC,TBD!!!F111!VCCSA(11)!!!!
S!PVSA_CPU1!U2D1!CE72!@baseboard_fab2_lib.baseboard_fab2(sch_1):page72_i33@chpset_lib.skx_ext_b(chips)!SKX_EXT_B_BGA1-IC,TBD!!!F111!VCCSA(12)!!!!
S!PVSA_CPU1!U2D1!CE68!@baseboard_fab2_lib.baseboard_fab2(sch_1):page72_i33@chpset_lib.skx_ext_b(chips)!SKX_EXT_B_BGA1-IC,TBD!!!F111!VCCSA(13)!!!!
S!PVSA_CPU1!U2D1!CE66!@baseboard_fab2_lib.baseboard_fab2(sch_1):page72_i33@chpset_lib.skx_ext_b(chips)!SKX_EXT_B_BGA1-IC,TBD!!!F111!VCCSA(14)!!!!
S!PVSA_CPU1!U2D1!CE64!@baseboard_fab2_lib.baseboard_fab2(sch_1):page72_i33@chpset_lib.skx_ext_b(chips)!SKX_EXT_B_BGA1-IC,TBD!!!F111!VCCSA(15)!!!!
S!PVSA_CPU1!U2D1!CD71!@baseboard_fab2_lib.baseboard_fab2(sch_1):page72_i33@chpset_lib.skx_ext_b(chips)!SKX_EXT_B_BGA1-IC,TBD!!!F111!VCCSA(16)!!!!
S!PVSA_CPU1!U2D1!CD69!@baseboard_fab2_lib.baseboard_fab2(sch_1):page72_i33@chpset_lib.skx_ext_b(chips)!SKX_EXT_B_BGA1-IC,TBD!!!F111!VCCSA(17)!!!!
S!PVSA_CPU1!U2D1!CD67!@baseboard_fab2_lib.baseboard_fab2(sch_1):page72_i33@chpset_lib.skx_ext_b(chips)!SKX_EXT_B_BGA1-IC,TBD!!!F111!VCCSA(18)!!!!
S!PVSA_CPU1!U2D1!CD65!@baseboard_fab2_lib.baseboard_fab2(sch_1):page72_i33@chpset_lib.skx_ext_b(chips)!SKX_EXT_B_BGA1-IC,TBD!!!F111!VCCSA(19)!!!!
S!PVSA_CPU1!U2D1!CJ64!@baseboard_fab2_lib.baseboard_fab2(sch_1):page72_i33@chpset_lib.skx_ext_b(chips)!SKX_EXT_B_BGA1-IC,TBD!!!F111!VCCSA(1)!!!!
S!PVSA_CPU1!U2D1!CC70!@baseboard_fab2_lib.baseboard_fab2(sch_1):page72_i33@chpset_lib.skx_ext_b(chips)!SKX_EXT_B_BGA1-IC,TBD!!!F111!VCCSA(20)!!!!
S!PVSA_CPU1!U2D1!CC68!@baseboard_fab2_lib.baseboard_fab2(sch_1):page72_i33@chpset_lib.skx_ext_b(chips)!SKX_EXT_B_BGA1-IC,TBD!!!F111!VCCSA(21)!!!!
S!PVSA_CPU1!U2D1!CC66!@baseboard_fab2_lib.baseboard_fab2(sch_1):page72_i33@chpset_lib.skx_ext_b(chips)!SKX_EXT_B_BGA1-IC,TBD!!!F111!VCCSA(22)!!!!
S!PVSA_CPU1!U2D1!CB69!@baseboard_fab2_lib.baseboard_fab2(sch_1):page72_i33@chpset_lib.skx_ext_b(chips)!SKX_EXT_B_BGA1-IC,TBD!!!F111!VCCSA(23)!!!!
S!PVSA_CPU1!U2D1!CB67!@baseboard_fab2_lib.baseboard_fab2(sch_1):page72_i33@chpset_lib.skx_ext_b(chips)!SKX_EXT_B_BGA1-IC,TBD!!!F111!VCCSA(24)!!!!
S!PVSA_CPU1!U2D1!CB65!@baseboard_fab2_lib.baseboard_fab2(sch_1):page72_i33@chpset_lib.skx_ext_b(chips)!SKX_EXT_B_BGA1-IC,TBD!!!F111!VCCSA(25)!!!!
S!PVSA_CPU1!U2D1!CH75!@baseboard_fab2_lib.baseboard_fab2(sch_1):page72_i33@chpset_lib.skx_ext_b(chips)!SKX_EXT_B_BGA1-IC,TBD!!!F111!VCCSA(2)!!!!
S!PVSA_CPU1!U2D1!CH65!@baseboard_fab2_lib.baseboard_fab2(sch_1):page72_i33@chpset_lib.skx_ext_b(chips)!SKX_EXT_B_BGA1-IC,TBD!!!F111!VCCSA(3)!!!!
S!PVSA_CPU1!U2D1!CG74!@baseboard_fab2_lib.baseboard_fab2(sch_1):page72_i33@chpset_lib.skx_ext_b(chips)!SKX_EXT_B_BGA1-IC,TBD!!!F111!VCCSA(4)!!!!
S!PVSA_CPU1!U2D1!CG66!@baseboard_fab2_lib.baseboard_fab2(sch_1):page72_i33@chpset_lib.skx_ext_b(chips)!SKX_EXT_B_BGA1-IC,TBD!!!F111!VCCSA(5)!!!!
S!PVSA_CPU1!U2D1!CG64!@baseboard_fab2_lib.baseboard_fab2(sch_1):page72_i33@chpset_lib.skx_ext_b(chips)!SKX_EXT_B_BGA1-IC,TBD!!!F111!VCCSA(6)!!!!
S!PVSA_CPU1!U2D1!CF75!@baseboard_fab2_lib.baseboard_fab2(sch_1):page72_i33@chpset_lib.skx_ext_b(chips)!SKX_EXT_B_BGA1-IC,TBD!!!F111!VCCSA(7)!!!!
S!PVSA_CPU1!U2D1!CF73!@baseboard_fab2_lib.baseboard_fab2(sch_1):page72_i33@chpset_lib.skx_ext_b(chips)!SKX_EXT_B_BGA1-IC,TBD!!!F111!VCCSA(8)!!!!
S!PVSA_CPU1!U2D1!CF67!@baseboard_fab2_lib.baseboard_fab2(sch_1):page72_i33@chpset_lib.skx_ext_b(chips)!SKX_EXT_B_BGA1-IC,TBD!!!F111!VCCSA(9)!!!!
S!VSENSE_PVCCIOMCP_CPU1_SKT_VSEN!U2D1!BT17!@baseboard_fab2_lib.baseboard_fab2(sch_1):page73_i107@chpset_lib.skx_ext_b(chips)!SKX_EXT_B_BGA1-IC,TBD!!!F110!CD_VCCP_SENSE(1)!!!!
S!VSENSE_PVCCMCP_CPU1_SKT_VSEN!U2D1!BN16!@baseboard_fab2_lib.baseboard_fab2(sch_1):page73_i107@chpset_lib.skx_ext_b(chips)!SKX_EXT_B_BGA1-IC,TBD!!!F110!CD_VCC_CORE_SENSE!!!!
S!VSENSE_PVCCIOMCP_CPU1_SKT_VRTN!U2D1!BU16!@baseboard_fab2_lib.baseboard_fab2(sch_1):page73_i107@chpset_lib.skx_ext_b(chips)!SKX_EXT_B_BGA1-IC,TBD!!!F110!CD_VCCP_SENSE(0)!!!!
S!VSENSE_PVCCMCP_CPU1_SKT_VRTN!U2D1!BL16!@baseboard_fab2_lib.baseboard_fab2(sch_1):page73_i107@chpset_lib.skx_ext_b(chips)!SKX_EXT_B_BGA1-IC,TBD!!!F110!CD_VSS_VCC_CORE_SENSE!!!!
S!PVCCIO_CPU1!U2D1!CJ28!@baseboard_fab2_lib.baseboard_fab2(sch_1):page72_i33@chpset_lib.skx_ext_b(chips)!SKX_EXT_B_BGA1-IC,TBD!!!F111!VCCIO(84)!!!!
S!PVCCIO_CPU1!U2D1!BF27!@baseboard_fab2_lib.baseboard_fab2(sch_1):page72_i33@chpset_lib.skx_ext_b(chips)!SKX_EXT_B_BGA1-IC,TBD!!!F111!VCCIO(94)!!!!
S!PVCCIO_CPU1!U2D1!CH27!@baseboard_fab2_lib.baseboard_fab2(sch_1):page72_i33@chpset_lib.skx_ext_b(chips)!SKX_EXT_B_BGA1-IC,TBD!!!F111!VCCIO(85)!!!!
S!PVCCIO_CPU1!U2D1!BM27!@baseboard_fab2_lib.baseboard_fab2(sch_1):page72_i33@chpset_lib.skx_ext_b(chips)!SKX_EXT_B_BGA1-IC,TBD!!!F111!VCCIO(86)!!!!
S!PVCCIO_CPU1!U2D1!BL26!@baseboard_fab2_lib.baseboard_fab2(sch_1):page72_i33@chpset_lib.skx_ext_b(chips)!SKX_EXT_B_BGA1-IC,TBD!!!F111!VCCIO(87)!!!!
S!PVCCIO_CPU1!U2D1!BK27!@baseboard_fab2_lib.baseboard_fab2(sch_1):page72_i33@chpset_lib.skx_ext_b(chips)!SKX_EXT_B_BGA1-IC,TBD!!!F111!VCCIO(88)!!!!
S!PVCCIO_CPU1!U2D1!BK25!@baseboard_fab2_lib.baseboard_fab2(sch_1):page72_i33@chpset_lib.skx_ext_b(chips)!SKX_EXT_B_BGA1-IC,TBD!!!F111!VCCIO(89)!!!!
S!PVCCIO_CPU1!U2D1!BJ26!@baseboard_fab2_lib.baseboard_fab2(sch_1):page72_i33@chpset_lib.skx_ext_b(chips)!SKX_EXT_B_BGA1-IC,TBD!!!F111!VCCIO(90)!!!!
S!PVCCIO_CPU1!U2D1!BH27!@baseboard_fab2_lib.baseboard_fab2(sch_1):page72_i33@chpset_lib.skx_ext_b(chips)!SKX_EXT_B_BGA1-IC,TBD!!!F111!VCCIO(91)!!!!
S!PVCCIO_CPU1!U2D1!BH25!@baseboard_fab2_lib.baseboard_fab2(sch_1):page72_i33@chpset_lib.skx_ext_b(chips)!SKX_EXT_B_BGA1-IC,TBD!!!F111!VCCIO(92)!!!!
S!PVCCIO_CPU1!U2D1!BG26!@baseboard_fab2_lib.baseboard_fab2(sch_1):page72_i33@chpset_lib.skx_ext_b(chips)!SKX_EXT_B_BGA1-IC,TBD!!!F111!VCCIO(93)!!!!
S!P1V8_MCP_CPU1!U2D1!B17!@baseboard_fab2_lib.baseboard_fab2(sch_1):page56_i169@chpset_lib.skx_ext_b(chips)!SKX_EXT_B_BGA1-IC,TBD!!!F130!RSVD(294)!!!!
S!P1V8_MCP_CPU1!U2D1!B15!@baseboard_fab2_lib.baseboard_fab2(sch_1):page56_i169@chpset_lib.skx_ext_b(chips)!SKX_EXT_B_BGA1-IC,TBD!!!F130!RSVD(295)!!!!
S!P1V8_MCP_CPU1!U2D1!B13!@baseboard_fab2_lib.baseboard_fab2(sch_1):page56_i169@chpset_lib.skx_ext_b(chips)!SKX_EXT_B_BGA1-IC,TBD!!!F130!RSVD(296)!!!!
S!P1V8_MCP_CPU1!U2D1!A16!@baseboard_fab2_lib.baseboard_fab2(sch_1):page56_i169@chpset_lib.skx_ext_b(chips)!SKX_EXT_B_BGA1-IC,TBD!!!F130!RSVD(301)!!!!
S!P1V8_MCP_CPU1!U2D1!A14!@baseboard_fab2_lib.baseboard_fab2(sch_1):page56_i169@chpset_lib.skx_ext_b(chips)!SKX_EXT_B_BGA1-IC,TBD!!!F130!RSVD(302)!!!!
S!PVCCMCP_CPU1!U2D1!DA24!@baseboard_fab2_lib.baseboard_fab2(sch_1):page73_i107@chpset_lib.skx_ext_b(chips)!SKX_EXT_B_BGA1-IC,TBD!!!F110!RSVD(52)!!!!
S!PVCCMCP_CPU1!U2D1!CL26!@baseboard_fab2_lib.baseboard_fab2(sch_1):page73_i107@chpset_lib.skx_ext_b(chips)!SKX_EXT_B_BGA1-IC,TBD!!!F110!RSVD(80)!!!!
S!PVCCMCP_CPU1!U2D1!CL24!@baseboard_fab2_lib.baseboard_fab2(sch_1):page70_i10@chpset_lib.skx_ext_b(chips)!SKX_EXT_B_BGA1-IC,TBD!!!F115!RSVD(81)!!!!
S!PVCCMCP_CPU1!U2D1!CK25!@baseboard_fab2_lib.baseboard_fab2(sch_1):page70_i10@chpset_lib.skx_ext_b(chips)!SKX_EXT_B_BGA1-IC,TBD!!!F115!RSVD(83)!!!!
S!PVCCMCP_CPU1!U2D1!CK23!@baseboard_fab2_lib.baseboard_fab2(sch_1):page70_i10@chpset_lib.skx_ext_b(chips)!SKX_EXT_B_BGA1-IC,TBD!!!F115!RSVD(84)!!!!
S!PVCCMCP_CPU1!U2D1!CJ26!@baseboard_fab2_lib.baseboard_fab2(sch_1):page70_i10@chpset_lib.skx_ext_b(chips)!SKX_EXT_B_BGA1-IC,TBD!!!F115!RSVD(86)!!!!
S!PVCCMCP_CPU1!U2D1!CJ24!@baseboard_fab2_lib.baseboard_fab2(sch_1):page70_i10@chpset_lib.skx_ext_b(chips)!SKX_EXT_B_BGA1-IC,TBD!!!F115!RSVD(87)!!!!
S!PVCCMCP_CPU1!U2D1!CJ22!@baseboard_fab2_lib.baseboard_fab2(sch_1):page70_i10@chpset_lib.skx_ext_b(chips)!SKX_EXT_B_BGA1-IC,TBD!!!F115!RSVD(88)!!!!
S!PVCCMCP_CPU1!U2D1!CJ20!@baseboard_fab2_lib.baseboard_fab2(sch_1):page70_i10@chpset_lib.skx_ext_b(chips)!SKX_EXT_B_BGA1-IC,TBD!!!F115!RSVD(89)!!!!
S!PVCCMCP_CPU1!U2D1!CH23!@baseboard_fab2_lib.baseboard_fab2(sch_1):page70_i9@chpset_lib.skx_ext_b(chips)!SKX_EXT_B_BGA1-IC,TBD!!!F116!RSVD(92)!!!!
S!PVCCMCP_CPU1!U2D1!CH21!@baseboard_fab2_lib.baseboard_fab2(sch_1):page70_i9@chpset_lib.skx_ext_b(chips)!SKX_EXT_B_BGA1-IC,TBD!!!F116!RSVD(93)!!!!
S!PVCCMCP_CPU1!U2D1!CY25!@baseboard_fab2_lib.baseboard_fab2(sch_1):page73_i107@chpset_lib.skx_ext_b(chips)!SKX_EXT_B_BGA1-IC,TBD!!!F110!RSVD(58)!!!!
S!PVCCMCP_CPU1!U2D1!CG26!@baseboard_fab2_lib.baseboard_fab2(sch_1):page70_i9@chpset_lib.skx_ext_b(chips)!SKX_EXT_B_BGA1-IC,TBD!!!F116!RSVD(96)!!!!
S!PVCCMCP_CPU1!U2D1!CG20!@baseboard_fab2_lib.baseboard_fab2(sch_1):page70_i9@chpset_lib.skx_ext_b(chips)!SKX_EXT_B_BGA1-IC,TBD!!!F116!RSVD(98)!!!!
S!PVCCMCP_CPU1!U2D1!CF23!@baseboard_fab2_lib.baseboard_fab2(sch_1):page70_i9@chpset_lib.skx_ext_b(chips)!SKX_EXT_B_BGA1-IC,TBD!!!F116!RSVD(102)!!!!
S!PVCCMCP_CPU1!U2D1!CF21!@baseboard_fab2_lib.baseboard_fab2(sch_1):page70_i9@chpset_lib.skx_ext_b(chips)!SKX_EXT_B_BGA1-IC,TBD!!!F116!RSVD(103)!!!!
S!PVCCMCP_CPU1!U2D1!CF19!@baseboard_fab2_lib.baseboard_fab2(sch_1):page70_i9@chpset_lib.skx_ext_b(chips)!SKX_EXT_B_BGA1-IC,TBD!!!F116!RSVD(104)!!!!
S!PVCCMCP_CPU1!U2D1!CE22!@baseboard_fab2_lib.baseboard_fab2(sch_1):page70_i9@chpset_lib.skx_ext_b(chips)!SKX_EXT_B_BGA1-IC,TBD!!!F116!RSVD(107)!!!!
S!PVCCMCP_CPU1!U2D1!CD21!@baseboard_fab2_lib.baseboard_fab2(sch_1):page70_i9@chpset_lib.skx_ext_b(chips)!SKX_EXT_B_BGA1-IC,TBD!!!F116!RSVD(109)!!!!
S!PVCCMCP_CPU1!U2D1!CD19!@baseboard_fab2_lib.baseboard_fab2(sch_1):page70_i9@chpset_lib.skx_ext_b(chips)!SKX_EXT_B_BGA1-IC,TBD!!!F116!RSVD(110)!!!!
S!PVCCMCP_CPU1!U2D1!CC20!@baseboard_fab2_lib.baseboard_fab2(sch_1):page70_i9@chpset_lib.skx_ext_b(chips)!SKX_EXT_B_BGA1-IC,TBD!!!F116!RSVD(112)!!!!
S!PVCCMCP_CPU1!U2D1!CB21!@baseboard_fab2_lib.baseboard_fab2(sch_1):page70_i9@chpset_lib.skx_ext_b(chips)!SKX_EXT_B_BGA1-IC,TBD!!!F116!RSVD(115)!!!!
S!PVCCMCP_CPU1!U2D1!CW24!@baseboard_fab2_lib.baseboard_fab2(sch_1):page73_i107@chpset_lib.skx_ext_b(chips)!SKX_EXT_B_BGA1-IC,TBD!!!F110!RSVD(62)!!!!
S!PVCCMCP_CPU1!U2D1!CB19!@baseboard_fab2_lib.baseboard_fab2(sch_1):page70_i9@chpset_lib.skx_ext_b(chips)!SKX_EXT_B_BGA1-IC,TBD!!!F116!RSVD(116)!!!!
S!PVCCMCP_CPU1!U2D1!CA22!@baseboard_fab2_lib.baseboard_fab2(sch_1):page70_i9@chpset_lib.skx_ext_b(chips)!SKX_EXT_B_BGA1-IC,TBD!!!F116!RSVD(118)!!!!
S!PVCCMCP_CPU1!U2D1!BY19!@baseboard_fab2_lib.baseboard_fab2(sch_1):page70_i9@chpset_lib.skx_ext_b(chips)!SKX_EXT_B_BGA1-IC,TBD!!!F116!RSVD(120)!!!!
S!PVCCMCP_CPU1!U2D1!BW20!@baseboard_fab2_lib.baseboard_fab2(sch_1):page70_i9@chpset_lib.skx_ext_b(chips)!SKX_EXT_B_BGA1-IC,TBD!!!F116!RSVD(122)!!!!
S!PVCCMCP_CPU1!U2D1!BV21!@baseboard_fab2_lib.baseboard_fab2(sch_1):page70_i9@chpset_lib.skx_ext_b(chips)!SKX_EXT_B_BGA1-IC,TBD!!!F116!RSVD(125)!!!!
S!PVCCMCP_CPU1!U2D1!BV19!@baseboard_fab2_lib.baseboard_fab2(sch_1):page70_i9@chpset_lib.skx_ext_b(chips)!SKX_EXT_B_BGA1-IC,TBD!!!F116!RSVD(126)!!!!
S!PVCCMCP_CPU1!U2D1!BU22!@baseboard_fab2_lib.baseboard_fab2(sch_1):page70_i9@chpset_lib.skx_ext_b(chips)!SKX_EXT_B_BGA1-IC,TBD!!!F116!RSVD(127)!!!!
S!PVCCMCP_CPU1!U2D1!BU20!@baseboard_fab2_lib.baseboard_fab2(sch_1):page70_i9@chpset_lib.skx_ext_b(chips)!SKX_EXT_B_BGA1-IC,TBD!!!F116!RSVD(128)!!!!
S!PVCCMCP_CPU1!U2D1!BU18!@baseboard_fab2_lib.baseboard_fab2(sch_1):page70_i9@chpset_lib.skx_ext_b(chips)!SKX_EXT_B_BGA1-IC,TBD!!!F116!RSVD(129)!!!!
S!PVCCMCP_CPU1!U2D1!BR24!@baseboard_fab2_lib.baseboard_fab2(sch_1):page70_i9@chpset_lib.skx_ext_b(chips)!SKX_EXT_B_BGA1-IC,TBD!!!F116!RSVD(130)!!!!
S!PVCCMCP_CPU1!U2D1!CV23!@baseboard_fab2_lib.baseboard_fab2(sch_1):page73_i107@chpset_lib.skx_ext_b(chips)!SKX_EXT_B_BGA1-IC,TBD!!!F110!RSVD(65)!!!!
S!PVCCMCP_CPU1!U2D1!BR22!@baseboard_fab2_lib.baseboard_fab2(sch_1):page70_i9@chpset_lib.skx_ext_b(chips)!SKX_EXT_B_BGA1-IC,TBD!!!F116!RSVD(131)!!!!
S!PVCCMCP_CPU1!U2D1!BP21!@baseboard_fab2_lib.baseboard_fab2(sch_1):page70_i9@chpset_lib.skx_ext_b(chips)!SKX_EXT_B_BGA1-IC,TBD!!!F116!RSVD(132)!!!!
S!PVCCMCP_CPU1!U2D1!BP17!@baseboard_fab2_lib.baseboard_fab2(sch_1):page70_i9@chpset_lib.skx_ext_b(chips)!SKX_EXT_B_BGA1-IC,TBD!!!F116!RSVD(133)!!!!
S!PVCCMCP_CPU1!U2D1!BN18!@baseboard_fab2_lib.baseboard_fab2(sch_1):page70_i9@chpset_lib.skx_ext_b(chips)!SKX_EXT_B_BGA1-IC,TBD!!!F116!RSVD(134)!!!!
S!PVCCMCP_CPU1!U2D1!BM19!@baseboard_fab2_lib.baseboard_fab2(sch_1):page70_i9@chpset_lib.skx_ext_b(chips)!SKX_EXT_B_BGA1-IC,TBD!!!F116!RSVD(135)!!!!
S!PVCCMCP_CPU1!U2D1!BM17!@baseboard_fab2_lib.baseboard_fab2(sch_1):page70_i9@chpset_lib.skx_ext_b(chips)!SKX_EXT_B_BGA1-IC,TBD!!!F116!RSVD(136)!!!!
S!PVCCMCP_CPU1!U2D1!BL20!@baseboard_fab2_lib.baseboard_fab2(sch_1):page70_i9@chpset_lib.skx_ext_b(chips)!SKX_EXT_B_BGA1-IC,TBD!!!F116!RSVD(137)!!!!
S!PVCCMCP_CPU1!U2D1!BL18!@baseboard_fab2_lib.baseboard_fab2(sch_1):page70_i9@chpset_lib.skx_ext_b(chips)!SKX_EXT_B_BGA1-IC,TBD!!!F116!RSVD(138)!!!!
S!PVCCMCP_CPU1!U2D1!BK17!@baseboard_fab2_lib.baseboard_fab2(sch_1):page70_i9@chpset_lib.skx_ext_b(chips)!SKX_EXT_B_BGA1-IC,TBD!!!F116!RSVD(139)!!!!
S!PVCCMCP_CPU1!U2D1!BJ20!@baseboard_fab2_lib.baseboard_fab2(sch_1):page70_i9@chpset_lib.skx_ext_b(chips)!SKX_EXT_B_BGA1-IC,TBD!!!F116!RSVD(140)!!!!
S!PVCCMCP_CPU1!U2D1!CU24!@baseboard_fab2_lib.baseboard_fab2(sch_1):page73_i107@chpset_lib.skx_ext_b(chips)!SKX_EXT_B_BGA1-IC,TBD!!!F110!RSVD(68)!!!!
S!PVCCMCP_CPU1!U2D1!BJ18!@baseboard_fab2_lib.baseboard_fab2(sch_1):page70_i9@chpset_lib.skx_ext_b(chips)!SKX_EXT_B_BGA1-IC,TBD!!!F116!RSVD(141)!!!!
S!PVCCMCP_CPU1!U2D1!BJ16!@baseboard_fab2_lib.baseboard_fab2(sch_1):page70_i9@chpset_lib.skx_ext_b(chips)!SKX_EXT_B_BGA1-IC,TBD!!!F116!RSVD(142)!!!!
S!PVCCMCP_CPU1!U2D1!BH19!@baseboard_fab2_lib.baseboard_fab2(sch_1):page70_i9@chpset_lib.skx_ext_b(chips)!SKX_EXT_B_BGA1-IC,TBD!!!F116!RSVD(143)!!!!
S!PVCCMCP_CPU1!U2D1!CT23!@baseboard_fab2_lib.baseboard_fab2(sch_1):page73_i107@chpset_lib.skx_ext_b(chips)!SKX_EXT_B_BGA1-IC,TBD!!!F110!RSVD(71)!!!!
S!PVCCMCP_CPU1!U2D1!CP23!@baseboard_fab2_lib.baseboard_fab2(sch_1):page73_i107@chpset_lib.skx_ext_b(chips)!SKX_EXT_B_BGA1-IC,TBD!!!F110!RSVD(74)!!!!
S!PVCCMCP_CPU1!U2D1!CN24!@baseboard_fab2_lib.baseboard_fab2(sch_1):page73_i107@chpset_lib.skx_ext_b(chips)!SKX_EXT_B_BGA1-IC,TBD!!!F110!RSVD(76)!!!!
S!PVCCMCP_CPU1!U2D1!CM25!@baseboard_fab2_lib.baseboard_fab2(sch_1):page73_i107@chpset_lib.skx_ext_b(chips)!SKX_EXT_B_BGA1-IC,TBD!!!F110!RSVD(78)!!!!
S!PVCCMCP_CPU1!U2D1!CM23!@baseboard_fab2_lib.baseboard_fab2(sch_1):page73_i107@chpset_lib.skx_ext_b(chips)!SKX_EXT_B_BGA1-IC,TBD!!!F110!RSVD(79)!!!!
S!PVCCMCP_CPU1!U2D1!AT25!@baseboard_fab2_lib.baseboard_fab2(sch_1):page63_i23@chpset_lib.skx_ext_b(chips)!SKX_EXT_B_BGA1-IC,TBD!!!F123!RSVD(187)!!!!
S!PVCCMCP_CPU1!U2D1!AN18!@baseboard_fab2_lib.baseboard_fab2(sch_1):page56_i169@chpset_lib.skx_ext_b(chips)!SKX_EXT_B_BGA1-IC,TBD!!!F130!RSVD(203)!!!!
S!PVCCMCP_CPU1!U2D1!AM25!@baseboard_fab2_lib.baseboard_fab2(sch_1):page56_i169@chpset_lib.skx_ext_b(chips)!SKX_EXT_B_BGA1-IC,TBD!!!F130!RSVD(207)!!!!
S!PVCCMCP_CPU1!U2D1!AM21!@baseboard_fab2_lib.baseboard_fab2(sch_1):page56_i169@chpset_lib.skx_ext_b(chips)!SKX_EXT_B_BGA1-IC,TBD!!!F130!RSVD(209)!!!!
S!VSENSE_P1V8MCP_CPU1_SKT_VRTN!U2D1!AL20!@baseboard_fab2_lib.baseboard_fab2(sch_1):page56_i169@chpset_lib.skx_ext_b(chips)!SKX_EXT_B_BGA1-IC,TBD!!!F130!RSVD(215)!!!!
S!VSENSE_P1V8MCP_CPU1_SKT_VSEN!U2D1!AK21!@baseboard_fab2_lib.baseboard_fab2(sch_1):page56_i169@chpset_lib.skx_ext_b(chips)!SKX_EXT_B_BGA1-IC,TBD!!!F130!RSVD(221)!!!!
S!PVCCMCP_CPU1!U2D1!AT23!@baseboard_fab2_lib.baseboard_fab2(sch_1):page63_i23@chpset_lib.skx_ext_b(chips)!SKX_EXT_B_BGA1-IC,TBD!!!F123!RSVD(188)!!!!
S!PVCCMCP_CPU1!U2D1!AR26!@baseboard_fab2_lib.baseboard_fab2(sch_1):page63_i23@chpset_lib.skx_ext_b(chips)!SKX_EXT_B_BGA1-IC,TBD!!!F123!RSVD(191)!!!!
S!PVCCMCP_CPU1!U2D1!AR22!@baseboard_fab2_lib.baseboard_fab2(sch_1):page63_i23@chpset_lib.skx_ext_b(chips)!SKX_EXT_B_BGA1-IC,TBD!!!F123!RSVD(192)!!!!
S!PVCCMCP_CPU1!U2D1!AR20!@baseboard_fab2_lib.baseboard_fab2(sch_1):page63_i23@chpset_lib.skx_ext_b(chips)!SKX_EXT_B_BGA1-IC,TBD!!!F123!RSVD(193)!!!!
S!PVCCMCP_CPU1!U2D1!AP25!@baseboard_fab2_lib.baseboard_fab2(sch_1):page56_i169@chpset_lib.skx_ext_b(chips)!SKX_EXT_B_BGA1-IC,TBD!!!F130!RSVD(196)!!!!
S!PVCCMCP_CPU1!U2D1!AP23!@baseboard_fab2_lib.baseboard_fab2(sch_1):page56_i169@chpset_lib.skx_ext_b(chips)!SKX_EXT_B_BGA1-IC,TBD!!!F130!RSVD(197)!!!!
S!PVCCMCP_CPU1!U2D1!AN26!@baseboard_fab2_lib.baseboard_fab2(sch_1):page56_i169@chpset_lib.skx_ext_b(chips)!SKX_EXT_B_BGA1-IC,TBD!!!F130!RSVD(200)!!!!
S!PVCCMCP_CPU1!U2D1!AN24!@baseboard_fab2_lib.baseboard_fab2(sch_1):page56_i169@chpset_lib.skx_ext_b(chips)!SKX_EXT_B_BGA1-IC,TBD!!!F130!RSVD(201)!!!!
S!PVCCMCP_CPU1!U2D1!AN22!@baseboard_fab2_lib.baseboard_fab2(sch_1):page56_i169@chpset_lib.skx_ext_b(chips)!SKX_EXT_B_BGA1-IC,TBD!!!F130!RSVD(202)!!!!
S!PVCCIO_CPU1!U2D1!AE36!@baseboard_fab2_lib.baseboard_fab2(sch_1):page72_i33@chpset_lib.skx_ext_b(chips)!SKX_EXT_B_BGA1-IC,TBD!!!F111!VCCIO(95)!!!!
S!PVCCIO_CPU1!U2D1!AD37!@baseboard_fab2_lib.baseboard_fab2(sch_1):page72_i33@chpset_lib.skx_ext_b(chips)!SKX_EXT_B_BGA1-IC,TBD!!!F111!VCCIO(96)!!!!
S!PVCCIO_CPU1!U2D1!AC36!@baseboard_fab2_lib.baseboard_fab2(sch_1):page72_i33@chpset_lib.skx_ext_b(chips)!SKX_EXT_B_BGA1-IC,TBD!!!F111!VCCIO(97)!!!!
S!PVCCIO_CPU1!U2D1!AF35!@baseboard_fab2_lib.baseboard_fab2(sch_1):page72_i33@chpset_lib.skx_ext_b(chips)!SKX_EXT_B_BGA1-IC,TBD!!!F111!VCCIO(98)!!!!
S!PVCCIO_CPU1!U2D1!AD35!@baseboard_fab2_lib.baseboard_fab2(sch_1):page72_i33@chpset_lib.skx_ext_b(chips)!SKX_EXT_B_BGA1-IC,TBD!!!F111!VCCIO(99)!!!!
S!PVCCIO_CPU1!U2D1!AE34!@baseboard_fab2_lib.baseboard_fab2(sch_1):page72_i33@chpset_lib.skx_ext_b(chips)!SKX_EXT_B_BGA1-IC,TBD!!!F111!VCCIO(100)!!!!
S!PVCCIO_CPU1!U2D1!AG34!@baseboard_fab2_lib.baseboard_fab2(sch_1):page72_i33@chpset_lib.skx_ext_b(chips)!SKX_EXT_B_BGA1-IC,TBD!!!F111!VCCIO(101)!!!!
S!PVCCIO_CPU1!U2D1!AM29!@baseboard_fab2_lib.baseboard_fab2(sch_1):page72_i33@chpset_lib.skx_ext_b(chips)!SKX_EXT_B_BGA1-IC,TBD!!!F111!VCCIO(102)!!!!
S!PVCCIO_CPU1!U2D1!AL28!@baseboard_fab2_lib.baseboard_fab2(sch_1):page72_i33@chpset_lib.skx_ext_b(chips)!SKX_EXT_B_BGA1-IC,TBD!!!F111!VCCIO(103)!!!!
S!CLK_100M_CPU1_RC_REFCLK0_DP!U2D1!AM27!@baseboard_fab2_lib.baseboard_fab2(sch_1):page56_i169@chpset_lib.skx_ext_b(chips)!SKX_EXT_B_BGA1-IC,TBD!!!F130!RSVD(206)!!!!
S!VSENSE_PVCCIO_CPU1_SKT_VSEN!U2D1!BH5!@baseboard_fab2_lib.baseboard_fab2(sch_1):page73_i107@chpset_lib.skx_ext_b(chips)!SKX_EXT_B_BGA1-IC,TBD!!!F110!VCCIO_SENSE!!!!
S!VSENSE_PVSA_CPU1_SKT_VSEN!U2D1!CE76!@baseboard_fab2_lib.baseboard_fab2(sch_1):page73_i107@chpset_lib.skx_ext_b(chips)!SKX_EXT_B_BGA1-IC,TBD!!!F110!VCCSA_SENSE!!!!
S!VSENSE_PVCCIO_CPU1_SKT_VRTN!U2D1!BF5!@baseboard_fab2_lib.baseboard_fab2(sch_1):page73_i107@chpset_lib.skx_ext_b(chips)!SKX_EXT_B_BGA1-IC,TBD!!!F110!VSS_VCCIO_SENSE!!!!
S!VSENSE_PVSA_CPU1_SKT_VRTN!U2D1!CG76!@baseboard_fab2_lib.baseboard_fab2(sch_1):page73_i107@chpset_lib.skx_ext_b(chips)!SKX_EXT_B_BGA1-IC,TBD!!!F110!VSS_VCCSA_SENSE!!!!
S!GND!U2D1!L72!@baseboard_fab2_lib.baseboard_fab2(sch_1):page74_i21@chpset_lib.skx_ext_b(chips)!SKX_EXT_B_BGA1-IC,TBD!!!F108!VSS(1068)!!!!
S!GND!U2D1!L22!@baseboard_fab2_lib.baseboard_fab2(sch_1):page74_i21@chpset_lib.skx_ext_b(chips)!SKX_EXT_B_BGA1-IC,TBD!!!F108!VSS(1069)!!!!
S!GND!U2D1!L20!@baseboard_fab2_lib.baseboard_fab2(sch_1):page74_i21@chpset_lib.skx_ext_b(chips)!SKX_EXT_B_BGA1-IC,TBD!!!F108!VSS(1070)!!!!
S!GND!U2D1!L6!@baseboard_fab2_lib.baseboard_fab2(sch_1):page74_i21@chpset_lib.skx_ext_b(chips)!SKX_EXT_B_BGA1-IC,TBD!!!F108!VSS(1071)!!!!
S!GND!U2D1!L2!@baseboard_fab2_lib.baseboard_fab2(sch_1):page74_i21@chpset_lib.skx_ext_b(chips)!SKX_EXT_B_BGA1-IC,TBD!!!F108!VSS(1072)!!!!
S!GND!U2D1!L10!@baseboard_fab2_lib.baseboard_fab2(sch_1):page74_i21@chpset_lib.skx_ext_b(chips)!SKX_EXT_B_BGA1-IC,TBD!!!F108!VSS(1073)!!!!
S!GND!U2D1!K85!@baseboard_fab2_lib.baseboard_fab2(sch_1):page74_i21@chpset_lib.skx_ext_b(chips)!SKX_EXT_B_BGA1-IC,TBD!!!F108!VSS(1074)!!!!
S!GND!U2D1!K83!@baseboard_fab2_lib.baseboard_fab2(sch_1):page74_i21@chpset_lib.skx_ext_b(chips)!SKX_EXT_B_BGA1-IC,TBD!!!F108!VSS(1075)!!!!
S!GND!U2D1!K81!@baseboard_fab2_lib.baseboard_fab2(sch_1):page74_i21@chpset_lib.skx_ext_b(chips)!SKX_EXT_B_BGA1-IC,TBD!!!F108!VSS(1076)!!!!
S!GND!U2D1!K77!@baseboard_fab2_lib.baseboard_fab2(sch_1):page74_i21@chpset_lib.skx_ext_b(chips)!SKX_EXT_B_BGA1-IC,TBD!!!F108!VSS(1077)!!!!
S!GND!U2D1!K73!@baseboard_fab2_lib.baseboard_fab2(sch_1):page74_i21@chpset_lib.skx_ext_b(chips)!SKX_EXT_B_BGA1-IC,TBD!!!F108!VSS(1078)!!!!
S!GND!U2D1!K71!@baseboard_fab2_lib.baseboard_fab2(sch_1):page74_i21@chpset_lib.skx_ext_b(chips)!SKX_EXT_B_BGA1-IC,TBD!!!F108!VSS(1079)!!!!
S!GND!U2D1!K69!@baseboard_fab2_lib.baseboard_fab2(sch_1):page74_i21@chpset_lib.skx_ext_b(chips)!SKX_EXT_B_BGA1-IC,TBD!!!F108!VSS(1080)!!!!
S!GND!U2D1!K67!@baseboard_fab2_lib.baseboard_fab2(sch_1):page74_i21@chpset_lib.skx_ext_b(chips)!SKX_EXT_B_BGA1-IC,TBD!!!F108!VSS(1081)!!!!
S!GND!U2D1!K65!@baseboard_fab2_lib.baseboard_fab2(sch_1):page74_i21@chpset_lib.skx_ext_b(chips)!SKX_EXT_B_BGA1-IC,TBD!!!F108!VSS(1082)!!!!
S!GND!U2D1!K39!@baseboard_fab2_lib.baseboard_fab2(sch_1):page74_i21@chpset_lib.skx_ext_b(chips)!SKX_EXT_B_BGA1-IC,TBD!!!F108!VSS(1083)!!!!
S!GND!U2D1!K33!@baseboard_fab2_lib.baseboard_fab2(sch_1):page74_i21@chpset_lib.skx_ext_b(chips)!SKX_EXT_B_BGA1-IC,TBD!!!F108!VSS(1084)!!!!
S!GND!U2D1!K27!@baseboard_fab2_lib.baseboard_fab2(sch_1):page74_i21@chpset_lib.skx_ext_b(chips)!SKX_EXT_B_BGA1-IC,TBD!!!F108!VSS(1085)!!!!
S!GND!U2D1!DB7!@baseboard_fab2_lib.baseboard_fab2(sch_1):page74_i21@chpset_lib.skx_ext_b(chips)!SKX_EXT_B_BGA1-IC,TBD!!!F108!VSS(1086)!!!!
S!GND!U2D1!K17!@baseboard_fab2_lib.baseboard_fab2(sch_1):page74_i21@chpset_lib.skx_ext_b(chips)!SKX_EXT_B_BGA1-IC,TBD!!!F108!VSS(1087)!!!!
S!GND!U2D1!K13!@baseboard_fab2_lib.baseboard_fab2(sch_1):page74_i21@chpset_lib.skx_ext_b(chips)!SKX_EXT_B_BGA1-IC,TBD!!!F108!VSS(1088)!!!!
S!GND!U2D1!K11!@baseboard_fab2_lib.baseboard_fab2(sch_1):page74_i21@chpset_lib.skx_ext_b(chips)!SKX_EXT_B_BGA1-IC,TBD!!!F108!VSS(1089)!!!!
S!GND!U2D1!K1!@baseboard_fab2_lib.baseboard_fab2(sch_1):page74_i21@chpset_lib.skx_ext_b(chips)!SKX_EXT_B_BGA1-IC,TBD!!!F108!VSS(1090)!!!!
S!GND!U2D1!J84!@baseboard_fab2_lib.baseboard_fab2(sch_1):page74_i21@chpset_lib.skx_ext_b(chips)!SKX_EXT_B_BGA1-IC,TBD!!!F108!VSS(1091)!!!!
S!GND!U2D1!J82!@baseboard_fab2_lib.baseboard_fab2(sch_1):page74_i21@chpset_lib.skx_ext_b(chips)!SKX_EXT_B_BGA1-IC,TBD!!!F108!VSS(1092)!!!!
S!GND!U2D1!J76!@baseboard_fab2_lib.baseboard_fab2(sch_1):page74_i21@chpset_lib.skx_ext_b(chips)!SKX_EXT_B_BGA1-IC,TBD!!!F108!VSS(1093)!!!!
S!GND!U2D1!J74!@baseboard_fab2_lib.baseboard_fab2(sch_1):page74_i20@chpset_lib.skx_ext_b(chips)!SKX_EXT_B_BGA1-IC,TBD!!!F109!VSS(1094)!!!!
S!GND!U2D1!J72!@baseboard_fab2_lib.baseboard_fab2(sch_1):page74_i20@chpset_lib.skx_ext_b(chips)!SKX_EXT_B_BGA1-IC,TBD!!!F109!VSS(1095)!!!!
S!GND!U2D1!J40!@baseboard_fab2_lib.baseboard_fab2(sch_1):page74_i20@chpset_lib.skx_ext_b(chips)!SKX_EXT_B_BGA1-IC,TBD!!!F109!VSS(1096)!!!!
S!GND!U2D1!J38!@baseboard_fab2_lib.baseboard_fab2(sch_1):page74_i20@chpset_lib.skx_ext_b(chips)!SKX_EXT_B_BGA1-IC,TBD!!!F109!VSS(1097)!!!!
S!GND!U2D1!J34!@baseboard_fab2_lib.baseboard_fab2(sch_1):page74_i20@chpset_lib.skx_ext_b(chips)!SKX_EXT_B_BGA1-IC,TBD!!!F109!VSS(1098)!!!!
S!GND!U2D1!J32!@baseboard_fab2_lib.baseboard_fab2(sch_1):page74_i20@chpset_lib.skx_ext_b(chips)!SKX_EXT_B_BGA1-IC,TBD!!!F109!VSS(1099)!!!!
S!GND!U2D1!J28!@baseboard_fab2_lib.baseboard_fab2(sch_1):page74_i20@chpset_lib.skx_ext_b(chips)!SKX_EXT_B_BGA1-IC,TBD!!!F109!VSS(1100)!!!!
S!GND!U2D1!J26!@baseboard_fab2_lib.baseboard_fab2(sch_1):page74_i20@chpset_lib.skx_ext_b(chips)!SKX_EXT_B_BGA1-IC,TBD!!!F109!VSS(1101)!!!!
S!GND!U2D1!J22!@baseboard_fab2_lib.baseboard_fab2(sch_1):page74_i20@chpset_lib.skx_ext_b(chips)!SKX_EXT_B_BGA1-IC,TBD!!!F109!VSS(1102)!!!!
S!GND!U2D1!J14!@baseboard_fab2_lib.baseboard_fab2(sch_1):page74_i20@chpset_lib.skx_ext_b(chips)!SKX_EXT_B_BGA1-IC,TBD!!!F109!VSS(1103)!!!!
S!GND!U2D1!J12!@baseboard_fab2_lib.baseboard_fab2(sch_1):page74_i20@chpset_lib.skx_ext_b(chips)!SKX_EXT_B_BGA1-IC,TBD!!!F109!VSS(1104)!!!!
S!GND!U2D1!J4!@baseboard_fab2_lib.baseboard_fab2(sch_1):page74_i20@chpset_lib.skx_ext_b(chips)!SKX_EXT_B_BGA1-IC,TBD!!!F109!VSS(1105)!!!!
S!GND!U2D1!DN44!@baseboard_fab2_lib.baseboard_fab2(sch_1):page74_i20@chpset_lib.skx_ext_b(chips)!SKX_EXT_B_BGA1-IC,TBD!!!F109!VSS(1106)!!!!
S!GND!U2D1!H75!@baseboard_fab2_lib.baseboard_fab2(sch_1):page74_i20@chpset_lib.skx_ext_b(chips)!SKX_EXT_B_BGA1-IC,TBD!!!F109!VSS(1107)!!!!
S!GND!U2D1!H71!@baseboard_fab2_lib.baseboard_fab2(sch_1):page74_i20@chpset_lib.skx_ext_b(chips)!SKX_EXT_B_BGA1-IC,TBD!!!F109!VSS(1108)!!!!
S!GND!U2D1!H65!@baseboard_fab2_lib.baseboard_fab2(sch_1):page74_i20@chpset_lib.skx_ext_b(chips)!SKX_EXT_B_BGA1-IC,TBD!!!F109!VSS(1109)!!!!
S!GND!U2D1!H41!@baseboard_fab2_lib.baseboard_fab2(sch_1):page74_i20@chpset_lib.skx_ext_b(chips)!SKX_EXT_B_BGA1-IC,TBD!!!F109!VSS(1110)!!!!
S!GND!U2D1!H39!@baseboard_fab2_lib.baseboard_fab2(sch_1):page74_i20@chpset_lib.skx_ext_b(chips)!SKX_EXT_B_BGA1-IC,TBD!!!F109!VSS(1111)!!!!
S!GND!U2D1!H37!@baseboard_fab2_lib.baseboard_fab2(sch_1):page74_i20@chpset_lib.skx_ext_b(chips)!SKX_EXT_B_BGA1-IC,TBD!!!F109!VSS(1112)!!!!
S!GND!U2D1!H35!@baseboard_fab2_lib.baseboard_fab2(sch_1):page74_i20@chpset_lib.skx_ext_b(chips)!SKX_EXT_B_BGA1-IC,TBD!!!F109!VSS(1113)!!!!
S!GND!U2D1!H33!@baseboard_fab2_lib.baseboard_fab2(sch_1):page74_i20@chpset_lib.skx_ext_b(chips)!SKX_EXT_B_BGA1-IC,TBD!!!F109!VSS(1114)!!!!
S!GND!U2D1!H31!@baseboard_fab2_lib.baseboard_fab2(sch_1):page74_i20@chpset_lib.skx_ext_b(chips)!SKX_EXT_B_BGA1-IC,TBD!!!F109!VSS(1115)!!!!
S!GND!U2D1!H29!@baseboard_fab2_lib.baseboard_fab2(sch_1):page74_i20@chpset_lib.skx_ext_b(chips)!SKX_EXT_B_BGA1-IC,TBD!!!F109!VSS(1116)!!!!
S!GND!U2D1!H27!@baseboard_fab2_lib.baseboard_fab2(sch_1):page74_i20@chpset_lib.skx_ext_b(chips)!SKX_EXT_B_BGA1-IC,TBD!!!F109!VSS(1117)!!!!
S!GND!U2D1!H25!@baseboard_fab2_lib.baseboard_fab2(sch_1):page74_i20@chpset_lib.skx_ext_b(chips)!SKX_EXT_B_BGA1-IC,TBD!!!F109!VSS(1118)!!!!
S!GND!U2D1!H11!@baseboard_fab2_lib.baseboard_fab2(sch_1):page74_i20@chpset_lib.skx_ext_b(chips)!SKX_EXT_B_BGA1-IC,TBD!!!F109!VSS(1119)!!!!
S!GND!U2D1!H3!@baseboard_fab2_lib.baseboard_fab2(sch_1):page74_i20@chpset_lib.skx_ext_b(chips)!SKX_EXT_B_BGA1-IC,TBD!!!F109!VSS(1120)!!!!
S!GND!U2D1!G82!@baseboard_fab2_lib.baseboard_fab2(sch_1):page74_i20@chpset_lib.skx_ext_b(chips)!SKX_EXT_B_BGA1-IC,TBD!!!F109!VSS(1121)!!!!
S!GND!U2D1!G80!@baseboard_fab2_lib.baseboard_fab2(sch_1):page74_i20@chpset_lib.skx_ext_b(chips)!SKX_EXT_B_BGA1-IC,TBD!!!F109!VSS(1122)!!!!
S!GND!U2D1!G78!@baseboard_fab2_lib.baseboard_fab2(sch_1):page74_i20@chpset_lib.skx_ext_b(chips)!SKX_EXT_B_BGA1-IC,TBD!!!F109!VSS(1123)!!!!
S!GND!U2D1!G76!@baseboard_fab2_lib.baseboard_fab2(sch_1):page74_i20@chpset_lib.skx_ext_b(chips)!SKX_EXT_B_BGA1-IC,TBD!!!F109!VSS(1124)!!!!
S!GND!U2D1!G70!@baseboard_fab2_lib.baseboard_fab2(sch_1):page74_i20@chpset_lib.skx_ext_b(chips)!SKX_EXT_B_BGA1-IC,TBD!!!F109!VSS(1125)!!!!
S!GND!U2D1!G66!@baseboard_fab2_lib.baseboard_fab2(sch_1):page74_i20@chpset_lib.skx_ext_b(chips)!SKX_EXT_B_BGA1-IC,TBD!!!F109!VSS(1126)!!!!
S!GND!U2D1!G42!@baseboard_fab2_lib.baseboard_fab2(sch_1):page74_i20@chpset_lib.skx_ext_b(chips)!SKX_EXT_B_BGA1-IC,TBD!!!F109!VSS(1127)!!!!
S!GND!U2D1!G38!@baseboard_fab2_lib.baseboard_fab2(sch_1):page74_i20@chpset_lib.skx_ext_b(chips)!SKX_EXT_B_BGA1-IC,TBD!!!F109!VSS(1128)!!!!
S!GND!U2D1!G36!@baseboard_fab2_lib.baseboard_fab2(sch_1):page74_i20@chpset_lib.skx_ext_b(chips)!SKX_EXT_B_BGA1-IC,TBD!!!F109!VSS(1129)!!!!
S!GND!U2D1!G32!@baseboard_fab2_lib.baseboard_fab2(sch_1):page74_i20@chpset_lib.skx_ext_b(chips)!SKX_EXT_B_BGA1-IC,TBD!!!F109!VSS(1130)!!!!
S!GND!U2D1!G30!@baseboard_fab2_lib.baseboard_fab2(sch_1):page74_i20@chpset_lib.skx_ext_b(chips)!SKX_EXT_B_BGA1-IC,TBD!!!F109!VSS(1131)!!!!
S!GND!U2D1!G26!@baseboard_fab2_lib.baseboard_fab2(sch_1):page74_i20@chpset_lib.skx_ext_b(chips)!SKX_EXT_B_BGA1-IC,TBD!!!F109!VSS(1132)!!!!
S!GND!U2D1!G24!@baseboard_fab2_lib.baseboard_fab2(sch_1):page74_i20@chpset_lib.skx_ext_b(chips)!SKX_EXT_B_BGA1-IC,TBD!!!F109!VSS(1133)!!!!
S!GND!U2D1!G22!@baseboard_fab2_lib.baseboard_fab2(sch_1):page74_i20@chpset_lib.skx_ext_b(chips)!SKX_EXT_B_BGA1-IC,TBD!!!F109!VSS(1134)!!!!
S!GND!U2D1!G8!@baseboard_fab2_lib.baseboard_fab2(sch_1):page74_i20@chpset_lib.skx_ext_b(chips)!SKX_EXT_B_BGA1-IC,TBD!!!F109!VSS(1135)!!!!
S!GND!U2D1!G4!@baseboard_fab2_lib.baseboard_fab2(sch_1):page74_i20@chpset_lib.skx_ext_b(chips)!SKX_EXT_B_BGA1-IC,TBD!!!F109!VSS(1136)!!!!
S!GND!U2D1!F69!@baseboard_fab2_lib.baseboard_fab2(sch_1):page74_i20@chpset_lib.skx_ext_b(chips)!SKX_EXT_B_BGA1-IC,TBD!!!F109!VSS(1137)!!!!
S!GND!U2D1!F67!@baseboard_fab2_lib.baseboard_fab2(sch_1):page74_i20@chpset_lib.skx_ext_b(chips)!SKX_EXT_B_BGA1-IC,TBD!!!F109!VSS(1138)!!!!
S!GND!U2D1!F43!@baseboard_fab2_lib.baseboard_fab2(sch_1):page74_i20@chpset_lib.skx_ext_b(chips)!SKX_EXT_B_BGA1-IC,TBD!!!F109!VSS(1139)!!!!
S!GND!U2D1!F37!@baseboard_fab2_lib.baseboard_fab2(sch_1):page74_i20@chpset_lib.skx_ext_b(chips)!SKX_EXT_B_BGA1-IC,TBD!!!F109!VSS(1140)!!!!
S!GND!U2D1!F31!@baseboard_fab2_lib.baseboard_fab2(sch_1):page74_i20@chpset_lib.skx_ext_b(chips)!SKX_EXT_B_BGA1-IC,TBD!!!F109!VSS(1141)!!!!
S!GND!U2D1!F25!@baseboard_fab2_lib.baseboard_fab2(sch_1):page74_i20@chpset_lib.skx_ext_b(chips)!SKX_EXT_B_BGA1-IC,TBD!!!F109!VSS(1142)!!!!
S!GND!U2D1!F19!@baseboard_fab2_lib.baseboard_fab2(sch_1):page74_i20@chpset_lib.skx_ext_b(chips)!SKX_EXT_B_BGA1-IC,TBD!!!F109!VSS(1143)!!!!
S!GND!U2D1!F17!@baseboard_fab2_lib.baseboard_fab2(sch_1):page74_i20@chpset_lib.skx_ext_b(chips)!SKX_EXT_B_BGA1-IC,TBD!!!F109!VSS(1144)!!!!
S!GND!U2D1!F5!@baseboard_fab2_lib.baseboard_fab2(sch_1):page74_i20@chpset_lib.skx_ext_b(chips)!SKX_EXT_B_BGA1-IC,TBD!!!F109!VSS(1145)!!!!
S!GND!U2D1!E76!@baseboard_fab2_lib.baseboard_fab2(sch_1):page74_i20@chpset_lib.skx_ext_b(chips)!SKX_EXT_B_BGA1-IC,TBD!!!F109!VSS(1146)!!!!
S!GND!U2D1!E74!@baseboard_fab2_lib.baseboard_fab2(sch_1):page74_i20@chpset_lib.skx_ext_b(chips)!SKX_EXT_B_BGA1-IC,TBD!!!F109!VSS(1147)!!!!
S!GND!U2D1!E72!@baseboard_fab2_lib.baseboard_fab2(sch_1):page74_i20@chpset_lib.skx_ext_b(chips)!SKX_EXT_B_BGA1-IC,TBD!!!F109!VSS(1148)!!!!
S!GND!U2D1!E22!@baseboard_fab2_lib.baseboard_fab2(sch_1):page74_i20@chpset_lib.skx_ext_b(chips)!SKX_EXT_B_BGA1-IC,TBD!!!F109!VSS(1149)!!!!
S!GND!U2D1!E20!@baseboard_fab2_lib.baseboard_fab2(sch_1):page74_i20@chpset_lib.skx_ext_b(chips)!SKX_EXT_B_BGA1-IC,TBD!!!F109!VSS(1150)!!!!
S!GND!U2D1!E18!@baseboard_fab2_lib.baseboard_fab2(sch_1):page74_i20@chpset_lib.skx_ext_b(chips)!SKX_EXT_B_BGA1-IC,TBD!!!F109!VSS(1151)!!!!
S!GND!U2D1!E16!@baseboard_fab2_lib.baseboard_fab2(sch_1):page74_i20@chpset_lib.skx_ext_b(chips)!SKX_EXT_B_BGA1-IC,TBD!!!F109!VSS(1152)!!!!
S!GND!U2D1!E8!@baseboard_fab2_lib.baseboard_fab2(sch_1):page74_i20@chpset_lib.skx_ext_b(chips)!SKX_EXT_B_BGA1-IC,TBD!!!F109!VSS(1153)!!!!
S!GND!U2D1!E6!@baseboard_fab2_lib.baseboard_fab2(sch_1):page74_i20@chpset_lib.skx_ext_b(chips)!SKX_EXT_B_BGA1-IC,TBD!!!F109!VSS(1154)!!!!
S!GND!U2D1!D77!@baseboard_fab2_lib.baseboard_fab2(sch_1):page74_i20@chpset_lib.skx_ext_b(chips)!SKX_EXT_B_BGA1-IC,TBD!!!F109!VSS(1155)!!!!
S!GND!U2D1!D43!@baseboard_fab2_lib.baseboard_fab2(sch_1):page74_i20@chpset_lib.skx_ext_b(chips)!SKX_EXT_B_BGA1-IC,TBD!!!F109!VSS(1156)!!!!
S!GND!U2D1!D41!@baseboard_fab2_lib.baseboard_fab2(sch_1):page74_i20@chpset_lib.skx_ext_b(chips)!SKX_EXT_B_BGA1-IC,TBD!!!F109!VSS(1157)!!!!
S!GND!U2D1!D39!@baseboard_fab2_lib.baseboard_fab2(sch_1):page74_i20@chpset_lib.skx_ext_b(chips)!SKX_EXT_B_BGA1-IC,TBD!!!F109!VSS(1158)!!!!
S!GND!U2D1!D37!@baseboard_fab2_lib.baseboard_fab2(sch_1):page74_i20@chpset_lib.skx_ext_b(chips)!SKX_EXT_B_BGA1-IC,TBD!!!F109!VSS(1159)!!!!
S!GND!U2D1!D35!@baseboard_fab2_lib.baseboard_fab2(sch_1):page74_i20@chpset_lib.skx_ext_b(chips)!SKX_EXT_B_BGA1-IC,TBD!!!F109!VSS(1160)!!!!
S!GND!U2D1!D33!@baseboard_fab2_lib.baseboard_fab2(sch_1):page74_i20@chpset_lib.skx_ext_b(chips)!SKX_EXT_B_BGA1-IC,TBD!!!F109!VSS(1161)!!!!
S!GND!U2D1!D31!@baseboard_fab2_lib.baseboard_fab2(sch_1):page74_i20@chpset_lib.skx_ext_b(chips)!SKX_EXT_B_BGA1-IC,TBD!!!F109!VSS(1162)!!!!
S!GND!U2D1!D29!@baseboard_fab2_lib.baseboard_fab2(sch_1):page74_i20@chpset_lib.skx_ext_b(chips)!SKX_EXT_B_BGA1-IC,TBD!!!F109!VSS(1163)!!!!
S!GND!U2D1!D27!@baseboard_fab2_lib.baseboard_fab2(sch_1):page74_i20@chpset_lib.skx_ext_b(chips)!SKX_EXT_B_BGA1-IC,TBD!!!F109!VSS(1164)!!!!
S!GND!U2D1!D25!@baseboard_fab2_lib.baseboard_fab2(sch_1):page74_i20@chpset_lib.skx_ext_b(chips)!SKX_EXT_B_BGA1-IC,TBD!!!F109!VSS(1165)!!!!
S!GND!U2D1!D13!@baseboard_fab2_lib.baseboard_fab2(sch_1):page74_i20@chpset_lib.skx_ext_b(chips)!SKX_EXT_B_BGA1-IC,TBD!!!F109!VSS(1166)!!!!
S!GND!U2D1!D11!@baseboard_fab2_lib.baseboard_fab2(sch_1):page74_i20@chpset_lib.skx_ext_b(chips)!SKX_EXT_B_BGA1-IC,TBD!!!F109!VSS(1167)!!!!
S!GND!U2D1!CM27!@baseboard_fab2_lib.baseboard_fab2(sch_1):page74_i20@chpset_lib.skx_ext_b(chips)!SKX_EXT_B_BGA1-IC,TBD!!!F109!VSS(1168)!!!!
S!GND!U2D1!C78!@baseboard_fab2_lib.baseboard_fab2(sch_1):page74_i20@chpset_lib.skx_ext_b(chips)!SKX_EXT_B_BGA1-IC,TBD!!!F109!VSS(1169)!!!!
S!GND!U2D1!C76!@baseboard_fab2_lib.baseboard_fab2(sch_1):page74_i20@chpset_lib.skx_ext_b(chips)!SKX_EXT_B_BGA1-IC,TBD!!!F109!VSS(1170)!!!!
S!GND!U2D1!C16!@baseboard_fab2_lib.baseboard_fab2(sch_1):page74_i20@chpset_lib.skx_ext_b(chips)!SKX_EXT_B_BGA1-IC,TBD!!!F109!VSS(1171)!!!!
S!GND!U2D1!C14!@baseboard_fab2_lib.baseboard_fab2(sch_1):page74_i20@chpset_lib.skx_ext_b(chips)!SKX_EXT_B_BGA1-IC,TBD!!!F109!VSS(1172)!!!!
S!GND!U2D1!C12!@baseboard_fab2_lib.baseboard_fab2(sch_1):page74_i20@chpset_lib.skx_ext_b(chips)!SKX_EXT_B_BGA1-IC,TBD!!!F109!VSS(1173)!!!!
S!GND!U2D1!C10!@baseboard_fab2_lib.baseboard_fab2(sch_1):page74_i20@chpset_lib.skx_ext_b(chips)!SKX_EXT_B_BGA1-IC,TBD!!!F109!VSS(1174)!!!!
S!GND!U2D1!C8!@baseboard_fab2_lib.baseboard_fab2(sch_1):page74_i20@chpset_lib.skx_ext_b(chips)!SKX_EXT_B_BGA1-IC,TBD!!!F109!VSS(1175)!!!!
S!GND!U2D1!B75!@baseboard_fab2_lib.baseboard_fab2(sch_1):page74_i20@chpset_lib.skx_ext_b(chips)!SKX_EXT_B_BGA1-IC,TBD!!!F109!VSS(1176)!!!!
S!GND!U2D1!B71!@baseboard_fab2_lib.baseboard_fab2(sch_1):page74_i20@chpset_lib.skx_ext_b(chips)!SKX_EXT_B_BGA1-IC,TBD!!!F109!VSS(1177)!!!!
S!GND!U2D1!B37!@baseboard_fab2_lib.baseboard_fab2(sch_1):page74_i20@chpset_lib.skx_ext_b(chips)!SKX_EXT_B_BGA1-IC,TBD!!!F109!VSS(1178)!!!!
S!GND!U2D1!B31!@baseboard_fab2_lib.baseboard_fab2(sch_1):page74_i20@chpset_lib.skx_ext_b(chips)!SKX_EXT_B_BGA1-IC,TBD!!!F109!VSS(1179)!!!!
S!GND!U2D1!B25!@baseboard_fab2_lib.baseboard_fab2(sch_1):page74_i20@chpset_lib.skx_ext_b(chips)!SKX_EXT_B_BGA1-IC,TBD!!!F109!VSS(1180)!!!!
S!GND!U2D1!A38!@baseboard_fab2_lib.baseboard_fab2(sch_1):page74_i20@chpset_lib.skx_ext_b(chips)!SKX_EXT_B_BGA1-IC,TBD!!!F109!VSS(1181)!!!!
S!GND!U2D1!A36!@baseboard_fab2_lib.baseboard_fab2(sch_1):page74_i20@chpset_lib.skx_ext_b(chips)!SKX_EXT_B_BGA1-IC,TBD!!!F109!VSS(1182)!!!!
S!GND!U2D1!A32!@baseboard_fab2_lib.baseboard_fab2(sch_1):page74_i20@chpset_lib.skx_ext_b(chips)!SKX_EXT_B_BGA1-IC,TBD!!!F109!VSS(1183)!!!!
S!GND!U2D1!A30!@baseboard_fab2_lib.baseboard_fab2(sch_1):page74_i20@chpset_lib.skx_ext_b(chips)!SKX_EXT_B_BGA1-IC,TBD!!!F109!VSS(1184)!!!!
S!GND!U2D1!A26!@baseboard_fab2_lib.baseboard_fab2(sch_1):page74_i20@chpset_lib.skx_ext_b(chips)!SKX_EXT_B_BGA1-IC,TBD!!!F109!VSS(1185)!!!!
S!GND!U2D1!AC58!@baseboard_fab2_lib.baseboard_fab2(sch_1):page74_i20@chpset_lib.skx_ext_b(chips)!SKX_EXT_B_BGA1-IC,TBD!!!F109!VSS(1186)!!!!
S!GND!U2D1!AC60!@baseboard_fab2_lib.baseboard_fab2(sch_1):page74_i20@chpset_lib.skx_ext_b(chips)!SKX_EXT_B_BGA1-IC,TBD!!!F109!VSS(1187)!!!!
S!GND!U2D1!AC62!@baseboard_fab2_lib.baseboard_fab2(sch_1):page74_i20@chpset_lib.skx_ext_b(chips)!SKX_EXT_B_BGA1-IC,TBD!!!F109!VSS(1188)!!!!
S!GND!U2D1!AJ4!@baseboard_fab2_lib.baseboard_fab2(sch_1):page74_i20@chpset_lib.skx_ext_b(chips)!SKX_EXT_B_BGA1-IC,TBD!!!F109!VSS(1189)!!!!
S!GND!U2D1!AR6!@baseboard_fab2_lib.baseboard_fab2(sch_1):page74_i20@chpset_lib.skx_ext_b(chips)!SKX_EXT_B_BGA1-IC,TBD!!!F109!VSS(1190)!!!!
S!GND!U2D1!CG6!@baseboard_fab2_lib.baseboard_fab2(sch_1):page74_i20@chpset_lib.skx_ext_b(chips)!SKX_EXT_B_BGA1-IC,TBD!!!F109!VSS(1191)!!!!
S!GND!U2D1!CW6!@baseboard_fab2_lib.baseboard_fab2(sch_1):page74_i20@chpset_lib.skx_ext_b(chips)!SKX_EXT_B_BGA1-IC,TBD!!!F109!VSS(1192)!!!!
S!GND!U2D1!DE48!@baseboard_fab2_lib.baseboard_fab2(sch_1):page74_i20@chpset_lib.skx_ext_b(chips)!SKX_EXT_B_BGA1-IC,TBD!!!F109!VSS(1193)!!!!
S!GND!U2D1!DE50!@baseboard_fab2_lib.baseboard_fab2(sch_1):page74_i20@chpset_lib.skx_ext_b(chips)!SKX_EXT_B_BGA1-IC,TBD!!!F109!VSS(1194)!!!!
S!GND!U2D1!DE52!@baseboard_fab2_lib.baseboard_fab2(sch_1):page74_i20@chpset_lib.skx_ext_b(chips)!SKX_EXT_B_BGA1-IC,TBD!!!F109!VSS(1195)!!!!
S!GND!U2D1!DE54!@baseboard_fab2_lib.baseboard_fab2(sch_1):page74_i20@chpset_lib.skx_ext_b(chips)!SKX_EXT_B_BGA1-IC,TBD!!!F109!VSS(1196)!!!!
S!GND!U2D1!DE56!@baseboard_fab2_lib.baseboard_fab2(sch_1):page74_i20@chpset_lib.skx_ext_b(chips)!SKX_EXT_B_BGA1-IC,TBD!!!F109!VSS(1197)!!!!
S!GND!U2D1!DE58!@baseboard_fab2_lib.baseboard_fab2(sch_1):page74_i20@chpset_lib.skx_ext_b(chips)!SKX_EXT_B_BGA1-IC,TBD!!!F109!VSS(1198)!!!!
S!GND!U2D1!DE60!@baseboard_fab2_lib.baseboard_fab2(sch_1):page74_i20@chpset_lib.skx_ext_b(chips)!SKX_EXT_B_BGA1-IC,TBD!!!F109!VSS(1199)!!!!
S!GND!U2D1!DE62!@baseboard_fab2_lib.baseboard_fab2(sch_1):page74_i20@chpset_lib.skx_ext_b(chips)!SKX_EXT_B_BGA1-IC,TBD!!!F109!VSS(1200)!!!!
S!GND!U2D1!DL8!@baseboard_fab2_lib.baseboard_fab2(sch_1):page74_i20@chpset_lib.skx_ext_b(chips)!SKX_EXT_B_BGA1-IC,TBD!!!F109!VSS(1201)!!!!
S!GND!U2D1!DN18!@baseboard_fab2_lib.baseboard_fab2(sch_1):page74_i20@chpset_lib.skx_ext_b(chips)!SKX_EXT_B_BGA1-IC,TBD!!!F109!VSS(1202)!!!!
S!GND!U2D1!DP45!@baseboard_fab2_lib.baseboard_fab2(sch_1):page74_i20@chpset_lib.skx_ext_b(chips)!SKX_EXT_B_BGA1-IC,TBD!!!F109!VSS(1203)!!!!
S!GND!U2D1!DP47!@baseboard_fab2_lib.baseboard_fab2(sch_1):page74_i20@chpset_lib.skx_ext_b(chips)!SKX_EXT_B_BGA1-IC,TBD!!!F109!VSS(1204)!!!!
S!GND!U2D1!DP49!@baseboard_fab2_lib.baseboard_fab2(sch_1):page74_i20@chpset_lib.skx_ext_b(chips)!SKX_EXT_B_BGA1-IC,TBD!!!F109!VSS(1205)!!!!
S!GND!U2D1!DP51!@baseboard_fab2_lib.baseboard_fab2(sch_1):page74_i20@chpset_lib.skx_ext_b(chips)!SKX_EXT_B_BGA1-IC,TBD!!!F109!VSS(1206)!!!!
S!GND!U2D1!DP53!@baseboard_fab2_lib.baseboard_fab2(sch_1):page74_i20@chpset_lib.skx_ext_b(chips)!SKX_EXT_B_BGA1-IC,TBD!!!F109!VSS(1207)!!!!
S!GND!U2D1!DP55!@baseboard_fab2_lib.baseboard_fab2(sch_1):page74_i20@chpset_lib.skx_ext_b(chips)!SKX_EXT_B_BGA1-IC,TBD!!!F109!VSS(1208)!!!!
S!GND!U2D1!DP57!@baseboard_fab2_lib.baseboard_fab2(sch_1):page74_i20@chpset_lib.skx_ext_b(chips)!SKX_EXT_B_BGA1-IC,TBD!!!F109!VSS(1209)!!!!
S!GND!U2D1!DP59!@baseboard_fab2_lib.baseboard_fab2(sch_1):page74_i20@chpset_lib.skx_ext_b(chips)!SKX_EXT_B_BGA1-IC,TBD!!!F109!VSS(1210)!!!!
S!GND!U2D1!DP61!@baseboard_fab2_lib.baseboard_fab2(sch_1):page74_i20@chpset_lib.skx_ext_b(chips)!SKX_EXT_B_BGA1-IC,TBD!!!F109!VSS(1211)!!!!
S!GND!U2D1!DP63!@baseboard_fab2_lib.baseboard_fab2(sch_1):page74_i20@chpset_lib.skx_ext_b(chips)!SKX_EXT_B_BGA1-IC,TBD!!!F109!VSS(1212)!!!!
S!GND!U2D1!DP9!@baseboard_fab2_lib.baseboard_fab2(sch_1):page74_i20@chpset_lib.skx_ext_b(chips)!SKX_EXT_B_BGA1-IC,TBD!!!F109!VSS(1213)!!!!
S!GND!U2D1!DV19!@baseboard_fab2_lib.baseboard_fab2(sch_1):page74_i20@chpset_lib.skx_ext_b(chips)!SKX_EXT_B_BGA1-IC,TBD!!!F109!VSS(1214)!!!!
S!GND!U2D1!DY45!@baseboard_fab2_lib.baseboard_fab2(sch_1):page74_i20@chpset_lib.skx_ext_b(chips)!SKX_EXT_B_BGA1-IC,TBD!!!F109!VSS(1215)!!!!
S!GND!U2D1!DY47!@baseboard_fab2_lib.baseboard_fab2(sch_1):page74_i20@chpset_lib.skx_ext_b(chips)!SKX_EXT_B_BGA1-IC,TBD!!!F109!VSS(1216)!!!!
S!GND!U2D1!DY49!@baseboard_fab2_lib.baseboard_fab2(sch_1):page74_i20@chpset_lib.skx_ext_b(chips)!SKX_EXT_B_BGA1-IC,TBD!!!F109!VSS(1217)!!!!
S!GND!U2D1!DY51!@baseboard_fab2_lib.baseboard_fab2(sch_1):page74_i20@chpset_lib.skx_ext_b(chips)!SKX_EXT_B_BGA1-IC,TBD!!!F109!VSS(1218)!!!!
S!GND!U2D1!DY53!@baseboard_fab2_lib.baseboard_fab2(sch_1):page74_i20@chpset_lib.skx_ext_b(chips)!SKX_EXT_B_BGA1-IC,TBD!!!F109!VSS(1219)!!!!
S!GND!U2D1!DY55!@baseboard_fab2_lib.baseboard_fab2(sch_1):page74_i20@chpset_lib.skx_ext_b(chips)!SKX_EXT_B_BGA1-IC,TBD!!!F109!VSS(1220)!!!!
S!GND!U2D1!DY57!@baseboard_fab2_lib.baseboard_fab2(sch_1):page74_i20@chpset_lib.skx_ext_b(chips)!SKX_EXT_B_BGA1-IC,TBD!!!F109!VSS(1221)!!!!
S!GND!U2D1!DY59!@baseboard_fab2_lib.baseboard_fab2(sch_1):page74_i20@chpset_lib.skx_ext_b(chips)!SKX_EXT_B_BGA1-IC,TBD!!!F109!VSS(1222)!!!!
S!GND!U2D1!DY61!@baseboard_fab2_lib.baseboard_fab2(sch_1):page74_i20@chpset_lib.skx_ext_b(chips)!SKX_EXT_B_BGA1-IC,TBD!!!F109!VSS(1223)!!!!
S!GND!U2D1!DY63!@baseboard_fab2_lib.baseboard_fab2(sch_1):page74_i20@chpset_lib.skx_ext_b(chips)!SKX_EXT_B_BGA1-IC,TBD!!!F109!VSS(1224)!!!!
S!GND!U2D1!EA14!@baseboard_fab2_lib.baseboard_fab2(sch_1):page74_i20@chpset_lib.skx_ext_b(chips)!SKX_EXT_B_BGA1-IC,TBD!!!F109!VSS(1225)!!!!
S!GND!U2D1!L8!@baseboard_fab2_lib.baseboard_fab2(sch_1):page74_i20@chpset_lib.skx_ext_b(chips)!SKX_EXT_B_BGA1-IC,TBD!!!F109!VSS(1226)!!!!
S!GND!U2D1!V11!@baseboard_fab2_lib.baseboard_fab2(sch_1):page74_i20@chpset_lib.skx_ext_b(chips)!SKX_EXT_B_BGA1-IC,TBD!!!F109!VSS(1227)!!!!
S!GND!U2D1!T37!@baseboard_fab2_lib.baseboard_fab2(sch_1):page74_i21@chpset_lib.skx_ext_b(chips)!SKX_EXT_B_BGA1-IC,TBD!!!F108!VSS(1000)!!!!
S!GND!U2D1!T35!@baseboard_fab2_lib.baseboard_fab2(sch_1):page74_i21@chpset_lib.skx_ext_b(chips)!SKX_EXT_B_BGA1-IC,TBD!!!F108!VSS(1001)!!!!
S!GND!U2D1!T31!@baseboard_fab2_lib.baseboard_fab2(sch_1):page74_i21@chpset_lib.skx_ext_b(chips)!SKX_EXT_B_BGA1-IC,TBD!!!F108!VSS(1002)!!!!
S!GND!U2D1!T29!@baseboard_fab2_lib.baseboard_fab2(sch_1):page74_i21@chpset_lib.skx_ext_b(chips)!SKX_EXT_B_BGA1-IC,TBD!!!F108!VSS(1003)!!!!
S!GND!U2D1!T25!@baseboard_fab2_lib.baseboard_fab2(sch_1):page74_i21@chpset_lib.skx_ext_b(chips)!SKX_EXT_B_BGA1-IC,TBD!!!F108!VSS(1004)!!!!
S!GND!U2D1!T17!@baseboard_fab2_lib.baseboard_fab2(sch_1):page74_i21@chpset_lib.skx_ext_b(chips)!SKX_EXT_B_BGA1-IC,TBD!!!F108!VSS(1005)!!!!
S!GND!U2D1!T13!@baseboard_fab2_lib.baseboard_fab2(sch_1):page74_i21@chpset_lib.skx_ext_b(chips)!SKX_EXT_B_BGA1-IC,TBD!!!F108!VSS(1006)!!!!
S!GND!U2D1!R86!@baseboard_fab2_lib.baseboard_fab2(sch_1):page74_i21@chpset_lib.skx_ext_b(chips)!SKX_EXT_B_BGA1-IC,TBD!!!F108!VSS(1007)!!!!
S!GND!U2D1!R78!@baseboard_fab2_lib.baseboard_fab2(sch_1):page74_i21@chpset_lib.skx_ext_b(chips)!SKX_EXT_B_BGA1-IC,TBD!!!F108!VSS(1008)!!!!
S!GND!U2D1!R72!@baseboard_fab2_lib.baseboard_fab2(sch_1):page74_i21@chpset_lib.skx_ext_b(chips)!SKX_EXT_B_BGA1-IC,TBD!!!F108!VSS(1009)!!!!
S!GND!U2D1!R68!@baseboard_fab2_lib.baseboard_fab2(sch_1):page74_i21@chpset_lib.skx_ext_b(chips)!SKX_EXT_B_BGA1-IC,TBD!!!F108!VSS(1010)!!!!
S!GND!U2D1!R40!@baseboard_fab2_lib.baseboard_fab2(sch_1):page74_i21@chpset_lib.skx_ext_b(chips)!SKX_EXT_B_BGA1-IC,TBD!!!F108!VSS(1011)!!!!
S!GND!U2D1!R38!@baseboard_fab2_lib.baseboard_fab2(sch_1):page74_i21@chpset_lib.skx_ext_b(chips)!SKX_EXT_B_BGA1-IC,TBD!!!F108!VSS(1012)!!!!
S!GND!U2D1!R34!@baseboard_fab2_lib.baseboard_fab2(sch_1):page74_i21@chpset_lib.skx_ext_b(chips)!SKX_EXT_B_BGA1-IC,TBD!!!F108!VSS(1013)!!!!
S!GND!U2D1!R32!@baseboard_fab2_lib.baseboard_fab2(sch_1):page74_i21@chpset_lib.skx_ext_b(chips)!SKX_EXT_B_BGA1-IC,TBD!!!F108!VSS(1014)!!!!
S!GND!U2D1!R28!@baseboard_fab2_lib.baseboard_fab2(sch_1):page74_i21@chpset_lib.skx_ext_b(chips)!SKX_EXT_B_BGA1-IC,TBD!!!F108!VSS(1015)!!!!
S!GND!U2D1!R26!@baseboard_fab2_lib.baseboard_fab2(sch_1):page74_i21@chpset_lib.skx_ext_b(chips)!SKX_EXT_B_BGA1-IC,TBD!!!F108!VSS(1016)!!!!
S!GND!U2D1!R22!@baseboard_fab2_lib.baseboard_fab2(sch_1):page74_i21@chpset_lib.skx_ext_b(chips)!SKX_EXT_B_BGA1-IC,TBD!!!F108!VSS(1017)!!!!
S!GND!U2D1!R4!@baseboard_fab2_lib.baseboard_fab2(sch_1):page74_i21@chpset_lib.skx_ext_b(chips)!SKX_EXT_B_BGA1-IC,TBD!!!F108!VSS(1018)!!!!
S!GND!U2D1!R2!@baseboard_fab2_lib.baseboard_fab2(sch_1):page74_i21@chpset_lib.skx_ext_b(chips)!SKX_EXT_B_BGA1-IC,TBD!!!F108!VSS(1019)!!!!
S!GND!U2D1!R18!@baseboard_fab2_lib.baseboard_fab2(sch_1):page74_i21@chpset_lib.skx_ext_b(chips)!SKX_EXT_B_BGA1-IC,TBD!!!F108!VSS(1020)!!!!
S!GND!U2D1!R14!@baseboard_fab2_lib.baseboard_fab2(sch_1):page74_i21@chpset_lib.skx_ext_b(chips)!SKX_EXT_B_BGA1-IC,TBD!!!F108!VSS(1021)!!!!
S!GND!U2D1!P83!@baseboard_fab2_lib.baseboard_fab2(sch_1):page74_i21@chpset_lib.skx_ext_b(chips)!SKX_EXT_B_BGA1-IC,TBD!!!F108!VSS(1022)!!!!
S!GND!U2D1!P81!@baseboard_fab2_lib.baseboard_fab2(sch_1):page74_i21@chpset_lib.skx_ext_b(chips)!SKX_EXT_B_BGA1-IC,TBD!!!F108!VSS(1023)!!!!
S!GND!U2D1!P71!@baseboard_fab2_lib.baseboard_fab2(sch_1):page74_i21@chpset_lib.skx_ext_b(chips)!SKX_EXT_B_BGA1-IC,TBD!!!F108!VSS(1024)!!!!
S!GND!U2D1!P69!@baseboard_fab2_lib.baseboard_fab2(sch_1):page74_i21@chpset_lib.skx_ext_b(chips)!SKX_EXT_B_BGA1-IC,TBD!!!F108!VSS(1025)!!!!
S!GND!U2D1!P67!@baseboard_fab2_lib.baseboard_fab2(sch_1):page74_i21@chpset_lib.skx_ext_b(chips)!SKX_EXT_B_BGA1-IC,TBD!!!F108!VSS(1026)!!!!
S!GND!U2D1!P39!@baseboard_fab2_lib.baseboard_fab2(sch_1):page74_i21@chpset_lib.skx_ext_b(chips)!SKX_EXT_B_BGA1-IC,TBD!!!F108!VSS(1027)!!!!
S!GND!U2D1!P33!@baseboard_fab2_lib.baseboard_fab2(sch_1):page74_i21@chpset_lib.skx_ext_b(chips)!SKX_EXT_B_BGA1-IC,TBD!!!F108!VSS(1028)!!!!
S!GND!U2D1!P27!@baseboard_fab2_lib.baseboard_fab2(sch_1):page74_i21@chpset_lib.skx_ext_b(chips)!SKX_EXT_B_BGA1-IC,TBD!!!F108!VSS(1029)!!!!
S!GND!U2D1!P15!@baseboard_fab2_lib.baseboard_fab2(sch_1):page74_i21@chpset_lib.skx_ext_b(chips)!SKX_EXT_B_BGA1-IC,TBD!!!F108!VSS(1030)!!!!
S!GND!U2D1!P11!@baseboard_fab2_lib.baseboard_fab2(sch_1):page74_i21@chpset_lib.skx_ext_b(chips)!SKX_EXT_B_BGA1-IC,TBD!!!F108!VSS(1031)!!!!
S!GND!U2D1!N8!@baseboard_fab2_lib.baseboard_fab2(sch_1):page74_i21@chpset_lib.skx_ext_b(chips)!SKX_EXT_B_BGA1-IC,TBD!!!F108!VSS(1032)!!!!
S!GND!U2D1!N4!@baseboard_fab2_lib.baseboard_fab2(sch_1):page74_i21@chpset_lib.skx_ext_b(chips)!SKX_EXT_B_BGA1-IC,TBD!!!F108!VSS(1033)!!!!
S!GND!U2D1!N78!@baseboard_fab2_lib.baseboard_fab2(sch_1):page74_i21@chpset_lib.skx_ext_b(chips)!SKX_EXT_B_BGA1-IC,TBD!!!F108!VSS(1034)!!!!
S!GND!U2D1!N76!@baseboard_fab2_lib.baseboard_fab2(sch_1):page74_i21@chpset_lib.skx_ext_b(chips)!SKX_EXT_B_BGA1-IC,TBD!!!F108!VSS(1035)!!!!
S!GND!U2D1!N74!@baseboard_fab2_lib.baseboard_fab2(sch_1):page74_i21@chpset_lib.skx_ext_b(chips)!SKX_EXT_B_BGA1-IC,TBD!!!F108!VSS(1036)!!!!
S!GND!U2D1!N72!@baseboard_fab2_lib.baseboard_fab2(sch_1):page74_i21@chpset_lib.skx_ext_b(chips)!SKX_EXT_B_BGA1-IC,TBD!!!F108!VSS(1037)!!!!
S!GND!U2D1!N70!@baseboard_fab2_lib.baseboard_fab2(sch_1):page74_i21@chpset_lib.skx_ext_b(chips)!SKX_EXT_B_BGA1-IC,TBD!!!F108!VSS(1038)!!!!
S!GND!U2D1!N66!@baseboard_fab2_lib.baseboard_fab2(sch_1):page74_i21@chpset_lib.skx_ext_b(chips)!SKX_EXT_B_BGA1-IC,TBD!!!F108!VSS(1039)!!!!
S!GND!U2D1!N6!@baseboard_fab2_lib.baseboard_fab2(sch_1):page74_i21@chpset_lib.skx_ext_b(chips)!SKX_EXT_B_BGA1-IC,TBD!!!F108!VSS(1040)!!!!
S!GND!U2D1!N22!@baseboard_fab2_lib.baseboard_fab2(sch_1):page74_i21@chpset_lib.skx_ext_b(chips)!SKX_EXT_B_BGA1-IC,TBD!!!F108!VSS(1041)!!!!
S!GND!U2D1!N20!@baseboard_fab2_lib.baseboard_fab2(sch_1):page74_i21@chpset_lib.skx_ext_b(chips)!SKX_EXT_B_BGA1-IC,TBD!!!F108!VSS(1042)!!!!
S!GND!U2D1!DM19!@baseboard_fab2_lib.baseboard_fab2(sch_1):page74_i21@chpset_lib.skx_ext_b(chips)!SKX_EXT_B_BGA1-IC,TBD!!!F108!VSS(1043)!!!!
S!GND!U2D1!M85!@baseboard_fab2_lib.baseboard_fab2(sch_1):page74_i21@chpset_lib.skx_ext_b(chips)!SKX_EXT_B_BGA1-IC,TBD!!!F108!VSS(1044)!!!!
S!GND!U2D1!M83!@baseboard_fab2_lib.baseboard_fab2(sch_1):page74_i21@chpset_lib.skx_ext_b(chips)!SKX_EXT_B_BGA1-IC,TBD!!!F108!VSS(1045)!!!!
S!GND!U2D1!M79!@baseboard_fab2_lib.baseboard_fab2(sch_1):page74_i21@chpset_lib.skx_ext_b(chips)!SKX_EXT_B_BGA1-IC,TBD!!!F108!VSS(1046)!!!!
S!GND!U2D1!M71!@baseboard_fab2_lib.baseboard_fab2(sch_1):page74_i21@chpset_lib.skx_ext_b(chips)!SKX_EXT_B_BGA1-IC,TBD!!!F108!VSS(1047)!!!!
S!GND!U2D1!M65!@baseboard_fab2_lib.baseboard_fab2(sch_1):page74_i21@chpset_lib.skx_ext_b(chips)!SKX_EXT_B_BGA1-IC,TBD!!!F108!VSS(1048)!!!!
S!GND!U2D1!M43!@baseboard_fab2_lib.baseboard_fab2(sch_1):page74_i21@chpset_lib.skx_ext_b(chips)!SKX_EXT_B_BGA1-IC,TBD!!!F108!VSS(1049)!!!!
S!GND!U2D1!M41!@baseboard_fab2_lib.baseboard_fab2(sch_1):page74_i21@chpset_lib.skx_ext_b(chips)!SKX_EXT_B_BGA1-IC,TBD!!!F108!VSS(1050)!!!!
S!GND!U2D1!M39!@baseboard_fab2_lib.baseboard_fab2(sch_1):page74_i21@chpset_lib.skx_ext_b(chips)!SKX_EXT_B_BGA1-IC,TBD!!!F108!VSS(1051)!!!!
S!GND!U2D1!M37!@baseboard_fab2_lib.baseboard_fab2(sch_1):page74_i21@chpset_lib.skx_ext_b(chips)!SKX_EXT_B_BGA1-IC,TBD!!!F108!VSS(1052)!!!!
S!GND!U2D1!M35!@baseboard_fab2_lib.baseboard_fab2(sch_1):page74_i21@chpset_lib.skx_ext_b(chips)!SKX_EXT_B_BGA1-IC,TBD!!!F108!VSS(1053)!!!!
S!GND!U2D1!M33!@baseboard_fab2_lib.baseboard_fab2(sch_1):page74_i21@chpset_lib.skx_ext_b(chips)!SKX_EXT_B_BGA1-IC,TBD!!!F108!VSS(1054)!!!!
S!GND!U2D1!M31!@baseboard_fab2_lib.baseboard_fab2(sch_1):page74_i21@chpset_lib.skx_ext_b(chips)!SKX_EXT_B_BGA1-IC,TBD!!!F108!VSS(1055)!!!!
S!GND!U2D1!M29!@baseboard_fab2_lib.baseboard_fab2(sch_1):page74_i21@chpset_lib.skx_ext_b(chips)!SKX_EXT_B_BGA1-IC,TBD!!!F108!VSS(1056)!!!!
S!GND!U2D1!M27!@baseboard_fab2_lib.baseboard_fab2(sch_1):page74_i21@chpset_lib.skx_ext_b(chips)!SKX_EXT_B_BGA1-IC,TBD!!!F108!VSS(1057)!!!!
S!GND!U2D1!M25!@baseboard_fab2_lib.baseboard_fab2(sch_1):page74_i21@chpset_lib.skx_ext_b(chips)!SKX_EXT_B_BGA1-IC,TBD!!!F108!VSS(1058)!!!!
S!GND!U2D1!M23!@baseboard_fab2_lib.baseboard_fab2(sch_1):page74_i21@chpset_lib.skx_ext_b(chips)!SKX_EXT_B_BGA1-IC,TBD!!!F108!VSS(1059)!!!!
S!GND!U2D1!M19!@baseboard_fab2_lib.baseboard_fab2(sch_1):page74_i21@chpset_lib.skx_ext_b(chips)!SKX_EXT_B_BGA1-IC,TBD!!!F108!VSS(1060)!!!!
S!GND!U2D1!M17!@baseboard_fab2_lib.baseboard_fab2(sch_1):page74_i21@chpset_lib.skx_ext_b(chips)!SKX_EXT_B_BGA1-IC,TBD!!!F108!VSS(1061)!!!!
S!GND!U2D1!M15!@baseboard_fab2_lib.baseboard_fab2(sch_1):page74_i21@chpset_lib.skx_ext_b(chips)!SKX_EXT_B_BGA1-IC,TBD!!!F108!VSS(1062)!!!!
S!GND!U2D1!CT7!@baseboard_fab2_lib.baseboard_fab2(sch_1):page74_i21@chpset_lib.skx_ext_b(chips)!SKX_EXT_B_BGA1-IC,TBD!!!F108!VSS(1063)!!!!
S!GND!U2D1!BT9!@baseboard_fab2_lib.baseboard_fab2(sch_1):page74_i21@chpset_lib.skx_ext_b(chips)!SKX_EXT_B_BGA1-IC,TBD!!!F108!VSS(1064)!!!!
S!GND!U2D1!L82!@baseboard_fab2_lib.baseboard_fab2(sch_1):page74_i21@chpset_lib.skx_ext_b(chips)!SKX_EXT_B_BGA1-IC,TBD!!!F108!VSS(1065)!!!!
S!GND!U2D1!L80!@baseboard_fab2_lib.baseboard_fab2(sch_1):page74_i21@chpset_lib.skx_ext_b(chips)!SKX_EXT_B_BGA1-IC,TBD!!!F108!VSS(1066)!!!!
S!GND!U2D1!L78!@baseboard_fab2_lib.baseboard_fab2(sch_1):page74_i21@chpset_lib.skx_ext_b(chips)!SKX_EXT_B_BGA1-IC,TBD!!!F108!VSS(1067)!!!!
S!GND!U2D1!AB69!@baseboard_fab2_lib.baseboard_fab2(sch_1):page74_i22@chpset_lib.skx_ext_b(chips)!SKX_EXT_B_BGA1-IC,TBD!!!F107!VSS(908)!!!!
S!GND!U2D1!AB65!@baseboard_fab2_lib.baseboard_fab2(sch_1):page74_i22@chpset_lib.skx_ext_b(chips)!SKX_EXT_B_BGA1-IC,TBD!!!F107!VSS(909)!!!!
S!GND!U2D1!AB41!@baseboard_fab2_lib.baseboard_fab2(sch_1):page74_i22@chpset_lib.skx_ext_b(chips)!SKX_EXT_B_BGA1-IC,TBD!!!F107!VSS(910)!!!!
S!GND!U2D1!AB37!@baseboard_fab2_lib.baseboard_fab2(sch_1):page74_i22@chpset_lib.skx_ext_b(chips)!SKX_EXT_B_BGA1-IC,TBD!!!F107!VSS(911)!!!!
S!GND!U2D1!AB35!@baseboard_fab2_lib.baseboard_fab2(sch_1):page74_i22@chpset_lib.skx_ext_b(chips)!SKX_EXT_B_BGA1-IC,TBD!!!F107!VSS(912)!!!!
S!GND!U2D1!AB31!@baseboard_fab2_lib.baseboard_fab2(sch_1):page74_i22@chpset_lib.skx_ext_b(chips)!SKX_EXT_B_BGA1-IC,TBD!!!F107!VSS(913)!!!!
S!GND!U2D1!AB29!@baseboard_fab2_lib.baseboard_fab2(sch_1):page74_i22@chpset_lib.skx_ext_b(chips)!SKX_EXT_B_BGA1-IC,TBD!!!F107!VSS(914)!!!!
S!GND!U2D1!AB25!@baseboard_fab2_lib.baseboard_fab2(sch_1):page74_i22@chpset_lib.skx_ext_b(chips)!SKX_EXT_B_BGA1-IC,TBD!!!F107!VSS(915)!!!!
S!GND!U2D1!AB23!@baseboard_fab2_lib.baseboard_fab2(sch_1):page74_i22@chpset_lib.skx_ext_b(chips)!SKX_EXT_B_BGA1-IC,TBD!!!F107!VSS(916)!!!!
S!GND!U2D1!AB21!@baseboard_fab2_lib.baseboard_fab2(sch_1):page74_i22@chpset_lib.skx_ext_b(chips)!SKX_EXT_B_BGA1-IC,TBD!!!F107!VSS(917)!!!!
S!GND!U2D1!AB11!@baseboard_fab2_lib.baseboard_fab2(sch_1):page74_i22@chpset_lib.skx_ext_b(chips)!SKX_EXT_B_BGA1-IC,TBD!!!F107!VSS(918)!!!!
S!GND!U2D1!AB5!@baseboard_fab2_lib.baseboard_fab2(sch_1):page74_i22@chpset_lib.skx_ext_b(chips)!SKX_EXT_B_BGA1-IC,TBD!!!F107!VSS(919)!!!!
S!GND!U2D1!AB1!@baseboard_fab2_lib.baseboard_fab2(sch_1):page74_i22@chpset_lib.skx_ext_b(chips)!SKX_EXT_B_BGA1-IC,TBD!!!F107!VSS(920)!!!!
S!GND!U2D1!AA82!@baseboard_fab2_lib.baseboard_fab2(sch_1):page74_i22@chpset_lib.skx_ext_b(chips)!SKX_EXT_B_BGA1-IC,TBD!!!F107!VSS(921)!!!!
S!GND!U2D1!AA80!@baseboard_fab2_lib.baseboard_fab2(sch_1):page74_i22@chpset_lib.skx_ext_b(chips)!SKX_EXT_B_BGA1-IC,TBD!!!F107!VSS(922)!!!!
S!GND!U2D1!AA78!@baseboard_fab2_lib.baseboard_fab2(sch_1):page74_i22@chpset_lib.skx_ext_b(chips)!SKX_EXT_B_BGA1-IC,TBD!!!F107!VSS(923)!!!!
S!GND!U2D1!AA76!@baseboard_fab2_lib.baseboard_fab2(sch_1):page74_i22@chpset_lib.skx_ext_b(chips)!SKX_EXT_B_BGA1-IC,TBD!!!F107!VSS(924)!!!!
S!GND!U2D1!AA68!@baseboard_fab2_lib.baseboard_fab2(sch_1):page74_i22@chpset_lib.skx_ext_b(chips)!SKX_EXT_B_BGA1-IC,TBD!!!F107!VSS(925)!!!!
S!GND!U2D1!AA66!@baseboard_fab2_lib.baseboard_fab2(sch_1):page74_i22@chpset_lib.skx_ext_b(chips)!SKX_EXT_B_BGA1-IC,TBD!!!F107!VSS(926)!!!!
S!GND!U2D1!AA64!@baseboard_fab2_lib.baseboard_fab2(sch_1):page74_i22@chpset_lib.skx_ext_b(chips)!SKX_EXT_B_BGA1-IC,TBD!!!F107!VSS(927)!!!!
S!GND!U2D1!AA42!@baseboard_fab2_lib.baseboard_fab2(sch_1):page74_i22@chpset_lib.skx_ext_b(chips)!SKX_EXT_B_BGA1-IC,TBD!!!F107!VSS(928)!!!!
S!GND!U2D1!AA36!@baseboard_fab2_lib.baseboard_fab2(sch_1):page74_i22@chpset_lib.skx_ext_b(chips)!SKX_EXT_B_BGA1-IC,TBD!!!F107!VSS(929)!!!!
S!GND!U2D1!AA30!@baseboard_fab2_lib.baseboard_fab2(sch_1):page74_i22@chpset_lib.skx_ext_b(chips)!SKX_EXT_B_BGA1-IC,TBD!!!F107!VSS(930)!!!!
S!GND!U2D1!AA24!@baseboard_fab2_lib.baseboard_fab2(sch_1):page74_i22@chpset_lib.skx_ext_b(chips)!SKX_EXT_B_BGA1-IC,TBD!!!F107!VSS(931)!!!!
S!GND!U2D1!AA22!@baseboard_fab2_lib.baseboard_fab2(sch_1):page74_i22@chpset_lib.skx_ext_b(chips)!SKX_EXT_B_BGA1-IC,TBD!!!F107!VSS(932)!!!!
S!GND!U2D1!AA18!@baseboard_fab2_lib.baseboard_fab2(sch_1):page74_i22@chpset_lib.skx_ext_b(chips)!SKX_EXT_B_BGA1-IC,TBD!!!F107!VSS(933)!!!!
S!GND!U2D1!AA16!@baseboard_fab2_lib.baseboard_fab2(sch_1):page74_i21@chpset_lib.skx_ext_b(chips)!SKX_EXT_B_BGA1-IC,TBD!!!F108!VSS(934)!!!!
S!GND!U2D1!AA4!@baseboard_fab2_lib.baseboard_fab2(sch_1):page74_i21@chpset_lib.skx_ext_b(chips)!SKX_EXT_B_BGA1-IC,TBD!!!F108!VSS(935)!!!!
S!GND!U2D1!Y85!@baseboard_fab2_lib.baseboard_fab2(sch_1):page74_i21@chpset_lib.skx_ext_b(chips)!SKX_EXT_B_BGA1-IC,TBD!!!F108!VSS(936)!!!!
S!GND!U2D1!Y83!@baseboard_fab2_lib.baseboard_fab2(sch_1):page74_i21@chpset_lib.skx_ext_b(chips)!SKX_EXT_B_BGA1-IC,TBD!!!F108!VSS(937)!!!!
S!GND!U2D1!Y81!@baseboard_fab2_lib.baseboard_fab2(sch_1):page74_i21@chpset_lib.skx_ext_b(chips)!SKX_EXT_B_BGA1-IC,TBD!!!F108!VSS(938)!!!!
S!GND!U2D1!Y79!@baseboard_fab2_lib.baseboard_fab2(sch_1):page74_i21@chpset_lib.skx_ext_b(chips)!SKX_EXT_B_BGA1-IC,TBD!!!F108!VSS(939)!!!!
S!GND!U2D1!Y73!@baseboard_fab2_lib.baseboard_fab2(sch_1):page74_i21@chpset_lib.skx_ext_b(chips)!SKX_EXT_B_BGA1-IC,TBD!!!F108!VSS(940)!!!!
S!GND!U2D1!Y71!@baseboard_fab2_lib.baseboard_fab2(sch_1):page74_i21@chpset_lib.skx_ext_b(chips)!SKX_EXT_B_BGA1-IC,TBD!!!F108!VSS(941)!!!!
S!GND!U2D1!Y9!@baseboard_fab2_lib.baseboard_fab2(sch_1):page74_i21@chpset_lib.skx_ext_b(chips)!SKX_EXT_B_BGA1-IC,TBD!!!F108!VSS(942)!!!!
S!GND!U2D1!Y7!@baseboard_fab2_lib.baseboard_fab2(sch_1):page74_i21@chpset_lib.skx_ext_b(chips)!SKX_EXT_B_BGA1-IC,TBD!!!F108!VSS(943)!!!!
S!GND!U2D1!Y67!@baseboard_fab2_lib.baseboard_fab2(sch_1):page74_i21@chpset_lib.skx_ext_b(chips)!SKX_EXT_B_BGA1-IC,TBD!!!F108!VSS(944)!!!!
S!GND!U2D1!Y5!@baseboard_fab2_lib.baseboard_fab2(sch_1):page74_i21@chpset_lib.skx_ext_b(chips)!SKX_EXT_B_BGA1-IC,TBD!!!F108!VSS(945)!!!!
S!GND!U2D1!Y17!@baseboard_fab2_lib.baseboard_fab2(sch_1):page74_i21@chpset_lib.skx_ext_b(chips)!SKX_EXT_B_BGA1-IC,TBD!!!F108!VSS(946)!!!!
S!GND!U2D1!Y15!@baseboard_fab2_lib.baseboard_fab2(sch_1):page74_i21@chpset_lib.skx_ext_b(chips)!SKX_EXT_B_BGA1-IC,TBD!!!F108!VSS(947)!!!!
S!GND!U2D1!W82!@baseboard_fab2_lib.baseboard_fab2(sch_1):page74_i21@chpset_lib.skx_ext_b(chips)!SKX_EXT_B_BGA1-IC,TBD!!!F108!VSS(948)!!!!
S!GND!U2D1!W78!@baseboard_fab2_lib.baseboard_fab2(sch_1):page74_i21@chpset_lib.skx_ext_b(chips)!SKX_EXT_B_BGA1-IC,TBD!!!F108!VSS(949)!!!!
S!GND!U2D1!W74!@baseboard_fab2_lib.baseboard_fab2(sch_1):page74_i21@chpset_lib.skx_ext_b(chips)!SKX_EXT_B_BGA1-IC,TBD!!!F108!VSS(950)!!!!
S!GND!U2D1!W68!@baseboard_fab2_lib.baseboard_fab2(sch_1):page74_i21@chpset_lib.skx_ext_b(chips)!SKX_EXT_B_BGA1-IC,TBD!!!F108!VSS(951)!!!!
S!GND!U2D1!W42!@baseboard_fab2_lib.baseboard_fab2(sch_1):page74_i21@chpset_lib.skx_ext_b(chips)!SKX_EXT_B_BGA1-IC,TBD!!!F108!VSS(952)!!!!
S!GND!U2D1!W40!@baseboard_fab2_lib.baseboard_fab2(sch_1):page74_i21@chpset_lib.skx_ext_b(chips)!SKX_EXT_B_BGA1-IC,TBD!!!F108!VSS(953)!!!!
S!GND!U2D1!W38!@baseboard_fab2_lib.baseboard_fab2(sch_1):page74_i21@chpset_lib.skx_ext_b(chips)!SKX_EXT_B_BGA1-IC,TBD!!!F108!VSS(954)!!!!
S!GND!U2D1!W36!@baseboard_fab2_lib.baseboard_fab2(sch_1):page74_i21@chpset_lib.skx_ext_b(chips)!SKX_EXT_B_BGA1-IC,TBD!!!F108!VSS(955)!!!!
S!GND!U2D1!W34!@baseboard_fab2_lib.baseboard_fab2(sch_1):page74_i21@chpset_lib.skx_ext_b(chips)!SKX_EXT_B_BGA1-IC,TBD!!!F108!VSS(956)!!!!
S!GND!U2D1!W32!@baseboard_fab2_lib.baseboard_fab2(sch_1):page74_i21@chpset_lib.skx_ext_b(chips)!SKX_EXT_B_BGA1-IC,TBD!!!F108!VSS(957)!!!!
S!GND!U2D1!W30!@baseboard_fab2_lib.baseboard_fab2(sch_1):page74_i21@chpset_lib.skx_ext_b(chips)!SKX_EXT_B_BGA1-IC,TBD!!!F108!VSS(958)!!!!
S!GND!U2D1!W28!@baseboard_fab2_lib.baseboard_fab2(sch_1):page74_i21@chpset_lib.skx_ext_b(chips)!SKX_EXT_B_BGA1-IC,TBD!!!F108!VSS(959)!!!!
S!GND!U2D1!W26!@baseboard_fab2_lib.baseboard_fab2(sch_1):page74_i21@chpset_lib.skx_ext_b(chips)!SKX_EXT_B_BGA1-IC,TBD!!!F108!VSS(960)!!!!
S!GND!U2D1!W24!@baseboard_fab2_lib.baseboard_fab2(sch_1):page74_i21@chpset_lib.skx_ext_b(chips)!SKX_EXT_B_BGA1-IC,TBD!!!F108!VSS(961)!!!!
S!GND!U2D1!W22!@baseboard_fab2_lib.baseboard_fab2(sch_1):page74_i21@chpset_lib.skx_ext_b(chips)!SKX_EXT_B_BGA1-IC,TBD!!!F108!VSS(962)!!!!
S!GND!U2D1!W12!@baseboard_fab2_lib.baseboard_fab2(sch_1):page74_i21@chpset_lib.skx_ext_b(chips)!SKX_EXT_B_BGA1-IC,TBD!!!F108!VSS(963)!!!!
S!GND!U2D1!AC56!@baseboard_fab2_lib.baseboard_fab2(sch_1):page74_i21@chpset_lib.skx_ext_b(chips)!SKX_EXT_B_BGA1-IC,TBD!!!F108!VSS(964)!!!!
S!GND!U2D1!W8!@baseboard_fab2_lib.baseboard_fab2(sch_1):page74_i21@chpset_lib.skx_ext_b(chips)!SKX_EXT_B_BGA1-IC,TBD!!!F108!VSS(965)!!!!
S!GND!U2D1!V83!@baseboard_fab2_lib.baseboard_fab2(sch_1):page74_i21@chpset_lib.skx_ext_b(chips)!SKX_EXT_B_BGA1-IC,TBD!!!F108!VSS(966)!!!!
S!GND!U2D1!V77!@baseboard_fab2_lib.baseboard_fab2(sch_1):page74_i21@chpset_lib.skx_ext_b(chips)!SKX_EXT_B_BGA1-IC,TBD!!!F108!VSS(967)!!!!
S!GND!U2D1!V75!@baseboard_fab2_lib.baseboard_fab2(sch_1):page74_i21@chpset_lib.skx_ext_b(chips)!SKX_EXT_B_BGA1-IC,TBD!!!F108!VSS(968)!!!!
S!GND!U2D1!V73!@baseboard_fab2_lib.baseboard_fab2(sch_1):page74_i21@chpset_lib.skx_ext_b(chips)!SKX_EXT_B_BGA1-IC,TBD!!!F108!VSS(969)!!!!
S!GND!U2D1!V43!@baseboard_fab2_lib.baseboard_fab2(sch_1):page74_i21@chpset_lib.skx_ext_b(chips)!SKX_EXT_B_BGA1-IC,TBD!!!F108!VSS(970)!!!!
S!GND!U2D1!V23!@baseboard_fab2_lib.baseboard_fab2(sch_1):page74_i21@chpset_lib.skx_ext_b(chips)!SKX_EXT_B_BGA1-IC,TBD!!!F108!VSS(971)!!!!
S!GND!U2D1!V21!@baseboard_fab2_lib.baseboard_fab2(sch_1):page74_i21@chpset_lib.skx_ext_b(chips)!SKX_EXT_B_BGA1-IC,TBD!!!F108!VSS(972)!!!!
S!GND!U2D1!V15!@baseboard_fab2_lib.baseboard_fab2(sch_1):page74_i21@chpset_lib.skx_ext_b(chips)!SKX_EXT_B_BGA1-IC,TBD!!!F108!VSS(973)!!!!
S!GND!U2D1!V13!@baseboard_fab2_lib.baseboard_fab2(sch_1):page74_i21@chpset_lib.skx_ext_b(chips)!SKX_EXT_B_BGA1-IC,TBD!!!F108!VSS(974)!!!!
S!GND!U2D1!V9!@baseboard_fab2_lib.baseboard_fab2(sch_1):page74_i21@chpset_lib.skx_ext_b(chips)!SKX_EXT_B_BGA1-IC,TBD!!!F108!VSS(975)!!!!
S!GND!U2D1!V5!@baseboard_fab2_lib.baseboard_fab2(sch_1):page74_i21@chpset_lib.skx_ext_b(chips)!SKX_EXT_B_BGA1-IC,TBD!!!F108!VSS(976)!!!!
S!GND!U2D1!V1!@baseboard_fab2_lib.baseboard_fab2(sch_1):page74_i21@chpset_lib.skx_ext_b(chips)!SKX_EXT_B_BGA1-IC,TBD!!!F108!VSS(977)!!!!
S!GND!U2D1!U86!@baseboard_fab2_lib.baseboard_fab2(sch_1):page74_i21@chpset_lib.skx_ext_b(chips)!SKX_EXT_B_BGA1-IC,TBD!!!F108!VSS(978)!!!!
S!GND!U2D1!U80!@baseboard_fab2_lib.baseboard_fab2(sch_1):page74_i21@chpset_lib.skx_ext_b(chips)!SKX_EXT_B_BGA1-IC,TBD!!!F108!VSS(979)!!!!
S!GND!U2D1!U78!@baseboard_fab2_lib.baseboard_fab2(sch_1):page74_i21@chpset_lib.skx_ext_b(chips)!SKX_EXT_B_BGA1-IC,TBD!!!F108!VSS(980)!!!!
S!GND!U2D1!U76!@baseboard_fab2_lib.baseboard_fab2(sch_1):page74_i21@chpset_lib.skx_ext_b(chips)!SKX_EXT_B_BGA1-IC,TBD!!!F108!VSS(981)!!!!
S!GND!U2D1!U74!@baseboard_fab2_lib.baseboard_fab2(sch_1):page74_i21@chpset_lib.skx_ext_b(chips)!SKX_EXT_B_BGA1-IC,TBD!!!F108!VSS(982)!!!!
S!GND!U2D1!U70!@baseboard_fab2_lib.baseboard_fab2(sch_1):page74_i21@chpset_lib.skx_ext_b(chips)!SKX_EXT_B_BGA1-IC,TBD!!!F108!VSS(983)!!!!
S!GND!U2D1!U68!@baseboard_fab2_lib.baseboard_fab2(sch_1):page74_i21@chpset_lib.skx_ext_b(chips)!SKX_EXT_B_BGA1-IC,TBD!!!F108!VSS(984)!!!!
S!GND!U2D1!U42!@baseboard_fab2_lib.baseboard_fab2(sch_1):page74_i21@chpset_lib.skx_ext_b(chips)!SKX_EXT_B_BGA1-IC,TBD!!!F108!VSS(985)!!!!
S!GND!U2D1!U36!@baseboard_fab2_lib.baseboard_fab2(sch_1):page74_i21@chpset_lib.skx_ext_b(chips)!SKX_EXT_B_BGA1-IC,TBD!!!F108!VSS(986)!!!!
S!GND!U2D1!U30!@baseboard_fab2_lib.baseboard_fab2(sch_1):page74_i21@chpset_lib.skx_ext_b(chips)!SKX_EXT_B_BGA1-IC,TBD!!!F108!VSS(987)!!!!
S!GND!U2D1!U24!@baseboard_fab2_lib.baseboard_fab2(sch_1):page74_i21@chpset_lib.skx_ext_b(chips)!SKX_EXT_B_BGA1-IC,TBD!!!F108!VSS(988)!!!!
S!GND!U2D1!U22!@baseboard_fab2_lib.baseboard_fab2(sch_1):page74_i21@chpset_lib.skx_ext_b(chips)!SKX_EXT_B_BGA1-IC,TBD!!!F108!VSS(989)!!!!
S!GND!U2D1!U20!@baseboard_fab2_lib.baseboard_fab2(sch_1):page74_i21@chpset_lib.skx_ext_b(chips)!SKX_EXT_B_BGA1-IC,TBD!!!F108!VSS(990)!!!!
S!GND!U2D1!U6!@baseboard_fab2_lib.baseboard_fab2(sch_1):page74_i21@chpset_lib.skx_ext_b(chips)!SKX_EXT_B_BGA1-IC,TBD!!!F108!VSS(991)!!!!
S!GND!U2D1!U4!@baseboard_fab2_lib.baseboard_fab2(sch_1):page74_i21@chpset_lib.skx_ext_b(chips)!SKX_EXT_B_BGA1-IC,TBD!!!F108!VSS(992)!!!!
S!GND!U2D1!U2!@baseboard_fab2_lib.baseboard_fab2(sch_1):page74_i21@chpset_lib.skx_ext_b(chips)!SKX_EXT_B_BGA1-IC,TBD!!!F108!VSS(993)!!!!
S!GND!U2D1!T85!@baseboard_fab2_lib.baseboard_fab2(sch_1):page74_i21@chpset_lib.skx_ext_b(chips)!SKX_EXT_B_BGA1-IC,TBD!!!F108!VSS(994)!!!!
S!GND!U2D1!T83!@baseboard_fab2_lib.baseboard_fab2(sch_1):page74_i21@chpset_lib.skx_ext_b(chips)!SKX_EXT_B_BGA1-IC,TBD!!!F108!VSS(995)!!!!
S!GND!U2D1!T77!@baseboard_fab2_lib.baseboard_fab2(sch_1):page74_i21@chpset_lib.skx_ext_b(chips)!SKX_EXT_B_BGA1-IC,TBD!!!F108!VSS(996)!!!!
S!GND!U2D1!T73!@baseboard_fab2_lib.baseboard_fab2(sch_1):page74_i21@chpset_lib.skx_ext_b(chips)!SKX_EXT_B_BGA1-IC,TBD!!!F108!VSS(997)!!!!
S!GND!U2D1!T65!@baseboard_fab2_lib.baseboard_fab2(sch_1):page74_i21@chpset_lib.skx_ext_b(chips)!SKX_EXT_B_BGA1-IC,TBD!!!F108!VSS(998)!!!!
S!GND!U2D1!T41!@baseboard_fab2_lib.baseboard_fab2(sch_1):page74_i21@chpset_lib.skx_ext_b(chips)!SKX_EXT_B_BGA1-IC,TBD!!!F108!VSS(999)!!!!
S!GND!U2D1!AP63!@baseboard_fab2_lib.baseboard_fab2(sch_1):page74_i23@chpset_lib.skx_ext_b(chips)!SKX_EXT_B_BGA1-IC,TBD!!!F106!VSS(748)!!!!
S!GND!U2D1!AP59!@baseboard_fab2_lib.baseboard_fab2(sch_1):page74_i23@chpset_lib.skx_ext_b(chips)!SKX_EXT_B_BGA1-IC,TBD!!!F106!VSS(749)!!!!
S!GND!U2D1!AP31!@baseboard_fab2_lib.baseboard_fab2(sch_1):page74_i23@chpset_lib.skx_ext_b(chips)!SKX_EXT_B_BGA1-IC,TBD!!!F106!VSS(750)!!!!
S!GND!U2D1!AP19!@baseboard_fab2_lib.baseboard_fab2(sch_1):page74_i23@chpset_lib.skx_ext_b(chips)!SKX_EXT_B_BGA1-IC,TBD!!!F106!VSS(751)!!!!
S!GND!U2D1!AP13!@baseboard_fab2_lib.baseboard_fab2(sch_1):page74_i23@chpset_lib.skx_ext_b(chips)!SKX_EXT_B_BGA1-IC,TBD!!!F106!VSS(752)!!!!
S!GND!U2D1!AP9!@baseboard_fab2_lib.baseboard_fab2(sch_1):page74_i23@chpset_lib.skx_ext_b(chips)!SKX_EXT_B_BGA1-IC,TBD!!!F106!VSS(753)!!!!
S!GND!U2D1!AP5!@baseboard_fab2_lib.baseboard_fab2(sch_1):page74_i23@chpset_lib.skx_ext_b(chips)!SKX_EXT_B_BGA1-IC,TBD!!!F106!VSS(754)!!!!
S!GND!U2D1!AN78!@baseboard_fab2_lib.baseboard_fab2(sch_1):page74_i23@chpset_lib.skx_ext_b(chips)!SKX_EXT_B_BGA1-IC,TBD!!!F106!VSS(755)!!!!
S!GND!U2D1!AN58!@baseboard_fab2_lib.baseboard_fab2(sch_1):page74_i23@chpset_lib.skx_ext_b(chips)!SKX_EXT_B_BGA1-IC,TBD!!!F106!VSS(756)!!!!
S!GND!U2D1!AN28!@baseboard_fab2_lib.baseboard_fab2(sch_1):page74_i23@chpset_lib.skx_ext_b(chips)!SKX_EXT_B_BGA1-IC,TBD!!!F106!VSS(757)!!!!
S!GND!U2D1!AN6!@baseboard_fab2_lib.baseboard_fab2(sch_1):page74_i23@chpset_lib.skx_ext_b(chips)!SKX_EXT_B_BGA1-IC,TBD!!!F106!VSS(758)!!!!
S!GND!U2D1!AN2!@baseboard_fab2_lib.baseboard_fab2(sch_1):page74_i23@chpset_lib.skx_ext_b(chips)!SKX_EXT_B_BGA1-IC,TBD!!!F106!VSS(759)!!!!
S!GND!U2D1!AM83!@baseboard_fab2_lib.baseboard_fab2(sch_1):page74_i23@chpset_lib.skx_ext_b(chips)!SKX_EXT_B_BGA1-IC,TBD!!!F106!VSS(760)!!!!
S!GND!U2D1!AM79!@baseboard_fab2_lib.baseboard_fab2(sch_1):page74_i23@chpset_lib.skx_ext_b(chips)!SKX_EXT_B_BGA1-IC,TBD!!!F106!VSS(761)!!!!
S!GND!U2D1!AM73!@baseboard_fab2_lib.baseboard_fab2(sch_1):page74_i23@chpset_lib.skx_ext_b(chips)!SKX_EXT_B_BGA1-IC,TBD!!!F106!VSS(762)!!!!
S!GND!U2D1!AM69!@baseboard_fab2_lib.baseboard_fab2(sch_1):page74_i23@chpset_lib.skx_ext_b(chips)!SKX_EXT_B_BGA1-IC,TBD!!!F106!VSS(763)!!!!
S!GND!U2D1!AM63!@baseboard_fab2_lib.baseboard_fab2(sch_1):page74_i23@chpset_lib.skx_ext_b(chips)!SKX_EXT_B_BGA1-IC,TBD!!!F106!VSS(764)!!!!
S!GND!U2D1!AM57!@baseboard_fab2_lib.baseboard_fab2(sch_1):page74_i23@chpset_lib.skx_ext_b(chips)!SKX_EXT_B_BGA1-IC,TBD!!!F106!VSS(765)!!!!
S!GND!U2D1!AM31!@baseboard_fab2_lib.baseboard_fab2(sch_1):page74_i23@chpset_lib.skx_ext_b(chips)!SKX_EXT_B_BGA1-IC,TBD!!!F106!VSS(766)!!!!
S!GND!U2D1!AC50!@baseboard_fab2_lib.baseboard_fab2(sch_1):page74_i23@chpset_lib.skx_ext_b(chips)!SKX_EXT_B_BGA1-IC,TBD!!!F106!VSS(767)!!!!
S!GND!U2D1!AM1!@baseboard_fab2_lib.baseboard_fab2(sch_1):page74_i23@chpset_lib.skx_ext_b(chips)!SKX_EXT_B_BGA1-IC,TBD!!!F106!VSS(768)!!!!
S!GND!U2D1!AL86!@baseboard_fab2_lib.baseboard_fab2(sch_1):page74_i23@chpset_lib.skx_ext_b(chips)!SKX_EXT_B_BGA1-IC,TBD!!!F106!VSS(769)!!!!
S!GND!U2D1!AL82!@baseboard_fab2_lib.baseboard_fab2(sch_1):page74_i23@chpset_lib.skx_ext_b(chips)!SKX_EXT_B_BGA1-IC,TBD!!!F106!VSS(770)!!!!
S!GND!U2D1!AL80!@baseboard_fab2_lib.baseboard_fab2(sch_1):page74_i23@chpset_lib.skx_ext_b(chips)!SKX_EXT_B_BGA1-IC,TBD!!!F106!VSS(771)!!!!
S!GND!U2D1!AL78!@baseboard_fab2_lib.baseboard_fab2(sch_1):page74_i23@chpset_lib.skx_ext_b(chips)!SKX_EXT_B_BGA1-IC,TBD!!!F106!VSS(772)!!!!
S!GND!U2D1!AL76!@baseboard_fab2_lib.baseboard_fab2(sch_1):page74_i23@chpset_lib.skx_ext_b(chips)!SKX_EXT_B_BGA1-IC,TBD!!!F106!VSS(773)!!!!
S!GND!U2D1!AL68!@baseboard_fab2_lib.baseboard_fab2(sch_1):page74_i22@chpset_lib.skx_ext_b(chips)!SKX_EXT_B_BGA1-IC,TBD!!!F107!VSS(774)!!!!
S!GND!U2D1!AL64!@baseboard_fab2_lib.baseboard_fab2(sch_1):page74_i22@chpset_lib.skx_ext_b(chips)!SKX_EXT_B_BGA1-IC,TBD!!!F107!VSS(775)!!!!
S!GND!U2D1!AL56!@baseboard_fab2_lib.baseboard_fab2(sch_1):page74_i22@chpset_lib.skx_ext_b(chips)!SKX_EXT_B_BGA1-IC,TBD!!!F107!VSS(776)!!!!
S!GND!U2D1!AL32!@baseboard_fab2_lib.baseboard_fab2(sch_1):page74_i22@chpset_lib.skx_ext_b(chips)!SKX_EXT_B_BGA1-IC,TBD!!!F107!VSS(777)!!!!
S!GND!U2D1!AL30!@baseboard_fab2_lib.baseboard_fab2(sch_1):page74_i22@chpset_lib.skx_ext_b(chips)!SKX_EXT_B_BGA1-IC,TBD!!!F107!VSS(778)!!!!
S!GND!U2D1!AL24!@baseboard_fab2_lib.baseboard_fab2(sch_1):page74_i22@chpset_lib.skx_ext_b(chips)!SKX_EXT_B_BGA1-IC,TBD!!!F107!VSS(779)!!!!
S!GND!U2D1!AL10!@baseboard_fab2_lib.baseboard_fab2(sch_1):page74_i22@chpset_lib.skx_ext_b(chips)!SKX_EXT_B_BGA1-IC,TBD!!!F107!VSS(780)!!!!
S!GND!U2D1!AL4!@baseboard_fab2_lib.baseboard_fab2(sch_1):page74_i22@chpset_lib.skx_ext_b(chips)!SKX_EXT_B_BGA1-IC,TBD!!!F107!VSS(781)!!!!
S!GND!U2D1!AK85!@baseboard_fab2_lib.baseboard_fab2(sch_1):page74_i22@chpset_lib.skx_ext_b(chips)!SKX_EXT_B_BGA1-IC,TBD!!!F107!VSS(782)!!!!
S!GND!U2D1!AK83!@baseboard_fab2_lib.baseboard_fab2(sch_1):page74_i22@chpset_lib.skx_ext_b(chips)!SKX_EXT_B_BGA1-IC,TBD!!!F107!VSS(783)!!!!
S!GND!U2D1!AK81!@baseboard_fab2_lib.baseboard_fab2(sch_1):page74_i22@chpset_lib.skx_ext_b(chips)!SKX_EXT_B_BGA1-IC,TBD!!!F107!VSS(784)!!!!
S!GND!U2D1!AK79!@baseboard_fab2_lib.baseboard_fab2(sch_1):page74_i22@chpset_lib.skx_ext_b(chips)!SKX_EXT_B_BGA1-IC,TBD!!!F107!VSS(785)!!!!
S!GND!U2D1!AK73!@baseboard_fab2_lib.baseboard_fab2(sch_1):page74_i22@chpset_lib.skx_ext_b(chips)!SKX_EXT_B_BGA1-IC,TBD!!!F107!VSS(786)!!!!
S!GND!U2D1!AK67!@baseboard_fab2_lib.baseboard_fab2(sch_1):page74_i22@chpset_lib.skx_ext_b(chips)!SKX_EXT_B_BGA1-IC,TBD!!!F107!VSS(787)!!!!
S!GND!U2D1!AK65!@baseboard_fab2_lib.baseboard_fab2(sch_1):page74_i22@chpset_lib.skx_ext_b(chips)!SKX_EXT_B_BGA1-IC,TBD!!!F107!VSS(788)!!!!
S!GND!U2D1!AK55!@baseboard_fab2_lib.baseboard_fab2(sch_1):page74_i22@chpset_lib.skx_ext_b(chips)!SKX_EXT_B_BGA1-IC,TBD!!!F107!VSS(789)!!!!
S!GND!U2D1!AK33!@baseboard_fab2_lib.baseboard_fab2(sch_1):page74_i22@chpset_lib.skx_ext_b(chips)!SKX_EXT_B_BGA1-IC,TBD!!!F107!VSS(790)!!!!
S!GND!U2D1!AK31!@baseboard_fab2_lib.baseboard_fab2(sch_1):page74_i22@chpset_lib.skx_ext_b(chips)!SKX_EXT_B_BGA1-IC,TBD!!!F107!VSS(791)!!!!
S!GND!U2D1!AK29!@baseboard_fab2_lib.baseboard_fab2(sch_1):page74_i22@chpset_lib.skx_ext_b(chips)!SKX_EXT_B_BGA1-IC,TBD!!!F107!VSS(792)!!!!
S!GND!U2D1!AK25!@baseboard_fab2_lib.baseboard_fab2(sch_1):page74_i22@chpset_lib.skx_ext_b(chips)!SKX_EXT_B_BGA1-IC,TBD!!!F107!VSS(793)!!!!
S!GND!U2D1!AK23!@baseboard_fab2_lib.baseboard_fab2(sch_1):page74_i22@chpset_lib.skx_ext_b(chips)!SKX_EXT_B_BGA1-IC,TBD!!!F107!VSS(794)!!!!
S!GND!U2D1!AK19!@baseboard_fab2_lib.baseboard_fab2(sch_1):page74_i22@chpset_lib.skx_ext_b(chips)!SKX_EXT_B_BGA1-IC,TBD!!!F107!VSS(795)!!!!
S!GND!U2D1!AK13!@baseboard_fab2_lib.baseboard_fab2(sch_1):page74_i22@chpset_lib.skx_ext_b(chips)!SKX_EXT_B_BGA1-IC,TBD!!!F107!VSS(796)!!!!
S!GND!U2D1!AK9!@baseboard_fab2_lib.baseboard_fab2(sch_1):page74_i22@chpset_lib.skx_ext_b(chips)!SKX_EXT_B_BGA1-IC,TBD!!!F107!VSS(797)!!!!
S!GND!U2D1!AJ86!@baseboard_fab2_lib.baseboard_fab2(sch_1):page74_i22@chpset_lib.skx_ext_b(chips)!SKX_EXT_B_BGA1-IC,TBD!!!F107!VSS(798)!!!!
S!GND!U2D1!AJ82!@baseboard_fab2_lib.baseboard_fab2(sch_1):page74_i22@chpset_lib.skx_ext_b(chips)!SKX_EXT_B_BGA1-IC,TBD!!!F107!VSS(799)!!!!
S!GND!U2D1!AJ78!@baseboard_fab2_lib.baseboard_fab2(sch_1):page74_i22@chpset_lib.skx_ext_b(chips)!SKX_EXT_B_BGA1-IC,TBD!!!F107!VSS(800)!!!!
S!GND!U2D1!AJ74!@baseboard_fab2_lib.baseboard_fab2(sch_1):page74_i22@chpset_lib.skx_ext_b(chips)!SKX_EXT_B_BGA1-IC,TBD!!!F107!VSS(801)!!!!
S!GND!U2D1!AJ68!@baseboard_fab2_lib.baseboard_fab2(sch_1):page74_i22@chpset_lib.skx_ext_b(chips)!SKX_EXT_B_BGA1-IC,TBD!!!F107!VSS(802)!!!!
S!GND!U2D1!AJ66!@baseboard_fab2_lib.baseboard_fab2(sch_1):page74_i22@chpset_lib.skx_ext_b(chips)!SKX_EXT_B_BGA1-IC,TBD!!!F107!VSS(803)!!!!
S!GND!U2D1!AJ54!@baseboard_fab2_lib.baseboard_fab2(sch_1):page74_i22@chpset_lib.skx_ext_b(chips)!SKX_EXT_B_BGA1-IC,TBD!!!F107!VSS(804)!!!!
S!GND!U2D1!AJ52!@baseboard_fab2_lib.baseboard_fab2(sch_1):page74_i22@chpset_lib.skx_ext_b(chips)!SKX_EXT_B_BGA1-IC,TBD!!!F107!VSS(805)!!!!
S!GND!U2D1!AJ50!@baseboard_fab2_lib.baseboard_fab2(sch_1):page74_i22@chpset_lib.skx_ext_b(chips)!SKX_EXT_B_BGA1-IC,TBD!!!F107!VSS(806)!!!!
S!GND!U2D1!AJ48!@baseboard_fab2_lib.baseboard_fab2(sch_1):page74_i22@chpset_lib.skx_ext_b(chips)!SKX_EXT_B_BGA1-IC,TBD!!!F107!VSS(807)!!!!
S!GND!U2D1!AJ46!@baseboard_fab2_lib.baseboard_fab2(sch_1):page74_i22@chpset_lib.skx_ext_b(chips)!SKX_EXT_B_BGA1-IC,TBD!!!F107!VSS(808)!!!!
S!GND!U2D1!AJ34!@baseboard_fab2_lib.baseboard_fab2(sch_1):page74_i22@chpset_lib.skx_ext_b(chips)!SKX_EXT_B_BGA1-IC,TBD!!!F107!VSS(809)!!!!
S!GND!U2D1!AJ32!@baseboard_fab2_lib.baseboard_fab2(sch_1):page74_i22@chpset_lib.skx_ext_b(chips)!SKX_EXT_B_BGA1-IC,TBD!!!F107!VSS(810)!!!!
S!GND!U2D1!AJ28!@baseboard_fab2_lib.baseboard_fab2(sch_1):page74_i22@chpset_lib.skx_ext_b(chips)!SKX_EXT_B_BGA1-IC,TBD!!!F107!VSS(811)!!!!
S!GND!U2D1!AJ26!@baseboard_fab2_lib.baseboard_fab2(sch_1):page74_i22@chpset_lib.skx_ext_b(chips)!SKX_EXT_B_BGA1-IC,TBD!!!F107!VSS(812)!!!!
S!GND!U2D1!AJ22!@baseboard_fab2_lib.baseboard_fab2(sch_1):page74_i22@chpset_lib.skx_ext_b(chips)!SKX_EXT_B_BGA1-IC,TBD!!!F107!VSS(813)!!!!
S!GND!U2D1!AJ8!@baseboard_fab2_lib.baseboard_fab2(sch_1):page74_i22@chpset_lib.skx_ext_b(chips)!SKX_EXT_B_BGA1-IC,TBD!!!F107!VSS(814)!!!!
S!GND!U2D1!AH83!@baseboard_fab2_lib.baseboard_fab2(sch_1):page74_i22@chpset_lib.skx_ext_b(chips)!SKX_EXT_B_BGA1-IC,TBD!!!F107!VSS(815)!!!!
S!GND!U2D1!AH77!@baseboard_fab2_lib.baseboard_fab2(sch_1):page74_i22@chpset_lib.skx_ext_b(chips)!SKX_EXT_B_BGA1-IC,TBD!!!F107!VSS(816)!!!!
S!GND!U2D1!AH75!@baseboard_fab2_lib.baseboard_fab2(sch_1):page74_i22@chpset_lib.skx_ext_b(chips)!SKX_EXT_B_BGA1-IC,TBD!!!F107!VSS(817)!!!!
S!GND!U2D1!AH69!@baseboard_fab2_lib.baseboard_fab2(sch_1):page74_i22@chpset_lib.skx_ext_b(chips)!SKX_EXT_B_BGA1-IC,TBD!!!F107!VSS(818)!!!!
S!GND!U2D1!AH65!@baseboard_fab2_lib.baseboard_fab2(sch_1):page74_i22@chpset_lib.skx_ext_b(chips)!SKX_EXT_B_BGA1-IC,TBD!!!F107!VSS(819)!!!!
S!GND!U2D1!AH61!@baseboard_fab2_lib.baseboard_fab2(sch_1):page74_i22@chpset_lib.skx_ext_b(chips)!SKX_EXT_B_BGA1-IC,TBD!!!F107!VSS(820)!!!!
S!GND!U2D1!AH59!@baseboard_fab2_lib.baseboard_fab2(sch_1):page74_i22@chpset_lib.skx_ext_b(chips)!SKX_EXT_B_BGA1-IC,TBD!!!F107!VSS(821)!!!!
S!GND!U2D1!AH53!@baseboard_fab2_lib.baseboard_fab2(sch_1):page74_i22@chpset_lib.skx_ext_b(chips)!SKX_EXT_B_BGA1-IC,TBD!!!F107!VSS(822)!!!!
S!GND!U2D1!AH51!@baseboard_fab2_lib.baseboard_fab2(sch_1):page74_i22@chpset_lib.skx_ext_b(chips)!SKX_EXT_B_BGA1-IC,TBD!!!F107!VSS(823)!!!!
S!GND!U2D1!AH49!@baseboard_fab2_lib.baseboard_fab2(sch_1):page74_i22@chpset_lib.skx_ext_b(chips)!SKX_EXT_B_BGA1-IC,TBD!!!F107!VSS(824)!!!!
S!GND!U2D1!AH47!@baseboard_fab2_lib.baseboard_fab2(sch_1):page74_i22@chpset_lib.skx_ext_b(chips)!SKX_EXT_B_BGA1-IC,TBD!!!F107!VSS(825)!!!!
S!GND!U2D1!AH45!@baseboard_fab2_lib.baseboard_fab2(sch_1):page74_i22@chpset_lib.skx_ext_b(chips)!SKX_EXT_B_BGA1-IC,TBD!!!F107!VSS(826)!!!!
S!GND!U2D1!AH35!@baseboard_fab2_lib.baseboard_fab2(sch_1):page74_i22@chpset_lib.skx_ext_b(chips)!SKX_EXT_B_BGA1-IC,TBD!!!F107!VSS(827)!!!!
S!GND!U2D1!AH33!@baseboard_fab2_lib.baseboard_fab2(sch_1):page74_i22@chpset_lib.skx_ext_b(chips)!SKX_EXT_B_BGA1-IC,TBD!!!F107!VSS(828)!!!!
S!GND!U2D1!AH27!@baseboard_fab2_lib.baseboard_fab2(sch_1):page74_i22@chpset_lib.skx_ext_b(chips)!SKX_EXT_B_BGA1-IC,TBD!!!F107!VSS(829)!!!!
S!GND!U2D1!AH21!@baseboard_fab2_lib.baseboard_fab2(sch_1):page74_i22@chpset_lib.skx_ext_b(chips)!SKX_EXT_B_BGA1-IC,TBD!!!F107!VSS(830)!!!!
S!GND!U2D1!AH5!@baseboard_fab2_lib.baseboard_fab2(sch_1):page74_i22@chpset_lib.skx_ext_b(chips)!SKX_EXT_B_BGA1-IC,TBD!!!F107!VSS(831)!!!!
S!GND!U2D1!AH1!@baseboard_fab2_lib.baseboard_fab2(sch_1):page74_i22@chpset_lib.skx_ext_b(chips)!SKX_EXT_B_BGA1-IC,TBD!!!F107!VSS(832)!!!!
S!GND!U2D1!AG80!@baseboard_fab2_lib.baseboard_fab2(sch_1):page74_i22@chpset_lib.skx_ext_b(chips)!SKX_EXT_B_BGA1-IC,TBD!!!F107!VSS(833)!!!!
S!GND!U2D1!AG78!@baseboard_fab2_lib.baseboard_fab2(sch_1):page74_i22@chpset_lib.skx_ext_b(chips)!SKX_EXT_B_BGA1-IC,TBD!!!F107!VSS(834)!!!!
S!GND!U2D1!AG76!@baseboard_fab2_lib.baseboard_fab2(sch_1):page74_i22@chpset_lib.skx_ext_b(chips)!SKX_EXT_B_BGA1-IC,TBD!!!F107!VSS(835)!!!!
S!GND!U2D1!AG74!@baseboard_fab2_lib.baseboard_fab2(sch_1):page74_i22@chpset_lib.skx_ext_b(chips)!SKX_EXT_B_BGA1-IC,TBD!!!F107!VSS(836)!!!!
S!GND!U2D1!AG70!@baseboard_fab2_lib.baseboard_fab2(sch_1):page74_i22@chpset_lib.skx_ext_b(chips)!SKX_EXT_B_BGA1-IC,TBD!!!F107!VSS(837)!!!!
S!GND!U2D1!AG64!@baseboard_fab2_lib.baseboard_fab2(sch_1):page74_i22@chpset_lib.skx_ext_b(chips)!SKX_EXT_B_BGA1-IC,TBD!!!F107!VSS(838)!!!!
S!GND!U2D1!AG36!@baseboard_fab2_lib.baseboard_fab2(sch_1):page74_i22@chpset_lib.skx_ext_b(chips)!SKX_EXT_B_BGA1-IC,TBD!!!F107!VSS(839)!!!!
S!GND!U2D1!AG18!@baseboard_fab2_lib.baseboard_fab2(sch_1):page74_i22@chpset_lib.skx_ext_b(chips)!SKX_EXT_B_BGA1-IC,TBD!!!F107!VSS(840)!!!!
S!GND!U2D1!AG14!@baseboard_fab2_lib.baseboard_fab2(sch_1):page74_i22@chpset_lib.skx_ext_b(chips)!SKX_EXT_B_BGA1-IC,TBD!!!F107!VSS(841)!!!!
S!GND!U2D1!AG12!@baseboard_fab2_lib.baseboard_fab2(sch_1):page74_i22@chpset_lib.skx_ext_b(chips)!SKX_EXT_B_BGA1-IC,TBD!!!F107!VSS(842)!!!!
S!GND!U2D1!AF85!@baseboard_fab2_lib.baseboard_fab2(sch_1):page74_i22@chpset_lib.skx_ext_b(chips)!SKX_EXT_B_BGA1-IC,TBD!!!F107!VSS(843)!!!!
S!GND!U2D1!AF83!@baseboard_fab2_lib.baseboard_fab2(sch_1):page74_i22@chpset_lib.skx_ext_b(chips)!SKX_EXT_B_BGA1-IC,TBD!!!F107!VSS(844)!!!!
S!GND!U2D1!AF77!@baseboard_fab2_lib.baseboard_fab2(sch_1):page74_i22@chpset_lib.skx_ext_b(chips)!SKX_EXT_B_BGA1-IC,TBD!!!F107!VSS(845)!!!!
S!GND!U2D1!AF73!@baseboard_fab2_lib.baseboard_fab2(sch_1):page74_i22@chpset_lib.skx_ext_b(chips)!SKX_EXT_B_BGA1-IC,TBD!!!F107!VSS(846)!!!!
S!GND!U2D1!AF41!@baseboard_fab2_lib.baseboard_fab2(sch_1):page74_i22@chpset_lib.skx_ext_b(chips)!SKX_EXT_B_BGA1-IC,TBD!!!F107!VSS(847)!!!!
S!GND!U2D1!AF39!@baseboard_fab2_lib.baseboard_fab2(sch_1):page74_i22@chpset_lib.skx_ext_b(chips)!SKX_EXT_B_BGA1-IC,TBD!!!F107!VSS(848)!!!!
S!GND!U2D1!AF37!@baseboard_fab2_lib.baseboard_fab2(sch_1):page74_i22@chpset_lib.skx_ext_b(chips)!SKX_EXT_B_BGA1-IC,TBD!!!F107!VSS(849)!!!!
S!GND!U2D1!AF33!@baseboard_fab2_lib.baseboard_fab2(sch_1):page74_i22@chpset_lib.skx_ext_b(chips)!SKX_EXT_B_BGA1-IC,TBD!!!F107!VSS(850)!!!!
S!GND!U2D1!AF31!@baseboard_fab2_lib.baseboard_fab2(sch_1):page74_i22@chpset_lib.skx_ext_b(chips)!SKX_EXT_B_BGA1-IC,TBD!!!F107!VSS(851)!!!!
S!GND!U2D1!AF29!@baseboard_fab2_lib.baseboard_fab2(sch_1):page74_i22@chpset_lib.skx_ext_b(chips)!SKX_EXT_B_BGA1-IC,TBD!!!F107!VSS(852)!!!!
S!GND!U2D1!AF27!@baseboard_fab2_lib.baseboard_fab2(sch_1):page74_i22@chpset_lib.skx_ext_b(chips)!SKX_EXT_B_BGA1-IC,TBD!!!F107!VSS(853)!!!!
S!GND!U2D1!AF25!@baseboard_fab2_lib.baseboard_fab2(sch_1):page74_i22@chpset_lib.skx_ext_b(chips)!SKX_EXT_B_BGA1-IC,TBD!!!F107!VSS(854)!!!!
S!GND!U2D1!AF23!@baseboard_fab2_lib.baseboard_fab2(sch_1):page74_i22@chpset_lib.skx_ext_b(chips)!SKX_EXT_B_BGA1-IC,TBD!!!F107!VSS(855)!!!!
S!GND!U2D1!AF21!@baseboard_fab2_lib.baseboard_fab2(sch_1):page74_i22@chpset_lib.skx_ext_b(chips)!SKX_EXT_B_BGA1-IC,TBD!!!F107!VSS(856)!!!!
S!GND!U2D1!AF9!@baseboard_fab2_lib.baseboard_fab2(sch_1):page74_i22@chpset_lib.skx_ext_b(chips)!SKX_EXT_B_BGA1-IC,TBD!!!F107!VSS(857)!!!!
S!GND!U2D1!AC52!@baseboard_fab2_lib.baseboard_fab2(sch_1):page74_i22@chpset_lib.skx_ext_b(chips)!SKX_EXT_B_BGA1-IC,TBD!!!F107!VSS(858)!!!!
S!GND!U2D1!AF1!@baseboard_fab2_lib.baseboard_fab2(sch_1):page74_i22@chpset_lib.skx_ext_b(chips)!SKX_EXT_B_BGA1-IC,TBD!!!F107!VSS(859)!!!!
S!GND!U2D1!AE78!@baseboard_fab2_lib.baseboard_fab2(sch_1):page74_i22@chpset_lib.skx_ext_b(chips)!SKX_EXT_B_BGA1-IC,TBD!!!F107!VSS(860)!!!!
S!GND!U2D1!AE70!@baseboard_fab2_lib.baseboard_fab2(sch_1):page74_i22@chpset_lib.skx_ext_b(chips)!SKX_EXT_B_BGA1-IC,TBD!!!F107!VSS(861)!!!!
S!GND!U2D1!AE68!@baseboard_fab2_lib.baseboard_fab2(sch_1):page74_i22@chpset_lib.skx_ext_b(chips)!SKX_EXT_B_BGA1-IC,TBD!!!F107!VSS(862)!!!!
S!GND!U2D1!AE66!@baseboard_fab2_lib.baseboard_fab2(sch_1):page74_i22@chpset_lib.skx_ext_b(chips)!SKX_EXT_B_BGA1-IC,TBD!!!F107!VSS(863)!!!!
S!GND!U2D1!AE64!@baseboard_fab2_lib.baseboard_fab2(sch_1):page74_i22@chpset_lib.skx_ext_b(chips)!SKX_EXT_B_BGA1-IC,TBD!!!F107!VSS(864)!!!!
S!GND!U2D1!AE42!@baseboard_fab2_lib.baseboard_fab2(sch_1):page74_i22@chpset_lib.skx_ext_b(chips)!SKX_EXT_B_BGA1-IC,TBD!!!F107!VSS(865)!!!!
S!GND!U2D1!AE40!@baseboard_fab2_lib.baseboard_fab2(sch_1):page74_i22@chpset_lib.skx_ext_b(chips)!SKX_EXT_B_BGA1-IC,TBD!!!F107!VSS(866)!!!!
S!GND!U2D1!AE38!@baseboard_fab2_lib.baseboard_fab2(sch_1):page74_i22@chpset_lib.skx_ext_b(chips)!SKX_EXT_B_BGA1-IC,TBD!!!F107!VSS(867)!!!!
S!GND!U2D1!AE16!@baseboard_fab2_lib.baseboard_fab2(sch_1):page74_i22@chpset_lib.skx_ext_b(chips)!SKX_EXT_B_BGA1-IC,TBD!!!F107!VSS(868)!!!!
S!GND!U2D1!AC54!@baseboard_fab2_lib.baseboard_fab2(sch_1):page74_i22@chpset_lib.skx_ext_b(chips)!SKX_EXT_B_BGA1-IC,TBD!!!F107!VSS(869)!!!!
S!GND!U2D1!AE8!@baseboard_fab2_lib.baseboard_fab2(sch_1):page74_i22@chpset_lib.skx_ext_b(chips)!SKX_EXT_B_BGA1-IC,TBD!!!F107!VSS(870)!!!!
S!GND!U2D1!AE4!@baseboard_fab2_lib.baseboard_fab2(sch_1):page74_i22@chpset_lib.skx_ext_b(chips)!SKX_EXT_B_BGA1-IC,TBD!!!F107!VSS(871)!!!!
S!GND!U2D1!AD85!@baseboard_fab2_lib.baseboard_fab2(sch_1):page74_i22@chpset_lib.skx_ext_b(chips)!SKX_EXT_B_BGA1-IC,TBD!!!F107!VSS(872)!!!!
S!GND!U2D1!AD83!@baseboard_fab2_lib.baseboard_fab2(sch_1):page74_i22@chpset_lib.skx_ext_b(chips)!SKX_EXT_B_BGA1-IC,TBD!!!F107!VSS(873)!!!!
S!GND!U2D1!AD81!@baseboard_fab2_lib.baseboard_fab2(sch_1):page74_i22@chpset_lib.skx_ext_b(chips)!SKX_EXT_B_BGA1-IC,TBD!!!F107!VSS(874)!!!!
S!GND!U2D1!AD75!@baseboard_fab2_lib.baseboard_fab2(sch_1):page74_i22@chpset_lib.skx_ext_b(chips)!SKX_EXT_B_BGA1-IC,TBD!!!F107!VSS(875)!!!!
S!GND!U2D1!AD73!@baseboard_fab2_lib.baseboard_fab2(sch_1):page74_i22@chpset_lib.skx_ext_b(chips)!SKX_EXT_B_BGA1-IC,TBD!!!F107!VSS(876)!!!!
S!GND!U2D1!AD71!@baseboard_fab2_lib.baseboard_fab2(sch_1):page74_i22@chpset_lib.skx_ext_b(chips)!SKX_EXT_B_BGA1-IC,TBD!!!F107!VSS(877)!!!!
S!GND!U2D1!AD43!@baseboard_fab2_lib.baseboard_fab2(sch_1):page74_i22@chpset_lib.skx_ext_b(chips)!SKX_EXT_B_BGA1-IC,TBD!!!F107!VSS(878)!!!!
S!GND!U2D1!AD39!@baseboard_fab2_lib.baseboard_fab2(sch_1):page74_i22@chpset_lib.skx_ext_b(chips)!SKX_EXT_B_BGA1-IC,TBD!!!F107!VSS(879)!!!!
S!GND!U2D1!AD33!@baseboard_fab2_lib.baseboard_fab2(sch_1):page74_i22@chpset_lib.skx_ext_b(chips)!SKX_EXT_B_BGA1-IC,TBD!!!F107!VSS(880)!!!!
S!GND!U2D1!AD27!@baseboard_fab2_lib.baseboard_fab2(sch_1):page74_i22@chpset_lib.skx_ext_b(chips)!SKX_EXT_B_BGA1-IC,TBD!!!F107!VSS(881)!!!!
S!GND!U2D1!AD21!@baseboard_fab2_lib.baseboard_fab2(sch_1):page74_i22@chpset_lib.skx_ext_b(chips)!SKX_EXT_B_BGA1-IC,TBD!!!F107!VSS(882)!!!!
S!GND!U2D1!AD19!@baseboard_fab2_lib.baseboard_fab2(sch_1):page74_i22@chpset_lib.skx_ext_b(chips)!SKX_EXT_B_BGA1-IC,TBD!!!F107!VSS(883)!!!!
S!GND!U2D1!AD15!@baseboard_fab2_lib.baseboard_fab2(sch_1):page74_i22@chpset_lib.skx_ext_b(chips)!SKX_EXT_B_BGA1-IC,TBD!!!F107!VSS(884)!!!!
S!GND!U2D1!AD13!@baseboard_fab2_lib.baseboard_fab2(sch_1):page74_i22@chpset_lib.skx_ext_b(chips)!SKX_EXT_B_BGA1-IC,TBD!!!F107!VSS(885)!!!!
S!GND!U2D1!AD11!@baseboard_fab2_lib.baseboard_fab2(sch_1):page74_i22@chpset_lib.skx_ext_b(chips)!SKX_EXT_B_BGA1-IC,TBD!!!F107!VSS(886)!!!!
S!GND!U2D1!AD9!@baseboard_fab2_lib.baseboard_fab2(sch_1):page74_i22@chpset_lib.skx_ext_b(chips)!SKX_EXT_B_BGA1-IC,TBD!!!F107!VSS(887)!!!!
S!GND!U2D1!AD7!@baseboard_fab2_lib.baseboard_fab2(sch_1):page74_i22@chpset_lib.skx_ext_b(chips)!SKX_EXT_B_BGA1-IC,TBD!!!F107!VSS(888)!!!!
S!GND!U2D1!AD3!@baseboard_fab2_lib.baseboard_fab2(sch_1):page74_i22@chpset_lib.skx_ext_b(chips)!SKX_EXT_B_BGA1-IC,TBD!!!F107!VSS(889)!!!!
S!GND!U2D1!AC86!@baseboard_fab2_lib.baseboard_fab2(sch_1):page74_i22@chpset_lib.skx_ext_b(chips)!SKX_EXT_B_BGA1-IC,TBD!!!F107!VSS(890)!!!!
S!GND!U2D1!AC84!@baseboard_fab2_lib.baseboard_fab2(sch_1):page74_i22@chpset_lib.skx_ext_b(chips)!SKX_EXT_B_BGA1-IC,TBD!!!F107!VSS(891)!!!!
S!GND!U2D1!AC78!@baseboard_fab2_lib.baseboard_fab2(sch_1):page74_i22@chpset_lib.skx_ext_b(chips)!SKX_EXT_B_BGA1-IC,TBD!!!F107!VSS(892)!!!!
S!GND!U2D1!AC72!@baseboard_fab2_lib.baseboard_fab2(sch_1):page74_i22@chpset_lib.skx_ext_b(chips)!SKX_EXT_B_BGA1-IC,TBD!!!F107!VSS(893)!!!!
S!GND!U2D1!AC70!@baseboard_fab2_lib.baseboard_fab2(sch_1):page74_i22@chpset_lib.skx_ext_b(chips)!SKX_EXT_B_BGA1-IC,TBD!!!F107!VSS(894)!!!!
S!GND!U2D1!AC64!@baseboard_fab2_lib.baseboard_fab2(sch_1):page74_i22@chpset_lib.skx_ext_b(chips)!SKX_EXT_B_BGA1-IC,TBD!!!F107!VSS(895)!!!!
S!GND!U2D1!AC40!@baseboard_fab2_lib.baseboard_fab2(sch_1):page74_i22@chpset_lib.skx_ext_b(chips)!SKX_EXT_B_BGA1-IC,TBD!!!F107!VSS(896)!!!!
S!GND!U2D1!AC38!@baseboard_fab2_lib.baseboard_fab2(sch_1):page74_i22@chpset_lib.skx_ext_b(chips)!SKX_EXT_B_BGA1-IC,TBD!!!F107!VSS(897)!!!!
S!GND!U2D1!AC34!@baseboard_fab2_lib.baseboard_fab2(sch_1):page74_i22@chpset_lib.skx_ext_b(chips)!SKX_EXT_B_BGA1-IC,TBD!!!F107!VSS(898)!!!!
S!GND!U2D1!AC32!@baseboard_fab2_lib.baseboard_fab2(sch_1):page74_i22@chpset_lib.skx_ext_b(chips)!SKX_EXT_B_BGA1-IC,TBD!!!F107!VSS(899)!!!!
S!GND!U2D1!AC28!@baseboard_fab2_lib.baseboard_fab2(sch_1):page74_i22@chpset_lib.skx_ext_b(chips)!SKX_EXT_B_BGA1-IC,TBD!!!F107!VSS(900)!!!!
S!GND!U2D1!AC26!@baseboard_fab2_lib.baseboard_fab2(sch_1):page74_i22@chpset_lib.skx_ext_b(chips)!SKX_EXT_B_BGA1-IC,TBD!!!F107!VSS(901)!!!!
S!GND!U2D1!AC22!@baseboard_fab2_lib.baseboard_fab2(sch_1):page74_i22@chpset_lib.skx_ext_b(chips)!SKX_EXT_B_BGA1-IC,TBD!!!F107!VSS(902)!!!!
S!GND!U2D1!AC18!@baseboard_fab2_lib.baseboard_fab2(sch_1):page74_i22@chpset_lib.skx_ext_b(chips)!SKX_EXT_B_BGA1-IC,TBD!!!F107!VSS(903)!!!!
S!GND!U2D1!AB85!@baseboard_fab2_lib.baseboard_fab2(sch_1):page74_i22@chpset_lib.skx_ext_b(chips)!SKX_EXT_B_BGA1-IC,TBD!!!F107!VSS(904)!!!!
S!GND!U2D1!AB83!@baseboard_fab2_lib.baseboard_fab2(sch_1):page74_i22@chpset_lib.skx_ext_b(chips)!SKX_EXT_B_BGA1-IC,TBD!!!F107!VSS(905)!!!!
S!GND!U2D1!AB79!@baseboard_fab2_lib.baseboard_fab2(sch_1):page74_i22@chpset_lib.skx_ext_b(chips)!SKX_EXT_B_BGA1-IC,TBD!!!F107!VSS(906)!!!!
S!GND!U2D1!AB73!@baseboard_fab2_lib.baseboard_fab2(sch_1):page74_i22@chpset_lib.skx_ext_b(chips)!SKX_EXT_B_BGA1-IC,TBD!!!F107!VSS(907)!!!!
S!GND!U2D1!BL70!@baseboard_fab2_lib.baseboard_fab2(sch_1):page75_i17@chpset_lib.skx_ext_b(chips)!SKX_EXT_B_BGA1-IC,TBD!!!F105!VSS(588)!!!!
S!GND!U2D1!BL68!@baseboard_fab2_lib.baseboard_fab2(sch_1):page75_i17@chpset_lib.skx_ext_b(chips)!SKX_EXT_B_BGA1-IC,TBD!!!F105!VSS(589)!!!!
S!GND!U2D1!BL66!@baseboard_fab2_lib.baseboard_fab2(sch_1):page75_i17@chpset_lib.skx_ext_b(chips)!SKX_EXT_B_BGA1-IC,TBD!!!F105!VSS(590)!!!!
S!GND!U2D1!BL64!@baseboard_fab2_lib.baseboard_fab2(sch_1):page75_i17@chpset_lib.skx_ext_b(chips)!SKX_EXT_B_BGA1-IC,TBD!!!F105!VSS(591)!!!!
S!GND!U2D1!BL24!@baseboard_fab2_lib.baseboard_fab2(sch_1):page75_i17@chpset_lib.skx_ext_b(chips)!SKX_EXT_B_BGA1-IC,TBD!!!F105!VSS(592)!!!!
S!GND!U2D1!BL22!@baseboard_fab2_lib.baseboard_fab2(sch_1):page75_i17@chpset_lib.skx_ext_b(chips)!SKX_EXT_B_BGA1-IC,TBD!!!F105!VSS(593)!!!!
S!GND!U2D1!P61!@baseboard_fab2_lib.baseboard_fab2(sch_1):page75_i17@chpset_lib.skx_ext_b(chips)!SKX_EXT_B_BGA1-IC,TBD!!!F105!VSS(594)!!!!
S!GND!U2D1!BL12!@baseboard_fab2_lib.baseboard_fab2(sch_1):page75_i17@chpset_lib.skx_ext_b(chips)!SKX_EXT_B_BGA1-IC,TBD!!!F105!VSS(595)!!!!
S!GND!U2D1!BL10!@baseboard_fab2_lib.baseboard_fab2(sch_1):page75_i17@chpset_lib.skx_ext_b(chips)!SKX_EXT_B_BGA1-IC,TBD!!!F105!VSS(596)!!!!
S!GND!U2D1!BL6!@baseboard_fab2_lib.baseboard_fab2(sch_1):page75_i17@chpset_lib.skx_ext_b(chips)!SKX_EXT_B_BGA1-IC,TBD!!!F105!VSS(597)!!!!
S!GND!U2D1!BK19!@baseboard_fab2_lib.baseboard_fab2(sch_1):page75_i17@chpset_lib.skx_ext_b(chips)!SKX_EXT_B_BGA1-IC,TBD!!!F105!VSS(598)!!!!
S!GND!U2D1!BK11!@baseboard_fab2_lib.baseboard_fab2(sch_1):page75_i17@chpset_lib.skx_ext_b(chips)!SKX_EXT_B_BGA1-IC,TBD!!!F105!VSS(599)!!!!
S!GND!U2D1!BK7!@baseboard_fab2_lib.baseboard_fab2(sch_1):page75_i17@chpset_lib.skx_ext_b(chips)!SKX_EXT_B_BGA1-IC,TBD!!!F105!VSS(600)!!!!
S!GND!U2D1!BK3!@baseboard_fab2_lib.baseboard_fab2(sch_1):page75_i17@chpset_lib.skx_ext_b(chips)!SKX_EXT_B_BGA1-IC,TBD!!!F105!VSS(601)!!!!
S!GND!U2D1!BJ6!@baseboard_fab2_lib.baseboard_fab2(sch_1):page75_i17@chpset_lib.skx_ext_b(chips)!SKX_EXT_B_BGA1-IC,TBD!!!F105!VSS(602)!!!!
S!GND!U2D1!BJ4!@baseboard_fab2_lib.baseboard_fab2(sch_1):page75_i17@chpset_lib.skx_ext_b(chips)!SKX_EXT_B_BGA1-IC,TBD!!!F105!VSS(603)!!!!
S!GND!U2D1!BH21!@baseboard_fab2_lib.baseboard_fab2(sch_1):page75_i17@chpset_lib.skx_ext_b(chips)!SKX_EXT_B_BGA1-IC,TBD!!!F105!VSS(604)!!!!
S!GND!U2D1!BH15!@baseboard_fab2_lib.baseboard_fab2(sch_1):page75_i17@chpset_lib.skx_ext_b(chips)!SKX_EXT_B_BGA1-IC,TBD!!!F105!VSS(605)!!!!
S!GND!U2D1!BH11!@baseboard_fab2_lib.baseboard_fab2(sch_1):page75_i17@chpset_lib.skx_ext_b(chips)!SKX_EXT_B_BGA1-IC,TBD!!!F105!VSS(606)!!!!
S!GND!U2D1!BH9!@baseboard_fab2_lib.baseboard_fab2(sch_1):page75_i17@chpset_lib.skx_ext_b(chips)!SKX_EXT_B_BGA1-IC,TBD!!!F105!VSS(607)!!!!
S!GND!U2D1!BH7!@baseboard_fab2_lib.baseboard_fab2(sch_1):page75_i17@chpset_lib.skx_ext_b(chips)!SKX_EXT_B_BGA1-IC,TBD!!!F105!VSS(608)!!!!
S!GND!U2D1!BG82!@baseboard_fab2_lib.baseboard_fab2(sch_1):page75_i17@chpset_lib.skx_ext_b(chips)!SKX_EXT_B_BGA1-IC,TBD!!!F105!VSS(609)!!!!
S!GND!U2D1!BG80!@baseboard_fab2_lib.baseboard_fab2(sch_1):page75_i17@chpset_lib.skx_ext_b(chips)!SKX_EXT_B_BGA1-IC,TBD!!!F105!VSS(610)!!!!
S!GND!U2D1!BG78!@baseboard_fab2_lib.baseboard_fab2(sch_1):page75_i17@chpset_lib.skx_ext_b(chips)!SKX_EXT_B_BGA1-IC,TBD!!!F105!VSS(611)!!!!
S!GND!U2D1!BG76!@baseboard_fab2_lib.baseboard_fab2(sch_1):page75_i17@chpset_lib.skx_ext_b(chips)!SKX_EXT_B_BGA1-IC,TBD!!!F105!VSS(612)!!!!
S!GND!U2D1!BG74!@baseboard_fab2_lib.baseboard_fab2(sch_1):page75_i17@chpset_lib.skx_ext_b(chips)!SKX_EXT_B_BGA1-IC,TBD!!!F105!VSS(613)!!!!
S!GND!U2D1!BG72!@baseboard_fab2_lib.baseboard_fab2(sch_1):page74_i23@chpset_lib.skx_ext_b(chips)!SKX_EXT_B_BGA1-IC,TBD!!!F106!VSS(614)!!!!
S!GND!U2D1!BG24!@baseboard_fab2_lib.baseboard_fab2(sch_1):page74_i23@chpset_lib.skx_ext_b(chips)!SKX_EXT_B_BGA1-IC,TBD!!!F106!VSS(615)!!!!
S!GND!U2D1!BG22!@baseboard_fab2_lib.baseboard_fab2(sch_1):page74_i23@chpset_lib.skx_ext_b(chips)!SKX_EXT_B_BGA1-IC,TBD!!!F106!VSS(616)!!!!
S!GND!U2D1!BG10!@baseboard_fab2_lib.baseboard_fab2(sch_1):page74_i23@chpset_lib.skx_ext_b(chips)!SKX_EXT_B_BGA1-IC,TBD!!!F106!VSS(617)!!!!
S!GND!U2D1!BG8!@baseboard_fab2_lib.baseboard_fab2(sch_1):page74_i23@chpset_lib.skx_ext_b(chips)!SKX_EXT_B_BGA1-IC,TBD!!!F106!VSS(618)!!!!
S!GND!U2D1!BG6!@baseboard_fab2_lib.baseboard_fab2(sch_1):page74_i23@chpset_lib.skx_ext_b(chips)!SKX_EXT_B_BGA1-IC,TBD!!!F106!VSS(619)!!!!
S!GND!U2D1!BF71!@baseboard_fab2_lib.baseboard_fab2(sch_1):page74_i23@chpset_lib.skx_ext_b(chips)!SKX_EXT_B_BGA1-IC,TBD!!!F106!VSS(620)!!!!
S!GND!U2D1!BF69!@baseboard_fab2_lib.baseboard_fab2(sch_1):page74_i23@chpset_lib.skx_ext_b(chips)!SKX_EXT_B_BGA1-IC,TBD!!!F106!VSS(621)!!!!
S!GND!U2D1!BF67!@baseboard_fab2_lib.baseboard_fab2(sch_1):page74_i23@chpset_lib.skx_ext_b(chips)!SKX_EXT_B_BGA1-IC,TBD!!!F106!VSS(622)!!!!
S!GND!U2D1!BF65!@baseboard_fab2_lib.baseboard_fab2(sch_1):page74_i23@chpset_lib.skx_ext_b(chips)!SKX_EXT_B_BGA1-IC,TBD!!!F106!VSS(623)!!!!
S!GND!U2D1!BF63!@baseboard_fab2_lib.baseboard_fab2(sch_1):page74_i23@chpset_lib.skx_ext_b(chips)!SKX_EXT_B_BGA1-IC,TBD!!!F106!VSS(624)!!!!
S!GND!U2D1!BF25!@baseboard_fab2_lib.baseboard_fab2(sch_1):page74_i23@chpset_lib.skx_ext_b(chips)!SKX_EXT_B_BGA1-IC,TBD!!!F106!VSS(625)!!!!
S!GND!U2D1!BF19!@baseboard_fab2_lib.baseboard_fab2(sch_1):page74_i23@chpset_lib.skx_ext_b(chips)!SKX_EXT_B_BGA1-IC,TBD!!!F106!VSS(626)!!!!
S!GND!U2D1!BF17!@baseboard_fab2_lib.baseboard_fab2(sch_1):page74_i23@chpset_lib.skx_ext_b(chips)!SKX_EXT_B_BGA1-IC,TBD!!!F106!VSS(627)!!!!
S!GND!U2D1!BF15!@baseboard_fab2_lib.baseboard_fab2(sch_1):page74_i23@chpset_lib.skx_ext_b(chips)!SKX_EXT_B_BGA1-IC,TBD!!!F106!VSS(628)!!!!
S!GND!U2D1!BF9!@baseboard_fab2_lib.baseboard_fab2(sch_1):page74_i23@chpset_lib.skx_ext_b(chips)!SKX_EXT_B_BGA1-IC,TBD!!!F106!VSS(629)!!!!
S!GND!U2D1!BE70!@baseboard_fab2_lib.baseboard_fab2(sch_1):page74_i23@chpset_lib.skx_ext_b(chips)!SKX_EXT_B_BGA1-IC,TBD!!!F106!VSS(630)!!!!
S!GND!U2D1!BE68!@baseboard_fab2_lib.baseboard_fab2(sch_1):page74_i23@chpset_lib.skx_ext_b(chips)!SKX_EXT_B_BGA1-IC,TBD!!!F106!VSS(631)!!!!
S!GND!U2D1!BE66!@baseboard_fab2_lib.baseboard_fab2(sch_1):page74_i23@chpset_lib.skx_ext_b(chips)!SKX_EXT_B_BGA1-IC,TBD!!!F106!VSS(632)!!!!
S!GND!U2D1!BE64!@baseboard_fab2_lib.baseboard_fab2(sch_1):page74_i23@chpset_lib.skx_ext_b(chips)!SKX_EXT_B_BGA1-IC,TBD!!!F106!VSS(633)!!!!
S!GND!U2D1!BE26!@baseboard_fab2_lib.baseboard_fab2(sch_1):page74_i23@chpset_lib.skx_ext_b(chips)!SKX_EXT_B_BGA1-IC,TBD!!!F106!VSS(634)!!!!
S!GND!U2D1!BE10!@baseboard_fab2_lib.baseboard_fab2(sch_1):page74_i23@chpset_lib.skx_ext_b(chips)!SKX_EXT_B_BGA1-IC,TBD!!!F106!VSS(635)!!!!
S!GND!U2D1!BE8!@baseboard_fab2_lib.baseboard_fab2(sch_1):page74_i23@chpset_lib.skx_ext_b(chips)!SKX_EXT_B_BGA1-IC,TBD!!!F106!VSS(636)!!!!
S!GND!U2D1!BE6!@baseboard_fab2_lib.baseboard_fab2(sch_1):page74_i23@chpset_lib.skx_ext_b(chips)!SKX_EXT_B_BGA1-IC,TBD!!!F106!VSS(637)!!!!
S!GND!U2D1!BE4!@baseboard_fab2_lib.baseboard_fab2(sch_1):page74_i23@chpset_lib.skx_ext_b(chips)!SKX_EXT_B_BGA1-IC,TBD!!!F106!VSS(638)!!!!
S!GND!U2D1!BD71!@baseboard_fab2_lib.baseboard_fab2(sch_1):page74_i23@chpset_lib.skx_ext_b(chips)!SKX_EXT_B_BGA1-IC,TBD!!!F106!VSS(639)!!!!
S!GND!U2D1!BD63!@baseboard_fab2_lib.baseboard_fab2(sch_1):page74_i23@chpset_lib.skx_ext_b(chips)!SKX_EXT_B_BGA1-IC,TBD!!!F106!VSS(640)!!!!
S!GND!U2D1!BD27!@baseboard_fab2_lib.baseboard_fab2(sch_1):page74_i23@chpset_lib.skx_ext_b(chips)!SKX_EXT_B_BGA1-IC,TBD!!!F106!VSS(641)!!!!
S!GND!U2D1!BD21!@baseboard_fab2_lib.baseboard_fab2(sch_1):page74_i23@chpset_lib.skx_ext_b(chips)!SKX_EXT_B_BGA1-IC,TBD!!!F106!VSS(642)!!!!
S!GND!U2D1!BD15!@baseboard_fab2_lib.baseboard_fab2(sch_1):page74_i23@chpset_lib.skx_ext_b(chips)!SKX_EXT_B_BGA1-IC,TBD!!!F106!VSS(643)!!!!
S!GND!U2D1!BD11!@baseboard_fab2_lib.baseboard_fab2(sch_1):page74_i23@chpset_lib.skx_ext_b(chips)!SKX_EXT_B_BGA1-IC,TBD!!!F106!VSS(644)!!!!
S!GND!U2D1!BD5!@baseboard_fab2_lib.baseboard_fab2(sch_1):page74_i23@chpset_lib.skx_ext_b(chips)!SKX_EXT_B_BGA1-IC,TBD!!!F106!VSS(645)!!!!
S!GND!U2D1!BC82!@baseboard_fab2_lib.baseboard_fab2(sch_1):page74_i23@chpset_lib.skx_ext_b(chips)!SKX_EXT_B_BGA1-IC,TBD!!!F106!VSS(646)!!!!
S!GND!U2D1!BC80!@baseboard_fab2_lib.baseboard_fab2(sch_1):page74_i23@chpset_lib.skx_ext_b(chips)!SKX_EXT_B_BGA1-IC,TBD!!!F106!VSS(647)!!!!
S!GND!U2D1!BC78!@baseboard_fab2_lib.baseboard_fab2(sch_1):page74_i23@chpset_lib.skx_ext_b(chips)!SKX_EXT_B_BGA1-IC,TBD!!!F106!VSS(648)!!!!
S!GND!U2D1!BC76!@baseboard_fab2_lib.baseboard_fab2(sch_1):page74_i23@chpset_lib.skx_ext_b(chips)!SKX_EXT_B_BGA1-IC,TBD!!!F106!VSS(649)!!!!
S!GND!U2D1!BC74!@baseboard_fab2_lib.baseboard_fab2(sch_1):page74_i23@chpset_lib.skx_ext_b(chips)!SKX_EXT_B_BGA1-IC,TBD!!!F106!VSS(650)!!!!
S!GND!U2D1!BC72!@baseboard_fab2_lib.baseboard_fab2(sch_1):page74_i23@chpset_lib.skx_ext_b(chips)!SKX_EXT_B_BGA1-IC,TBD!!!F106!VSS(651)!!!!
S!GND!U2D1!BC70!@baseboard_fab2_lib.baseboard_fab2(sch_1):page74_i23@chpset_lib.skx_ext_b(chips)!SKX_EXT_B_BGA1-IC,TBD!!!F106!VSS(652)!!!!
S!GND!U2D1!BC16!@baseboard_fab2_lib.baseboard_fab2(sch_1):page74_i23@chpset_lib.skx_ext_b(chips)!SKX_EXT_B_BGA1-IC,TBD!!!F106!VSS(653)!!!!
S!GND!U2D1!BC12!@baseboard_fab2_lib.baseboard_fab2(sch_1):page74_i23@chpset_lib.skx_ext_b(chips)!SKX_EXT_B_BGA1-IC,TBD!!!F106!VSS(654)!!!!
S!GND!U2D1!BC8!@baseboard_fab2_lib.baseboard_fab2(sch_1):page74_i23@chpset_lib.skx_ext_b(chips)!SKX_EXT_B_BGA1-IC,TBD!!!F106!VSS(655)!!!!
S!GND!U2D1!BC4!@baseboard_fab2_lib.baseboard_fab2(sch_1):page74_i23@chpset_lib.skx_ext_b(chips)!SKX_EXT_B_BGA1-IC,TBD!!!F106!VSS(656)!!!!
S!GND!U2D1!BB83!@baseboard_fab2_lib.baseboard_fab2(sch_1):page74_i23@chpset_lib.skx_ext_b(chips)!SKX_EXT_B_BGA1-IC,TBD!!!F106!VSS(657)!!!!
S!GND!U2D1!BB81!@baseboard_fab2_lib.baseboard_fab2(sch_1):page74_i23@chpset_lib.skx_ext_b(chips)!SKX_EXT_B_BGA1-IC,TBD!!!F106!VSS(658)!!!!
S!GND!U2D1!BB79!@baseboard_fab2_lib.baseboard_fab2(sch_1):page74_i23@chpset_lib.skx_ext_b(chips)!SKX_EXT_B_BGA1-IC,TBD!!!F106!VSS(659)!!!!
S!GND!U2D1!BB77!@baseboard_fab2_lib.baseboard_fab2(sch_1):page74_i23@chpset_lib.skx_ext_b(chips)!SKX_EXT_B_BGA1-IC,TBD!!!F106!VSS(660)!!!!
S!GND!U2D1!BB75!@baseboard_fab2_lib.baseboard_fab2(sch_1):page74_i23@chpset_lib.skx_ext_b(chips)!SKX_EXT_B_BGA1-IC,TBD!!!F106!VSS(661)!!!!
S!GND!U2D1!BB73!@baseboard_fab2_lib.baseboard_fab2(sch_1):page74_i23@chpset_lib.skx_ext_b(chips)!SKX_EXT_B_BGA1-IC,TBD!!!F106!VSS(662)!!!!
S!GND!U2D1!BB69!@baseboard_fab2_lib.baseboard_fab2(sch_1):page74_i23@chpset_lib.skx_ext_b(chips)!SKX_EXT_B_BGA1-IC,TBD!!!F106!VSS(663)!!!!
S!GND!U2D1!BB63!@baseboard_fab2_lib.baseboard_fab2(sch_1):page74_i23@chpset_lib.skx_ext_b(chips)!SKX_EXT_B_BGA1-IC,TBD!!!F106!VSS(664)!!!!
S!GND!U2D1!BB23!@baseboard_fab2_lib.baseboard_fab2(sch_1):page74_i23@chpset_lib.skx_ext_b(chips)!SKX_EXT_B_BGA1-IC,TBD!!!F106!VSS(665)!!!!
S!GND!U2D1!BB19!@baseboard_fab2_lib.baseboard_fab2(sch_1):page74_i23@chpset_lib.skx_ext_b(chips)!SKX_EXT_B_BGA1-IC,TBD!!!F106!VSS(666)!!!!
S!GND!U2D1!BA84!@baseboard_fab2_lib.baseboard_fab2(sch_1):page74_i23@chpset_lib.skx_ext_b(chips)!SKX_EXT_B_BGA1-IC,TBD!!!F106!VSS(667)!!!!
S!GND!U2D1!BA80!@baseboard_fab2_lib.baseboard_fab2(sch_1):page74_i23@chpset_lib.skx_ext_b(chips)!SKX_EXT_B_BGA1-IC,TBD!!!F106!VSS(668)!!!!
S!GND!U2D1!BA74!@baseboard_fab2_lib.baseboard_fab2(sch_1):page74_i23@chpset_lib.skx_ext_b(chips)!SKX_EXT_B_BGA1-IC,TBD!!!F106!VSS(669)!!!!
S!GND!U2D1!BA68!@baseboard_fab2_lib.baseboard_fab2(sch_1):page74_i23@chpset_lib.skx_ext_b(chips)!SKX_EXT_B_BGA1-IC,TBD!!!F106!VSS(670)!!!!
S!GND!U2D1!BA62!@baseboard_fab2_lib.baseboard_fab2(sch_1):page74_i23@chpset_lib.skx_ext_b(chips)!SKX_EXT_B_BGA1-IC,TBD!!!F106!VSS(671)!!!!
S!GND!U2D1!BA12!@baseboard_fab2_lib.baseboard_fab2(sch_1):page74_i23@chpset_lib.skx_ext_b(chips)!SKX_EXT_B_BGA1-IC,TBD!!!F106!VSS(672)!!!!
S!GND!U2D1!BA6!@baseboard_fab2_lib.baseboard_fab2(sch_1):page74_i23@chpset_lib.skx_ext_b(chips)!SKX_EXT_B_BGA1-IC,TBD!!!F106!VSS(673)!!!!
S!GND!U2D1!BA2!@baseboard_fab2_lib.baseboard_fab2(sch_1):page74_i23@chpset_lib.skx_ext_b(chips)!SKX_EXT_B_BGA1-IC,TBD!!!F106!VSS(674)!!!!
S!GND!U2D1!AY81!@baseboard_fab2_lib.baseboard_fab2(sch_1):page74_i23@chpset_lib.skx_ext_b(chips)!SKX_EXT_B_BGA1-IC,TBD!!!F106!VSS(675)!!!!
S!GND!U2D1!AY79!@baseboard_fab2_lib.baseboard_fab2(sch_1):page74_i23@chpset_lib.skx_ext_b(chips)!SKX_EXT_B_BGA1-IC,TBD!!!F106!VSS(676)!!!!
S!GND!U2D1!AY63!@baseboard_fab2_lib.baseboard_fab2(sch_1):page74_i23@chpset_lib.skx_ext_b(chips)!SKX_EXT_B_BGA1-IC,TBD!!!F106!VSS(677)!!!!
S!GND!U2D1!AY25!@baseboard_fab2_lib.baseboard_fab2(sch_1):page74_i23@chpset_lib.skx_ext_b(chips)!SKX_EXT_B_BGA1-IC,TBD!!!F106!VSS(678)!!!!
S!GND!U2D1!AY23!@baseboard_fab2_lib.baseboard_fab2(sch_1):page74_i23@chpset_lib.skx_ext_b(chips)!SKX_EXT_B_BGA1-IC,TBD!!!F106!VSS(679)!!!!
S!GND!U2D1!AY21!@baseboard_fab2_lib.baseboard_fab2(sch_1):page74_i23@chpset_lib.skx_ext_b(chips)!SKX_EXT_B_BGA1-IC,TBD!!!F106!VSS(680)!!!!
S!GND!U2D1!AY17!@baseboard_fab2_lib.baseboard_fab2(sch_1):page74_i23@chpset_lib.skx_ext_b(chips)!SKX_EXT_B_BGA1-IC,TBD!!!F106!VSS(681)!!!!
S!GND!U2D1!AY15!@baseboard_fab2_lib.baseboard_fab2(sch_1):page74_i23@chpset_lib.skx_ext_b(chips)!SKX_EXT_B_BGA1-IC,TBD!!!F106!VSS(682)!!!!
S!GND!U2D1!AY5!@baseboard_fab2_lib.baseboard_fab2(sch_1):page74_i23@chpset_lib.skx_ext_b(chips)!SKX_EXT_B_BGA1-IC,TBD!!!F106!VSS(683)!!!!
S!GND!U2D1!AW84!@baseboard_fab2_lib.baseboard_fab2(sch_1):page74_i23@chpset_lib.skx_ext_b(chips)!SKX_EXT_B_BGA1-IC,TBD!!!F106!VSS(684)!!!!
S!GND!U2D1!AW82!@baseboard_fab2_lib.baseboard_fab2(sch_1):page74_i23@chpset_lib.skx_ext_b(chips)!SKX_EXT_B_BGA1-IC,TBD!!!F106!VSS(685)!!!!
S!GND!U2D1!AW78!@baseboard_fab2_lib.baseboard_fab2(sch_1):page74_i23@chpset_lib.skx_ext_b(chips)!SKX_EXT_B_BGA1-IC,TBD!!!F106!VSS(686)!!!!
S!GND!U2D1!AW74!@baseboard_fab2_lib.baseboard_fab2(sch_1):page74_i23@chpset_lib.skx_ext_b(chips)!SKX_EXT_B_BGA1-IC,TBD!!!F106!VSS(687)!!!!
S!GND!U2D1!AW72!@baseboard_fab2_lib.baseboard_fab2(sch_1):page74_i23@chpset_lib.skx_ext_b(chips)!SKX_EXT_B_BGA1-IC,TBD!!!F106!VSS(688)!!!!
S!GND!U2D1!AW70!@baseboard_fab2_lib.baseboard_fab2(sch_1):page74_i23@chpset_lib.skx_ext_b(chips)!SKX_EXT_B_BGA1-IC,TBD!!!F106!VSS(689)!!!!
S!GND!U2D1!AW68!@baseboard_fab2_lib.baseboard_fab2(sch_1):page74_i23@chpset_lib.skx_ext_b(chips)!SKX_EXT_B_BGA1-IC,TBD!!!F106!VSS(690)!!!!
S!GND!U2D1!AW66!@baseboard_fab2_lib.baseboard_fab2(sch_1):page74_i23@chpset_lib.skx_ext_b(chips)!SKX_EXT_B_BGA1-IC,TBD!!!F106!VSS(691)!!!!
S!GND!U2D1!AW62!@baseboard_fab2_lib.baseboard_fab2(sch_1):page74_i23@chpset_lib.skx_ext_b(chips)!SKX_EXT_B_BGA1-IC,TBD!!!F106!VSS(692)!!!!
S!GND!U2D1!AW10!@baseboard_fab2_lib.baseboard_fab2(sch_1):page74_i23@chpset_lib.skx_ext_b(chips)!SKX_EXT_B_BGA1-IC,TBD!!!F106!VSS(693)!!!!
S!GND!U2D1!AW2!@baseboard_fab2_lib.baseboard_fab2(sch_1):page74_i23@chpset_lib.skx_ext_b(chips)!SKX_EXT_B_BGA1-IC,TBD!!!F106!VSS(694)!!!!
S!GND!U2D1!AV83!@baseboard_fab2_lib.baseboard_fab2(sch_1):page74_i23@chpset_lib.skx_ext_b(chips)!SKX_EXT_B_BGA1-IC,TBD!!!F106!VSS(695)!!!!
S!GND!U2D1!AV75!@baseboard_fab2_lib.baseboard_fab2(sch_1):page74_i23@chpset_lib.skx_ext_b(chips)!SKX_EXT_B_BGA1-IC,TBD!!!F106!VSS(696)!!!!
S!GND!U2D1!AV67!@baseboard_fab2_lib.baseboard_fab2(sch_1):page74_i23@chpset_lib.skx_ext_b(chips)!SKX_EXT_B_BGA1-IC,TBD!!!F106!VSS(697)!!!!
S!GND!U2D1!AV65!@baseboard_fab2_lib.baseboard_fab2(sch_1):page74_i23@chpset_lib.skx_ext_b(chips)!SKX_EXT_B_BGA1-IC,TBD!!!F106!VSS(698)!!!!
S!GND!U2D1!AV63!@baseboard_fab2_lib.baseboard_fab2(sch_1):page74_i23@chpset_lib.skx_ext_b(chips)!SKX_EXT_B_BGA1-IC,TBD!!!F106!VSS(699)!!!!
S!GND!U2D1!AV25!@baseboard_fab2_lib.baseboard_fab2(sch_1):page74_i23@chpset_lib.skx_ext_b(chips)!SKX_EXT_B_BGA1-IC,TBD!!!F106!VSS(700)!!!!
S!GND!U2D1!AV23!@baseboard_fab2_lib.baseboard_fab2(sch_1):page74_i23@chpset_lib.skx_ext_b(chips)!SKX_EXT_B_BGA1-IC,TBD!!!F106!VSS(701)!!!!
S!GND!U2D1!AV19!@baseboard_fab2_lib.baseboard_fab2(sch_1):page74_i23@chpset_lib.skx_ext_b(chips)!SKX_EXT_B_BGA1-IC,TBD!!!F106!VSS(702)!!!!
S!GND!U2D1!AV13!@baseboard_fab2_lib.baseboard_fab2(sch_1):page74_i23@chpset_lib.skx_ext_b(chips)!SKX_EXT_B_BGA1-IC,TBD!!!F106!VSS(703)!!!!
S!GND!U2D1!AV11!@baseboard_fab2_lib.baseboard_fab2(sch_1):page74_i23@chpset_lib.skx_ext_b(chips)!SKX_EXT_B_BGA1-IC,TBD!!!F106!VSS(704)!!!!
S!GND!U2D1!AV7!@baseboard_fab2_lib.baseboard_fab2(sch_1):page74_i23@chpset_lib.skx_ext_b(chips)!SKX_EXT_B_BGA1-IC,TBD!!!F106!VSS(705)!!!!
S!GND!U2D1!AV3!@baseboard_fab2_lib.baseboard_fab2(sch_1):page74_i23@chpset_lib.skx_ext_b(chips)!SKX_EXT_B_BGA1-IC,TBD!!!F106!VSS(706)!!!!
S!GND!U2D1!AV1!@baseboard_fab2_lib.baseboard_fab2(sch_1):page74_i23@chpset_lib.skx_ext_b(chips)!SKX_EXT_B_BGA1-IC,TBD!!!F106!VSS(707)!!!!
S!GND!U2D1!AU86!@baseboard_fab2_lib.baseboard_fab2(sch_1):page74_i23@chpset_lib.skx_ext_b(chips)!SKX_EXT_B_BGA1-IC,TBD!!!F106!VSS(708)!!!!
S!GND!U2D1!AU84!@baseboard_fab2_lib.baseboard_fab2(sch_1):page74_i23@chpset_lib.skx_ext_b(chips)!SKX_EXT_B_BGA1-IC,TBD!!!F106!VSS(709)!!!!
S!GND!U2D1!AU80!@baseboard_fab2_lib.baseboard_fab2(sch_1):page74_i23@chpset_lib.skx_ext_b(chips)!SKX_EXT_B_BGA1-IC,TBD!!!F106!VSS(710)!!!!
S!GND!U2D1!AU78!@baseboard_fab2_lib.baseboard_fab2(sch_1):page74_i23@chpset_lib.skx_ext_b(chips)!SKX_EXT_B_BGA1-IC,TBD!!!F106!VSS(711)!!!!
S!GND!U2D1!AU76!@baseboard_fab2_lib.baseboard_fab2(sch_1):page74_i23@chpset_lib.skx_ext_b(chips)!SKX_EXT_B_BGA1-IC,TBD!!!F106!VSS(712)!!!!
S!GND!U2D1!AU74!@baseboard_fab2_lib.baseboard_fab2(sch_1):page74_i23@chpset_lib.skx_ext_b(chips)!SKX_EXT_B_BGA1-IC,TBD!!!F106!VSS(713)!!!!
S!GND!U2D1!AU68!@baseboard_fab2_lib.baseboard_fab2(sch_1):page74_i23@chpset_lib.skx_ext_b(chips)!SKX_EXT_B_BGA1-IC,TBD!!!F106!VSS(714)!!!!
S!GND!U2D1!AU64!@baseboard_fab2_lib.baseboard_fab2(sch_1):page74_i23@chpset_lib.skx_ext_b(chips)!SKX_EXT_B_BGA1-IC,TBD!!!F106!VSS(715)!!!!
S!GND!U2D1!AU62!@baseboard_fab2_lib.baseboard_fab2(sch_1):page74_i23@chpset_lib.skx_ext_b(chips)!SKX_EXT_B_BGA1-IC,TBD!!!F106!VSS(716)!!!!
S!GND!U2D1!AU28!@baseboard_fab2_lib.baseboard_fab2(sch_1):page74_i23@chpset_lib.skx_ext_b(chips)!SKX_EXT_B_BGA1-IC,TBD!!!F106!VSS(717)!!!!
S!GND!U2D1!AU26!@baseboard_fab2_lib.baseboard_fab2(sch_1):page74_i23@chpset_lib.skx_ext_b(chips)!SKX_EXT_B_BGA1-IC,TBD!!!F106!VSS(718)!!!!
S!GND!U2D1!AU6!@baseboard_fab2_lib.baseboard_fab2(sch_1):page74_i23@chpset_lib.skx_ext_b(chips)!SKX_EXT_B_BGA1-IC,TBD!!!F106!VSS(719)!!!!
S!GND!U2D1!AU2!@baseboard_fab2_lib.baseboard_fab2(sch_1):page74_i23@chpset_lib.skx_ext_b(chips)!SKX_EXT_B_BGA1-IC,TBD!!!F106!VSS(720)!!!!
S!GND!U2D1!AT85!@baseboard_fab2_lib.baseboard_fab2(sch_1):page74_i23@chpset_lib.skx_ext_b(chips)!SKX_EXT_B_BGA1-IC,TBD!!!F106!VSS(721)!!!!
S!GND!U2D1!AT83!@baseboard_fab2_lib.baseboard_fab2(sch_1):page74_i23@chpset_lib.skx_ext_b(chips)!SKX_EXT_B_BGA1-IC,TBD!!!F106!VSS(722)!!!!
S!GND!U2D1!AT77!@baseboard_fab2_lib.baseboard_fab2(sch_1):page74_i23@chpset_lib.skx_ext_b(chips)!SKX_EXT_B_BGA1-IC,TBD!!!F106!VSS(723)!!!!
S!GND!U2D1!AT73!@baseboard_fab2_lib.baseboard_fab2(sch_1):page74_i23@chpset_lib.skx_ext_b(chips)!SKX_EXT_B_BGA1-IC,TBD!!!F106!VSS(724)!!!!
S!GND!U2D1!AT69!@baseboard_fab2_lib.baseboard_fab2(sch_1):page74_i23@chpset_lib.skx_ext_b(chips)!SKX_EXT_B_BGA1-IC,TBD!!!F106!VSS(725)!!!!
S!GND!U2D1!AT63!@baseboard_fab2_lib.baseboard_fab2(sch_1):page74_i23@chpset_lib.skx_ext_b(chips)!SKX_EXT_B_BGA1-IC,TBD!!!F106!VSS(726)!!!!
S!GND!U2D1!AT61!@baseboard_fab2_lib.baseboard_fab2(sch_1):page74_i23@chpset_lib.skx_ext_b(chips)!SKX_EXT_B_BGA1-IC,TBD!!!F106!VSS(727)!!!!
S!GND!U2D1!AT27!@baseboard_fab2_lib.baseboard_fab2(sch_1):page74_i23@chpset_lib.skx_ext_b(chips)!SKX_EXT_B_BGA1-IC,TBD!!!F106!VSS(728)!!!!
S!GND!U2D1!AT21!@baseboard_fab2_lib.baseboard_fab2(sch_1):page74_i23@chpset_lib.skx_ext_b(chips)!SKX_EXT_B_BGA1-IC,TBD!!!F106!VSS(729)!!!!
S!GND!U2D1!AT17!@baseboard_fab2_lib.baseboard_fab2(sch_1):page74_i23@chpset_lib.skx_ext_b(chips)!SKX_EXT_B_BGA1-IC,TBD!!!F106!VSS(730)!!!!
S!GND!U2D1!AT15!@baseboard_fab2_lib.baseboard_fab2(sch_1):page74_i23@chpset_lib.skx_ext_b(chips)!SKX_EXT_B_BGA1-IC,TBD!!!F106!VSS(731)!!!!
S!GND!U2D1!P63!@baseboard_fab2_lib.baseboard_fab2(sch_1):page74_i23@chpset_lib.skx_ext_b(chips)!SKX_EXT_B_BGA1-IC,TBD!!!F106!VSS(732)!!!!
S!GND!U2D1!AC48!@baseboard_fab2_lib.baseboard_fab2(sch_1):page74_i23@chpset_lib.skx_ext_b(chips)!SKX_EXT_B_BGA1-IC,TBD!!!F106!VSS(733)!!!!
S!GND!U2D1!AR78!@baseboard_fab2_lib.baseboard_fab2(sch_1):page74_i23@chpset_lib.skx_ext_b(chips)!SKX_EXT_B_BGA1-IC,TBD!!!F106!VSS(734)!!!!
S!GND!U2D1!AR72!@baseboard_fab2_lib.baseboard_fab2(sch_1):page74_i23@chpset_lib.skx_ext_b(chips)!SKX_EXT_B_BGA1-IC,TBD!!!F106!VSS(735)!!!!
S!GND!U2D1!AR60!@baseboard_fab2_lib.baseboard_fab2(sch_1):page74_i23@chpset_lib.skx_ext_b(chips)!SKX_EXT_B_BGA1-IC,TBD!!!F106!VSS(736)!!!!
S!GND!U2D1!AR30!@baseboard_fab2_lib.baseboard_fab2(sch_1):page74_i23@chpset_lib.skx_ext_b(chips)!SKX_EXT_B_BGA1-IC,TBD!!!F106!VSS(737)!!!!
S!GND!U2D1!AR24!@baseboard_fab2_lib.baseboard_fab2(sch_1):page74_i23@chpset_lib.skx_ext_b(chips)!SKX_EXT_B_BGA1-IC,TBD!!!F106!VSS(738)!!!!
S!GND!U2D1!AR10!@baseboard_fab2_lib.baseboard_fab2(sch_1):page74_i23@chpset_lib.skx_ext_b(chips)!SKX_EXT_B_BGA1-IC,TBD!!!F106!VSS(739)!!!!
S!GND!U2D1!AP85!@baseboard_fab2_lib.baseboard_fab2(sch_1):page74_i23@chpset_lib.skx_ext_b(chips)!SKX_EXT_B_BGA1-IC,TBD!!!F106!VSS(740)!!!!
S!GND!U2D1!AP83!@baseboard_fab2_lib.baseboard_fab2(sch_1):page74_i23@chpset_lib.skx_ext_b(chips)!SKX_EXT_B_BGA1-IC,TBD!!!F106!VSS(741)!!!!
S!GND!U2D1!AP81!@baseboard_fab2_lib.baseboard_fab2(sch_1):page74_i23@chpset_lib.skx_ext_b(chips)!SKX_EXT_B_BGA1-IC,TBD!!!F106!VSS(742)!!!!
S!GND!U2D1!AP75!@baseboard_fab2_lib.baseboard_fab2(sch_1):page74_i23@chpset_lib.skx_ext_b(chips)!SKX_EXT_B_BGA1-IC,TBD!!!F106!VSS(743)!!!!
S!GND!U2D1!AP73!@baseboard_fab2_lib.baseboard_fab2(sch_1):page74_i23@chpset_lib.skx_ext_b(chips)!SKX_EXT_B_BGA1-IC,TBD!!!F106!VSS(744)!!!!
S!GND!U2D1!AP69!@baseboard_fab2_lib.baseboard_fab2(sch_1):page74_i23@chpset_lib.skx_ext_b(chips)!SKX_EXT_B_BGA1-IC,TBD!!!F106!VSS(745)!!!!
S!GND!U2D1!AP67!@baseboard_fab2_lib.baseboard_fab2(sch_1):page74_i23@chpset_lib.skx_ext_b(chips)!SKX_EXT_B_BGA1-IC,TBD!!!F106!VSS(746)!!!!
S!GND!U2D1!AP65!@baseboard_fab2_lib.baseboard_fab2(sch_1):page74_i23@chpset_lib.skx_ext_b(chips)!SKX_EXT_B_BGA1-IC,TBD!!!F106!VSS(747)!!!!
S!GND!U2D1!H63!@baseboard_fab2_lib.baseboard_fab2(sch_1):page75_i18@chpset_lib.skx_ext_b(chips)!SKX_EXT_B_BGA1-IC,TBD!!!F104!VSS(428)!!!!
S!GND!U2D1!P45!@baseboard_fab2_lib.baseboard_fab2(sch_1):page75_i18@chpset_lib.skx_ext_b(chips)!SKX_EXT_B_BGA1-IC,TBD!!!F104!VSS(429)!!!!
S!GND!U2D1!CL18!@baseboard_fab2_lib.baseboard_fab2(sch_1):page75_i18@chpset_lib.skx_ext_b(chips)!SKX_EXT_B_BGA1-IC,TBD!!!F104!VSS(430)!!!!
S!GND!U2D1!CL14!@baseboard_fab2_lib.baseboard_fab2(sch_1):page75_i18@chpset_lib.skx_ext_b(chips)!SKX_EXT_B_BGA1-IC,TBD!!!F104!VSS(431)!!!!
S!GND!U2D1!CL8!@baseboard_fab2_lib.baseboard_fab2(sch_1):page75_i18@chpset_lib.skx_ext_b(chips)!SKX_EXT_B_BGA1-IC,TBD!!!F104!VSS(432)!!!!
S!GND!U2D1!CK85!@baseboard_fab2_lib.baseboard_fab2(sch_1):page75_i18@chpset_lib.skx_ext_b(chips)!SKX_EXT_B_BGA1-IC,TBD!!!F104!VSS(433)!!!!
S!GND!U2D1!CK83!@baseboard_fab2_lib.baseboard_fab2(sch_1):page75_i18@chpset_lib.skx_ext_b(chips)!SKX_EXT_B_BGA1-IC,TBD!!!F104!VSS(434)!!!!
S!GND!U2D1!CK75!@baseboard_fab2_lib.baseboard_fab2(sch_1):page75_i18@chpset_lib.skx_ext_b(chips)!SKX_EXT_B_BGA1-IC,TBD!!!F104!VSS(435)!!!!
S!GND!U2D1!CK73!@baseboard_fab2_lib.baseboard_fab2(sch_1):page75_i18@chpset_lib.skx_ext_b(chips)!SKX_EXT_B_BGA1-IC,TBD!!!F104!VSS(436)!!!!
S!GND!U2D1!CK71!@baseboard_fab2_lib.baseboard_fab2(sch_1):page75_i18@chpset_lib.skx_ext_b(chips)!SKX_EXT_B_BGA1-IC,TBD!!!F104!VSS(437)!!!!
S!GND!U2D1!CK69!@baseboard_fab2_lib.baseboard_fab2(sch_1):page75_i18@chpset_lib.skx_ext_b(chips)!SKX_EXT_B_BGA1-IC,TBD!!!F104!VSS(438)!!!!
S!GND!U2D1!CK67!@baseboard_fab2_lib.baseboard_fab2(sch_1):page75_i18@chpset_lib.skx_ext_b(chips)!SKX_EXT_B_BGA1-IC,TBD!!!F104!VSS(439)!!!!
S!GND!U2D1!CK65!@baseboard_fab2_lib.baseboard_fab2(sch_1):page75_i18@chpset_lib.skx_ext_b(chips)!SKX_EXT_B_BGA1-IC,TBD!!!F104!VSS(440)!!!!
S!GND!U2D1!CK63!@baseboard_fab2_lib.baseboard_fab2(sch_1):page75_i18@chpset_lib.skx_ext_b(chips)!SKX_EXT_B_BGA1-IC,TBD!!!F104!VSS(441)!!!!
S!GND!U2D1!CK27!@baseboard_fab2_lib.baseboard_fab2(sch_1):page75_i18@chpset_lib.skx_ext_b(chips)!SKX_EXT_B_BGA1-IC,TBD!!!F104!VSS(442)!!!!
S!GND!U2D1!CK21!@baseboard_fab2_lib.baseboard_fab2(sch_1):page75_i18@chpset_lib.skx_ext_b(chips)!SKX_EXT_B_BGA1-IC,TBD!!!F104!VSS(443)!!!!
S!GND!U2D1!CK15!@baseboard_fab2_lib.baseboard_fab2(sch_1):page75_i18@chpset_lib.skx_ext_b(chips)!SKX_EXT_B_BGA1-IC,TBD!!!F104!VSS(444)!!!!
S!GND!U2D1!CK11!@baseboard_fab2_lib.baseboard_fab2(sch_1):page75_i18@chpset_lib.skx_ext_b(chips)!SKX_EXT_B_BGA1-IC,TBD!!!F104!VSS(445)!!!!
S!GND!U2D1!CJ86!@baseboard_fab2_lib.baseboard_fab2(sch_1):page75_i18@chpset_lib.skx_ext_b(chips)!SKX_EXT_B_BGA1-IC,TBD!!!F104!VSS(446)!!!!
S!GND!U2D1!CJ84!@baseboard_fab2_lib.baseboard_fab2(sch_1):page75_i18@chpset_lib.skx_ext_b(chips)!SKX_EXT_B_BGA1-IC,TBD!!!F104!VSS(447)!!!!
S!GND!U2D1!CJ82!@baseboard_fab2_lib.baseboard_fab2(sch_1):page75_i18@chpset_lib.skx_ext_b(chips)!SKX_EXT_B_BGA1-IC,TBD!!!F104!VSS(448)!!!!
S!GND!U2D1!CJ78!@baseboard_fab2_lib.baseboard_fab2(sch_1):page75_i18@chpset_lib.skx_ext_b(chips)!SKX_EXT_B_BGA1-IC,TBD!!!F104!VSS(449)!!!!
S!GND!U2D1!CJ76!@baseboard_fab2_lib.baseboard_fab2(sch_1):page75_i18@chpset_lib.skx_ext_b(chips)!SKX_EXT_B_BGA1-IC,TBD!!!F104!VSS(450)!!!!
S!GND!U2D1!CJ74!@baseboard_fab2_lib.baseboard_fab2(sch_1):page75_i18@chpset_lib.skx_ext_b(chips)!SKX_EXT_B_BGA1-IC,TBD!!!F104!VSS(451)!!!!
S!GND!U2D1!CJ62!@baseboard_fab2_lib.baseboard_fab2(sch_1):page75_i18@chpset_lib.skx_ext_b(chips)!SKX_EXT_B_BGA1-IC,TBD!!!F104!VSS(452)!!!!
S!GND!U2D1!P47!@baseboard_fab2_lib.baseboard_fab2(sch_1):page75_i18@chpset_lib.skx_ext_b(chips)!SKX_EXT_B_BGA1-IC,TBD!!!F104!VSS(453)!!!!
S!GND!U2D1!P49!@baseboard_fab2_lib.baseboard_fab2(sch_1):page75_i17@chpset_lib.skx_ext_b(chips)!SKX_EXT_B_BGA1-IC,TBD!!!F105!VSS(454)!!!!
S!GND!U2D1!CJ12!@baseboard_fab2_lib.baseboard_fab2(sch_1):page75_i17@chpset_lib.skx_ext_b(chips)!SKX_EXT_B_BGA1-IC,TBD!!!F105!VSS(455)!!!!
S!GND!U2D1!CJ10!@baseboard_fab2_lib.baseboard_fab2(sch_1):page75_i17@chpset_lib.skx_ext_b(chips)!SKX_EXT_B_BGA1-IC,TBD!!!F105!VSS(456)!!!!
S!GND!U2D1!CJ8!@baseboard_fab2_lib.baseboard_fab2(sch_1):page75_i17@chpset_lib.skx_ext_b(chips)!SKX_EXT_B_BGA1-IC,TBD!!!F105!VSS(457)!!!!
S!GND!U2D1!CJ6!@baseboard_fab2_lib.baseboard_fab2(sch_1):page75_i17@chpset_lib.skx_ext_b(chips)!SKX_EXT_B_BGA1-IC,TBD!!!F105!VSS(458)!!!!
S!GND!U2D1!CJ2!@baseboard_fab2_lib.baseboard_fab2(sch_1):page75_i17@chpset_lib.skx_ext_b(chips)!SKX_EXT_B_BGA1-IC,TBD!!!F105!VSS(459)!!!!
S!GND!U2D1!CH83!@baseboard_fab2_lib.baseboard_fab2(sch_1):page75_i17@chpset_lib.skx_ext_b(chips)!SKX_EXT_B_BGA1-IC,TBD!!!F105!VSS(460)!!!!
S!GND!U2D1!CH81!@baseboard_fab2_lib.baseboard_fab2(sch_1):page75_i17@chpset_lib.skx_ext_b(chips)!SKX_EXT_B_BGA1-IC,TBD!!!F105!VSS(461)!!!!
S!GND!U2D1!CH79!@baseboard_fab2_lib.baseboard_fab2(sch_1):page75_i17@chpset_lib.skx_ext_b(chips)!SKX_EXT_B_BGA1-IC,TBD!!!F105!VSS(462)!!!!
S!GND!U2D1!CH73!@baseboard_fab2_lib.baseboard_fab2(sch_1):page75_i17@chpset_lib.skx_ext_b(chips)!SKX_EXT_B_BGA1-IC,TBD!!!F105!VSS(463)!!!!
S!GND!U2D1!CH67!@baseboard_fab2_lib.baseboard_fab2(sch_1):page75_i17@chpset_lib.skx_ext_b(chips)!SKX_EXT_B_BGA1-IC,TBD!!!F105!VSS(464)!!!!
S!GND!U2D1!CH63!@baseboard_fab2_lib.baseboard_fab2(sch_1):page75_i17@chpset_lib.skx_ext_b(chips)!SKX_EXT_B_BGA1-IC,TBD!!!F105!VSS(465)!!!!
S!GND!U2D1!CH19!@baseboard_fab2_lib.baseboard_fab2(sch_1):page75_i17@chpset_lib.skx_ext_b(chips)!SKX_EXT_B_BGA1-IC,TBD!!!F105!VSS(466)!!!!
S!GND!U2D1!CH15!@baseboard_fab2_lib.baseboard_fab2(sch_1):page75_i17@chpset_lib.skx_ext_b(chips)!SKX_EXT_B_BGA1-IC,TBD!!!F105!VSS(467)!!!!
S!GND!U2D1!CH3!@baseboard_fab2_lib.baseboard_fab2(sch_1):page75_i17@chpset_lib.skx_ext_b(chips)!SKX_EXT_B_BGA1-IC,TBD!!!F105!VSS(468)!!!!
S!GND!U2D1!CH1!@baseboard_fab2_lib.baseboard_fab2(sch_1):page75_i17@chpset_lib.skx_ext_b(chips)!SKX_EXT_B_BGA1-IC,TBD!!!F105!VSS(469)!!!!
S!GND!U2D1!CG80!@baseboard_fab2_lib.baseboard_fab2(sch_1):page75_i17@chpset_lib.skx_ext_b(chips)!SKX_EXT_B_BGA1-IC,TBD!!!F105!VSS(470)!!!!
S!GND!U2D1!CG72!@baseboard_fab2_lib.baseboard_fab2(sch_1):page75_i17@chpset_lib.skx_ext_b(chips)!SKX_EXT_B_BGA1-IC,TBD!!!F105!VSS(471)!!!!
S!GND!U2D1!CG68!@baseboard_fab2_lib.baseboard_fab2(sch_1):page75_i17@chpset_lib.skx_ext_b(chips)!SKX_EXT_B_BGA1-IC,TBD!!!F105!VSS(472)!!!!
S!GND!U2D1!CG62!@baseboard_fab2_lib.baseboard_fab2(sch_1):page75_i17@chpset_lib.skx_ext_b(chips)!SKX_EXT_B_BGA1-IC,TBD!!!F105!VSS(473)!!!!
S!GND!U2D1!CG22!@baseboard_fab2_lib.baseboard_fab2(sch_1):page75_i17@chpset_lib.skx_ext_b(chips)!SKX_EXT_B_BGA1-IC,TBD!!!F105!VSS(474)!!!!
S!GND!U2D1!CG18!@baseboard_fab2_lib.baseboard_fab2(sch_1):page75_i17@chpset_lib.skx_ext_b(chips)!SKX_EXT_B_BGA1-IC,TBD!!!F105!VSS(475)!!!!
S!GND!U2D1!P51!@baseboard_fab2_lib.baseboard_fab2(sch_1):page75_i17@chpset_lib.skx_ext_b(chips)!SKX_EXT_B_BGA1-IC,TBD!!!F105!VSS(476)!!!!
S!GND!U2D1!CF83!@baseboard_fab2_lib.baseboard_fab2(sch_1):page75_i17@chpset_lib.skx_ext_b(chips)!SKX_EXT_B_BGA1-IC,TBD!!!F105!VSS(477)!!!!
S!GND!U2D1!CF77!@baseboard_fab2_lib.baseboard_fab2(sch_1):page75_i17@chpset_lib.skx_ext_b(chips)!SKX_EXT_B_BGA1-IC,TBD!!!F105!VSS(478)!!!!
S!GND!U2D1!CF71!@baseboard_fab2_lib.baseboard_fab2(sch_1):page75_i17@chpset_lib.skx_ext_b(chips)!SKX_EXT_B_BGA1-IC,TBD!!!F105!VSS(479)!!!!
S!GND!U2D1!CF69!@baseboard_fab2_lib.baseboard_fab2(sch_1):page75_i17@chpset_lib.skx_ext_b(chips)!SKX_EXT_B_BGA1-IC,TBD!!!F105!VSS(480)!!!!
S!GND!U2D1!CF63!@baseboard_fab2_lib.baseboard_fab2(sch_1):page75_i17@chpset_lib.skx_ext_b(chips)!SKX_EXT_B_BGA1-IC,TBD!!!F105!VSS(481)!!!!
S!GND!U2D1!CF9!@baseboard_fab2_lib.baseboard_fab2(sch_1):page75_i17@chpset_lib.skx_ext_b(chips)!SKX_EXT_B_BGA1-IC,TBD!!!F105!VSS(482)!!!!
S!GND!U2D1!P53!@baseboard_fab2_lib.baseboard_fab2(sch_1):page75_i17@chpset_lib.skx_ext_b(chips)!SKX_EXT_B_BGA1-IC,TBD!!!F105!VSS(483)!!!!
S!GND!U2D1!CE82!@baseboard_fab2_lib.baseboard_fab2(sch_1):page75_i17@chpset_lib.skx_ext_b(chips)!SKX_EXT_B_BGA1-IC,TBD!!!F105!VSS(484)!!!!
S!GND!U2D1!CE70!@baseboard_fab2_lib.baseboard_fab2(sch_1):page75_i17@chpset_lib.skx_ext_b(chips)!SKX_EXT_B_BGA1-IC,TBD!!!F105!VSS(485)!!!!
S!GND!U2D1!CE62!@baseboard_fab2_lib.baseboard_fab2(sch_1):page75_i17@chpset_lib.skx_ext_b(chips)!SKX_EXT_B_BGA1-IC,TBD!!!F105!VSS(486)!!!!
S!GND!U2D1!CE26!@baseboard_fab2_lib.baseboard_fab2(sch_1):page75_i17@chpset_lib.skx_ext_b(chips)!SKX_EXT_B_BGA1-IC,TBD!!!F105!VSS(487)!!!!
S!GND!U2D1!CE20!@baseboard_fab2_lib.baseboard_fab2(sch_1):page75_i17@chpset_lib.skx_ext_b(chips)!SKX_EXT_B_BGA1-IC,TBD!!!F105!VSS(488)!!!!
S!GND!U2D1!CE14!@baseboard_fab2_lib.baseboard_fab2(sch_1):page75_i17@chpset_lib.skx_ext_b(chips)!SKX_EXT_B_BGA1-IC,TBD!!!F105!VSS(489)!!!!
S!GND!U2D1!CE10!@baseboard_fab2_lib.baseboard_fab2(sch_1):page75_i17@chpset_lib.skx_ext_b(chips)!SKX_EXT_B_BGA1-IC,TBD!!!F105!VSS(490)!!!!
S!GND!U2D1!CD81!@baseboard_fab2_lib.baseboard_fab2(sch_1):page75_i17@chpset_lib.skx_ext_b(chips)!SKX_EXT_B_BGA1-IC,TBD!!!F105!VSS(491)!!!!
S!GND!U2D1!CD79!@baseboard_fab2_lib.baseboard_fab2(sch_1):page75_i17@chpset_lib.skx_ext_b(chips)!SKX_EXT_B_BGA1-IC,TBD!!!F105!VSS(492)!!!!
S!GND!U2D1!CD77!@baseboard_fab2_lib.baseboard_fab2(sch_1):page75_i17@chpset_lib.skx_ext_b(chips)!SKX_EXT_B_BGA1-IC,TBD!!!F105!VSS(493)!!!!
S!GND!U2D1!CD75!@baseboard_fab2_lib.baseboard_fab2(sch_1):page75_i17@chpset_lib.skx_ext_b(chips)!SKX_EXT_B_BGA1-IC,TBD!!!F105!VSS(494)!!!!
S!GND!U2D1!CD73!@baseboard_fab2_lib.baseboard_fab2(sch_1):page75_i17@chpset_lib.skx_ext_b(chips)!SKX_EXT_B_BGA1-IC,TBD!!!F105!VSS(495)!!!!
S!GND!U2D1!CD63!@baseboard_fab2_lib.baseboard_fab2(sch_1):page75_i17@chpset_lib.skx_ext_b(chips)!SKX_EXT_B_BGA1-IC,TBD!!!F105!VSS(496)!!!!
S!GND!U2D1!CD13!@baseboard_fab2_lib.baseboard_fab2(sch_1):page75_i17@chpset_lib.skx_ext_b(chips)!SKX_EXT_B_BGA1-IC,TBD!!!F105!VSS(497)!!!!
S!GND!U2D1!CD5!@baseboard_fab2_lib.baseboard_fab2(sch_1):page75_i17@chpset_lib.skx_ext_b(chips)!SKX_EXT_B_BGA1-IC,TBD!!!F105!VSS(498)!!!!
S!GND!U2D1!CC82!@baseboard_fab2_lib.baseboard_fab2(sch_1):page75_i17@chpset_lib.skx_ext_b(chips)!SKX_EXT_B_BGA1-IC,TBD!!!F105!VSS(499)!!!!
S!GND!U2D1!CC80!@baseboard_fab2_lib.baseboard_fab2(sch_1):page75_i17@chpset_lib.skx_ext_b(chips)!SKX_EXT_B_BGA1-IC,TBD!!!F105!VSS(500)!!!!
S!GND!U2D1!CC78!@baseboard_fab2_lib.baseboard_fab2(sch_1):page75_i17@chpset_lib.skx_ext_b(chips)!SKX_EXT_B_BGA1-IC,TBD!!!F105!VSS(501)!!!!
S!GND!U2D1!CC76!@baseboard_fab2_lib.baseboard_fab2(sch_1):page75_i17@chpset_lib.skx_ext_b(chips)!SKX_EXT_B_BGA1-IC,TBD!!!F105!VSS(502)!!!!
S!GND!U2D1!CC74!@baseboard_fab2_lib.baseboard_fab2(sch_1):page75_i17@chpset_lib.skx_ext_b(chips)!SKX_EXT_B_BGA1-IC,TBD!!!F105!VSS(503)!!!!
S!GND!U2D1!CC72!@baseboard_fab2_lib.baseboard_fab2(sch_1):page75_i17@chpset_lib.skx_ext_b(chips)!SKX_EXT_B_BGA1-IC,TBD!!!F105!VSS(504)!!!!
S!GND!U2D1!CC64!@baseboard_fab2_lib.baseboard_fab2(sch_1):page75_i17@chpset_lib.skx_ext_b(chips)!SKX_EXT_B_BGA1-IC,TBD!!!F105!VSS(505)!!!!
S!GND!U2D1!CC24!@baseboard_fab2_lib.baseboard_fab2(sch_1):page75_i17@chpset_lib.skx_ext_b(chips)!SKX_EXT_B_BGA1-IC,TBD!!!F105!VSS(506)!!!!
S!GND!U2D1!CC18!@baseboard_fab2_lib.baseboard_fab2(sch_1):page75_i17@chpset_lib.skx_ext_b(chips)!SKX_EXT_B_BGA1-IC,TBD!!!F105!VSS(507)!!!!
S!GND!U2D1!CC16!@baseboard_fab2_lib.baseboard_fab2(sch_1):page75_i17@chpset_lib.skx_ext_b(chips)!SKX_EXT_B_BGA1-IC,TBD!!!F105!VSS(508)!!!!
S!GND!U2D1!CC4!@baseboard_fab2_lib.baseboard_fab2(sch_1):page75_i17@chpset_lib.skx_ext_b(chips)!SKX_EXT_B_BGA1-IC,TBD!!!F105!VSS(509)!!!!
S!GND!U2D1!CB71!@baseboard_fab2_lib.baseboard_fab2(sch_1):page75_i17@chpset_lib.skx_ext_b(chips)!SKX_EXT_B_BGA1-IC,TBD!!!F105!VSS(510)!!!!
S!GND!U2D1!CB63!@baseboard_fab2_lib.baseboard_fab2(sch_1):page75_i17@chpset_lib.skx_ext_b(chips)!SKX_EXT_B_BGA1-IC,TBD!!!F105!VSS(511)!!!!
S!GND!U2D1!CB27!@baseboard_fab2_lib.baseboard_fab2(sch_1):page75_i17@chpset_lib.skx_ext_b(chips)!SKX_EXT_B_BGA1-IC,TBD!!!F105!VSS(512)!!!!
S!GND!U2D1!CB9!@baseboard_fab2_lib.baseboard_fab2(sch_1):page75_i17@chpset_lib.skx_ext_b(chips)!SKX_EXT_B_BGA1-IC,TBD!!!F105!VSS(513)!!!!
S!GND!U2D1!CB7!@baseboard_fab2_lib.baseboard_fab2(sch_1):page75_i17@chpset_lib.skx_ext_b(chips)!SKX_EXT_B_BGA1-IC,TBD!!!F105!VSS(514)!!!!
S!GND!U2D1!CA70!@baseboard_fab2_lib.baseboard_fab2(sch_1):page75_i17@chpset_lib.skx_ext_b(chips)!SKX_EXT_B_BGA1-IC,TBD!!!F105!VSS(515)!!!!
S!GND!U2D1!CA68!@baseboard_fab2_lib.baseboard_fab2(sch_1):page75_i17@chpset_lib.skx_ext_b(chips)!SKX_EXT_B_BGA1-IC,TBD!!!F105!VSS(516)!!!!
S!GND!U2D1!CA66!@baseboard_fab2_lib.baseboard_fab2(sch_1):page75_i17@chpset_lib.skx_ext_b(chips)!SKX_EXT_B_BGA1-IC,TBD!!!F105!VSS(517)!!!!
S!GND!U2D1!CA64!@baseboard_fab2_lib.baseboard_fab2(sch_1):page75_i17@chpset_lib.skx_ext_b(chips)!SKX_EXT_B_BGA1-IC,TBD!!!F105!VSS(518)!!!!
S!GND!U2D1!CA26!@baseboard_fab2_lib.baseboard_fab2(sch_1):page75_i17@chpset_lib.skx_ext_b(chips)!SKX_EXT_B_BGA1-IC,TBD!!!F105!VSS(519)!!!!
S!GND!U2D1!CA18!@baseboard_fab2_lib.baseboard_fab2(sch_1):page75_i17@chpset_lib.skx_ext_b(chips)!SKX_EXT_B_BGA1-IC,TBD!!!F105!VSS(520)!!!!
S!GND!U2D1!CA14!@baseboard_fab2_lib.baseboard_fab2(sch_1):page75_i17@chpset_lib.skx_ext_b(chips)!SKX_EXT_B_BGA1-IC,TBD!!!F105!VSS(521)!!!!
S!GND!U2D1!CA10!@baseboard_fab2_lib.baseboard_fab2(sch_1):page75_i17@chpset_lib.skx_ext_b(chips)!SKX_EXT_B_BGA1-IC,TBD!!!F105!VSS(522)!!!!
S!GND!U2D1!CA8!@baseboard_fab2_lib.baseboard_fab2(sch_1):page75_i17@chpset_lib.skx_ext_b(chips)!SKX_EXT_B_BGA1-IC,TBD!!!F105!VSS(523)!!!!
S!GND!U2D1!CA6!@baseboard_fab2_lib.baseboard_fab2(sch_1):page75_i17@chpset_lib.skx_ext_b(chips)!SKX_EXT_B_BGA1-IC,TBD!!!F105!VSS(524)!!!!
S!GND!U2D1!CA2!@baseboard_fab2_lib.baseboard_fab2(sch_1):page75_i17@chpset_lib.skx_ext_b(chips)!SKX_EXT_B_BGA1-IC,TBD!!!F105!VSS(525)!!!!
S!GND!U2D1!BY71!@baseboard_fab2_lib.baseboard_fab2(sch_1):page75_i17@chpset_lib.skx_ext_b(chips)!SKX_EXT_B_BGA1-IC,TBD!!!F105!VSS(526)!!!!
S!GND!U2D1!BY69!@baseboard_fab2_lib.baseboard_fab2(sch_1):page75_i17@chpset_lib.skx_ext_b(chips)!SKX_EXT_B_BGA1-IC,TBD!!!F105!VSS(527)!!!!
S!GND!U2D1!BY67!@baseboard_fab2_lib.baseboard_fab2(sch_1):page75_i17@chpset_lib.skx_ext_b(chips)!SKX_EXT_B_BGA1-IC,TBD!!!F105!VSS(528)!!!!
S!GND!U2D1!BY65!@baseboard_fab2_lib.baseboard_fab2(sch_1):page75_i17@chpset_lib.skx_ext_b(chips)!SKX_EXT_B_BGA1-IC,TBD!!!F105!VSS(529)!!!!
S!GND!U2D1!BY63!@baseboard_fab2_lib.baseboard_fab2(sch_1):page75_i17@chpset_lib.skx_ext_b(chips)!SKX_EXT_B_BGA1-IC,TBD!!!F105!VSS(530)!!!!
S!GND!U2D1!BY23!@baseboard_fab2_lib.baseboard_fab2(sch_1):page75_i17@chpset_lib.skx_ext_b(chips)!SKX_EXT_B_BGA1-IC,TBD!!!F105!VSS(531)!!!!
S!GND!U2D1!BY13!@baseboard_fab2_lib.baseboard_fab2(sch_1):page75_i17@chpset_lib.skx_ext_b(chips)!SKX_EXT_B_BGA1-IC,TBD!!!F105!VSS(532)!!!!
S!GND!U2D1!BY11!@baseboard_fab2_lib.baseboard_fab2(sch_1):page75_i17@chpset_lib.skx_ext_b(chips)!SKX_EXT_B_BGA1-IC,TBD!!!F105!VSS(533)!!!!
S!GND!U2D1!BW82!@baseboard_fab2_lib.baseboard_fab2(sch_1):page75_i17@chpset_lib.skx_ext_b(chips)!SKX_EXT_B_BGA1-IC,TBD!!!F105!VSS(534)!!!!
S!GND!U2D1!BW80!@baseboard_fab2_lib.baseboard_fab2(sch_1):page75_i17@chpset_lib.skx_ext_b(chips)!SKX_EXT_B_BGA1-IC,TBD!!!F105!VSS(535)!!!!
S!GND!U2D1!BW78!@baseboard_fab2_lib.baseboard_fab2(sch_1):page75_i17@chpset_lib.skx_ext_b(chips)!SKX_EXT_B_BGA1-IC,TBD!!!F105!VSS(536)!!!!
S!GND!U2D1!BW76!@baseboard_fab2_lib.baseboard_fab2(sch_1):page75_i17@chpset_lib.skx_ext_b(chips)!SKX_EXT_B_BGA1-IC,TBD!!!F105!VSS(537)!!!!
S!GND!U2D1!BW74!@baseboard_fab2_lib.baseboard_fab2(sch_1):page75_i17@chpset_lib.skx_ext_b(chips)!SKX_EXT_B_BGA1-IC,TBD!!!F105!VSS(538)!!!!
S!GND!U2D1!BW72!@baseboard_fab2_lib.baseboard_fab2(sch_1):page75_i17@chpset_lib.skx_ext_b(chips)!SKX_EXT_B_BGA1-IC,TBD!!!F105!VSS(539)!!!!
S!GND!U2D1!BW26!@baseboard_fab2_lib.baseboard_fab2(sch_1):page75_i17@chpset_lib.skx_ext_b(chips)!SKX_EXT_B_BGA1-IC,TBD!!!F105!VSS(540)!!!!
S!GND!U2D1!BW18!@baseboard_fab2_lib.baseboard_fab2(sch_1):page75_i17@chpset_lib.skx_ext_b(chips)!SKX_EXT_B_BGA1-IC,TBD!!!F105!VSS(541)!!!!
S!GND!U2D1!BW16!@baseboard_fab2_lib.baseboard_fab2(sch_1):page75_i17@chpset_lib.skx_ext_b(chips)!SKX_EXT_B_BGA1-IC,TBD!!!F105!VSS(542)!!!!
S!GND!U2D1!BW14!@baseboard_fab2_lib.baseboard_fab2(sch_1):page75_i17@chpset_lib.skx_ext_b(chips)!SKX_EXT_B_BGA1-IC,TBD!!!F105!VSS(543)!!!!
S!GND!U2D1!BW12!@baseboard_fab2_lib.baseboard_fab2(sch_1):page75_i17@chpset_lib.skx_ext_b(chips)!SKX_EXT_B_BGA1-IC,TBD!!!F105!VSS(544)!!!!
S!GND!U2D1!P55!@baseboard_fab2_lib.baseboard_fab2(sch_1):page75_i17@chpset_lib.skx_ext_b(chips)!SKX_EXT_B_BGA1-IC,TBD!!!F105!VSS(545)!!!!
S!GND!U2D1!BW6!@baseboard_fab2_lib.baseboard_fab2(sch_1):page75_i17@chpset_lib.skx_ext_b(chips)!SKX_EXT_B_BGA1-IC,TBD!!!F105!VSS(546)!!!!
S!GND!U2D1!BV25!@baseboard_fab2_lib.baseboard_fab2(sch_1):page75_i17@chpset_lib.skx_ext_b(chips)!SKX_EXT_B_BGA1-IC,TBD!!!F105!VSS(547)!!!!
S!GND!U2D1!BV17!@baseboard_fab2_lib.baseboard_fab2(sch_1):page75_i17@chpset_lib.skx_ext_b(chips)!SKX_EXT_B_BGA1-IC,TBD!!!F105!VSS(548)!!!!
S!GND!U2D1!BU10!@baseboard_fab2_lib.baseboard_fab2(sch_1):page75_i17@chpset_lib.skx_ext_b(chips)!SKX_EXT_B_BGA1-IC,TBD!!!F105!VSS(549)!!!!
S!GND!U2D1!BV5!@baseboard_fab2_lib.baseboard_fab2(sch_1):page75_i17@chpset_lib.skx_ext_b(chips)!SKX_EXT_B_BGA1-IC,TBD!!!F105!VSS(550)!!!!
S!GND!U2D1!BU8!@baseboard_fab2_lib.baseboard_fab2(sch_1):page75_i17@chpset_lib.skx_ext_b(chips)!SKX_EXT_B_BGA1-IC,TBD!!!F105!VSS(551)!!!!
S!GND!U2D1!BT25!@baseboard_fab2_lib.baseboard_fab2(sch_1):page75_i17@chpset_lib.skx_ext_b(chips)!SKX_EXT_B_BGA1-IC,TBD!!!F105!VSS(552)!!!!
S!GND!U2D1!BT23!@baseboard_fab2_lib.baseboard_fab2(sch_1):page75_i17@chpset_lib.skx_ext_b(chips)!SKX_EXT_B_BGA1-IC,TBD!!!F105!VSS(553)!!!!
S!GND!U2D1!BT21!@baseboard_fab2_lib.baseboard_fab2(sch_1):page75_i17@chpset_lib.skx_ext_b(chips)!SKX_EXT_B_BGA1-IC,TBD!!!F105!VSS(554)!!!!
S!GND!U2D1!BT5!@baseboard_fab2_lib.baseboard_fab2(sch_1):page75_i17@chpset_lib.skx_ext_b(chips)!SKX_EXT_B_BGA1-IC,TBD!!!F105!VSS(555)!!!!
S!GND!U2D1!BT3!@baseboard_fab2_lib.baseboard_fab2(sch_1):page75_i17@chpset_lib.skx_ext_b(chips)!SKX_EXT_B_BGA1-IC,TBD!!!F105!VSS(556)!!!!
S!GND!U2D1!BR82!@baseboard_fab2_lib.baseboard_fab2(sch_1):page75_i17@chpset_lib.skx_ext_b(chips)!SKX_EXT_B_BGA1-IC,TBD!!!F105!VSS(557)!!!!
S!GND!U2D1!BR80!@baseboard_fab2_lib.baseboard_fab2(sch_1):page75_i17@chpset_lib.skx_ext_b(chips)!SKX_EXT_B_BGA1-IC,TBD!!!F105!VSS(558)!!!!
S!GND!U2D1!BR78!@baseboard_fab2_lib.baseboard_fab2(sch_1):page75_i17@chpset_lib.skx_ext_b(chips)!SKX_EXT_B_BGA1-IC,TBD!!!F105!VSS(559)!!!!
S!GND!U2D1!BR76!@baseboard_fab2_lib.baseboard_fab2(sch_1):page75_i17@chpset_lib.skx_ext_b(chips)!SKX_EXT_B_BGA1-IC,TBD!!!F105!VSS(560)!!!!
S!GND!U2D1!BR74!@baseboard_fab2_lib.baseboard_fab2(sch_1):page75_i17@chpset_lib.skx_ext_b(chips)!SKX_EXT_B_BGA1-IC,TBD!!!F105!VSS(561)!!!!
S!GND!U2D1!BR72!@baseboard_fab2_lib.baseboard_fab2(sch_1):page75_i17@chpset_lib.skx_ext_b(chips)!SKX_EXT_B_BGA1-IC,TBD!!!F105!VSS(562)!!!!
S!GND!U2D1!BR70!@baseboard_fab2_lib.baseboard_fab2(sch_1):page75_i17@chpset_lib.skx_ext_b(chips)!SKX_EXT_B_BGA1-IC,TBD!!!F105!VSS(563)!!!!
S!GND!U2D1!BR68!@baseboard_fab2_lib.baseboard_fab2(sch_1):page75_i17@chpset_lib.skx_ext_b(chips)!SKX_EXT_B_BGA1-IC,TBD!!!F105!VSS(564)!!!!
S!GND!U2D1!BR66!@baseboard_fab2_lib.baseboard_fab2(sch_1):page75_i17@chpset_lib.skx_ext_b(chips)!SKX_EXT_B_BGA1-IC,TBD!!!F105!VSS(565)!!!!
S!GND!U2D1!BR64!@baseboard_fab2_lib.baseboard_fab2(sch_1):page75_i17@chpset_lib.skx_ext_b(chips)!SKX_EXT_B_BGA1-IC,TBD!!!F105!VSS(566)!!!!
S!GND!U2D1!P57!@baseboard_fab2_lib.baseboard_fab2(sch_1):page75_i17@chpset_lib.skx_ext_b(chips)!SKX_EXT_B_BGA1-IC,TBD!!!F105!VSS(567)!!!!
S!GND!U2D1!BR16!@baseboard_fab2_lib.baseboard_fab2(sch_1):page75_i17@chpset_lib.skx_ext_b(chips)!SKX_EXT_B_BGA1-IC,TBD!!!F105!VSS(568)!!!!
S!GND!U2D1!BR10!@baseboard_fab2_lib.baseboard_fab2(sch_1):page75_i17@chpset_lib.skx_ext_b(chips)!SKX_EXT_B_BGA1-IC,TBD!!!F105!VSS(569)!!!!
S!GND!U2D1!BR6!@baseboard_fab2_lib.baseboard_fab2(sch_1):page75_i17@chpset_lib.skx_ext_b(chips)!SKX_EXT_B_BGA1-IC,TBD!!!F105!VSS(570)!!!!
S!GND!U2D1!BP27!@baseboard_fab2_lib.baseboard_fab2(sch_1):page75_i17@chpset_lib.skx_ext_b(chips)!SKX_EXT_B_BGA1-IC,TBD!!!F105!VSS(571)!!!!
S!GND!U2D1!BP3!@baseboard_fab2_lib.baseboard_fab2(sch_1):page75_i17@chpset_lib.skx_ext_b(chips)!SKX_EXT_B_BGA1-IC,TBD!!!F105!VSS(572)!!!!
S!GND!U2D1!BN26!@baseboard_fab2_lib.baseboard_fab2(sch_1):page75_i17@chpset_lib.skx_ext_b(chips)!SKX_EXT_B_BGA1-IC,TBD!!!F105!VSS(573)!!!!
S!GND!U2D1!BN20!@baseboard_fab2_lib.baseboard_fab2(sch_1):page75_i17@chpset_lib.skx_ext_b(chips)!SKX_EXT_B_BGA1-IC,TBD!!!F105!VSS(574)!!!!
S!GND!U2D1!BN10!@baseboard_fab2_lib.baseboard_fab2(sch_1):page75_i17@chpset_lib.skx_ext_b(chips)!SKX_EXT_B_BGA1-IC,TBD!!!F105!VSS(575)!!!!
S!GND!U2D1!BN6!@baseboard_fab2_lib.baseboard_fab2(sch_1):page75_i17@chpset_lib.skx_ext_b(chips)!SKX_EXT_B_BGA1-IC,TBD!!!F105!VSS(576)!!!!
S!GND!U2D1!BM25!@baseboard_fab2_lib.baseboard_fab2(sch_1):page75_i17@chpset_lib.skx_ext_b(chips)!SKX_EXT_B_BGA1-IC,TBD!!!F105!VSS(577)!!!!
S!GND!U2D1!P59!@baseboard_fab2_lib.baseboard_fab2(sch_1):page75_i17@chpset_lib.skx_ext_b(chips)!SKX_EXT_B_BGA1-IC,TBD!!!F105!VSS(578)!!!!
S!GND!U2D1!BM15!@baseboard_fab2_lib.baseboard_fab2(sch_1):page75_i17@chpset_lib.skx_ext_b(chips)!SKX_EXT_B_BGA1-IC,TBD!!!F105!VSS(579)!!!!
S!GND!U2D1!BM13!@baseboard_fab2_lib.baseboard_fab2(sch_1):page75_i17@chpset_lib.skx_ext_b(chips)!SKX_EXT_B_BGA1-IC,TBD!!!F105!VSS(580)!!!!
S!GND!U2D1!BM9!@baseboard_fab2_lib.baseboard_fab2(sch_1):page75_i17@chpset_lib.skx_ext_b(chips)!SKX_EXT_B_BGA1-IC,TBD!!!F105!VSS(581)!!!!
S!GND!U2D1!BL82!@baseboard_fab2_lib.baseboard_fab2(sch_1):page75_i17@chpset_lib.skx_ext_b(chips)!SKX_EXT_B_BGA1-IC,TBD!!!F105!VSS(582)!!!!
S!GND!U2D1!BL80!@baseboard_fab2_lib.baseboard_fab2(sch_1):page75_i17@chpset_lib.skx_ext_b(chips)!SKX_EXT_B_BGA1-IC,TBD!!!F105!VSS(583)!!!!
S!GND!U2D1!BL78!@baseboard_fab2_lib.baseboard_fab2(sch_1):page75_i17@chpset_lib.skx_ext_b(chips)!SKX_EXT_B_BGA1-IC,TBD!!!F105!VSS(584)!!!!
S!GND!U2D1!BL76!@baseboard_fab2_lib.baseboard_fab2(sch_1):page75_i17@chpset_lib.skx_ext_b(chips)!SKX_EXT_B_BGA1-IC,TBD!!!F105!VSS(585)!!!!
S!GND!U2D1!BL74!@baseboard_fab2_lib.baseboard_fab2(sch_1):page75_i17@chpset_lib.skx_ext_b(chips)!SKX_EXT_B_BGA1-IC,TBD!!!F105!VSS(586)!!!!
S!GND!U2D1!BL72!@baseboard_fab2_lib.baseboard_fab2(sch_1):page75_i17@chpset_lib.skx_ext_b(chips)!SKX_EXT_B_BGA1-IC,TBD!!!F105!VSS(587)!!!!
S!GND!U2D1!DC38!@baseboard_fab2_lib.baseboard_fab2(sch_1):page75_i19@chpset_lib.skx_ext_b(chips)!SKX_EXT_B_BGA1-IC,TBD!!!F103!VSS(268)!!!!
S!GND!U2D1!DC32!@baseboard_fab2_lib.baseboard_fab2(sch_1):page75_i19@chpset_lib.skx_ext_b(chips)!SKX_EXT_B_BGA1-IC,TBD!!!F103!VSS(269)!!!!
S!GND!U2D1!DC26!@baseboard_fab2_lib.baseboard_fab2(sch_1):page75_i19@chpset_lib.skx_ext_b(chips)!SKX_EXT_B_BGA1-IC,TBD!!!F103!VSS(270)!!!!
S!GND!U2D1!DC24!@baseboard_fab2_lib.baseboard_fab2(sch_1):page75_i19@chpset_lib.skx_ext_b(chips)!SKX_EXT_B_BGA1-IC,TBD!!!F103!VSS(271)!!!!
S!GND!U2D1!DC14!@baseboard_fab2_lib.baseboard_fab2(sch_1):page75_i19@chpset_lib.skx_ext_b(chips)!SKX_EXT_B_BGA1-IC,TBD!!!F103!VSS(272)!!!!
S!GND!U2D1!DB85!@baseboard_fab2_lib.baseboard_fab2(sch_1):page75_i19@chpset_lib.skx_ext_b(chips)!SKX_EXT_B_BGA1-IC,TBD!!!F103!VSS(273)!!!!
S!GND!U2D1!DB83!@baseboard_fab2_lib.baseboard_fab2(sch_1):page75_i19@chpset_lib.skx_ext_b(chips)!SKX_EXT_B_BGA1-IC,TBD!!!F103!VSS(274)!!!!
S!GND!U2D1!DB77!@baseboard_fab2_lib.baseboard_fab2(sch_1):page75_i19@chpset_lib.skx_ext_b(chips)!SKX_EXT_B_BGA1-IC,TBD!!!F103!VSS(275)!!!!
S!GND!U2D1!DB73!@baseboard_fab2_lib.baseboard_fab2(sch_1):page75_i19@chpset_lib.skx_ext_b(chips)!SKX_EXT_B_BGA1-IC,TBD!!!F103!VSS(276)!!!!
S!GND!U2D1!DB49!@baseboard_fab2_lib.baseboard_fab2(sch_1):page75_i19@chpset_lib.skx_ext_b(chips)!SKX_EXT_B_BGA1-IC,TBD!!!F103!VSS(277)!!!!
S!GND!U2D1!DB47!@baseboard_fab2_lib.baseboard_fab2(sch_1):page75_i19@chpset_lib.skx_ext_b(chips)!SKX_EXT_B_BGA1-IC,TBD!!!F103!VSS(278)!!!!
S!GND!U2D1!DB41!@baseboard_fab2_lib.baseboard_fab2(sch_1):page75_i19@chpset_lib.skx_ext_b(chips)!SKX_EXT_B_BGA1-IC,TBD!!!F103!VSS(279)!!!!
S!GND!U2D1!DB39!@baseboard_fab2_lib.baseboard_fab2(sch_1):page75_i19@chpset_lib.skx_ext_b(chips)!SKX_EXT_B_BGA1-IC,TBD!!!F103!VSS(280)!!!!
S!GND!U2D1!DB25!@baseboard_fab2_lib.baseboard_fab2(sch_1):page75_i19@chpset_lib.skx_ext_b(chips)!SKX_EXT_B_BGA1-IC,TBD!!!F103!VSS(281)!!!!
S!GND!U2D1!DB23!@baseboard_fab2_lib.baseboard_fab2(sch_1):page75_i19@chpset_lib.skx_ext_b(chips)!SKX_EXT_B_BGA1-IC,TBD!!!F103!VSS(282)!!!!
S!GND!U2D1!DB17!@baseboard_fab2_lib.baseboard_fab2(sch_1):page75_i19@chpset_lib.skx_ext_b(chips)!SKX_EXT_B_BGA1-IC,TBD!!!F103!VSS(283)!!!!
S!GND!U2D1!DB13!@baseboard_fab2_lib.baseboard_fab2(sch_1):page75_i19@chpset_lib.skx_ext_b(chips)!SKX_EXT_B_BGA1-IC,TBD!!!F103!VSS(284)!!!!
S!GND!U2D1!DB3!@baseboard_fab2_lib.baseboard_fab2(sch_1):page75_i19@chpset_lib.skx_ext_b(chips)!SKX_EXT_B_BGA1-IC,TBD!!!F103!VSS(285)!!!!
S!GND!U2D1!DA80!@baseboard_fab2_lib.baseboard_fab2(sch_1):page75_i19@chpset_lib.skx_ext_b(chips)!SKX_EXT_B_BGA1-IC,TBD!!!F103!VSS(286)!!!!
S!GND!U2D1!DA78!@baseboard_fab2_lib.baseboard_fab2(sch_1):page75_i19@chpset_lib.skx_ext_b(chips)!SKX_EXT_B_BGA1-IC,TBD!!!F103!VSS(287)!!!!
S!GND!U2D1!DA76!@baseboard_fab2_lib.baseboard_fab2(sch_1):page75_i19@chpset_lib.skx_ext_b(chips)!SKX_EXT_B_BGA1-IC,TBD!!!F103!VSS(288)!!!!
S!GND!U2D1!DA74!@baseboard_fab2_lib.baseboard_fab2(sch_1):page75_i19@chpset_lib.skx_ext_b(chips)!SKX_EXT_B_BGA1-IC,TBD!!!F103!VSS(289)!!!!
S!GND!U2D1!DA70!@baseboard_fab2_lib.baseboard_fab2(sch_1):page75_i19@chpset_lib.skx_ext_b(chips)!SKX_EXT_B_BGA1-IC,TBD!!!F103!VSS(290)!!!!
S!GND!U2D1!DA64!@baseboard_fab2_lib.baseboard_fab2(sch_1):page75_i19@chpset_lib.skx_ext_b(chips)!SKX_EXT_B_BGA1-IC,TBD!!!F103!VSS(291)!!!!
S!GND!U2D1!DA50!@baseboard_fab2_lib.baseboard_fab2(sch_1):page75_i19@chpset_lib.skx_ext_b(chips)!SKX_EXT_B_BGA1-IC,TBD!!!F103!VSS(292)!!!!
S!GND!U2D1!DA48!@baseboard_fab2_lib.baseboard_fab2(sch_1):page75_i19@chpset_lib.skx_ext_b(chips)!SKX_EXT_B_BGA1-IC,TBD!!!F103!VSS(293)!!!!
S!GND!U2D1!DA46!@baseboard_fab2_lib.baseboard_fab2(sch_1):page75_i18@chpset_lib.skx_ext_b(chips)!SKX_EXT_B_BGA1-IC,TBD!!!F104!VSS(294)!!!!
S!GND!U2D1!DA44!@baseboard_fab2_lib.baseboard_fab2(sch_1):page75_i18@chpset_lib.skx_ext_b(chips)!SKX_EXT_B_BGA1-IC,TBD!!!F104!VSS(295)!!!!
S!GND!U2D1!DA38!@baseboard_fab2_lib.baseboard_fab2(sch_1):page75_i18@chpset_lib.skx_ext_b(chips)!SKX_EXT_B_BGA1-IC,TBD!!!F104!VSS(296)!!!!
S!GND!U2D1!DA36!@baseboard_fab2_lib.baseboard_fab2(sch_1):page75_i18@chpset_lib.skx_ext_b(chips)!SKX_EXT_B_BGA1-IC,TBD!!!F104!VSS(297)!!!!
S!GND!U2D1!DA34!@baseboard_fab2_lib.baseboard_fab2(sch_1):page75_i18@chpset_lib.skx_ext_b(chips)!SKX_EXT_B_BGA1-IC,TBD!!!F104!VSS(298)!!!!
S!GND!U2D1!DA32!@baseboard_fab2_lib.baseboard_fab2(sch_1):page75_i18@chpset_lib.skx_ext_b(chips)!SKX_EXT_B_BGA1-IC,TBD!!!F104!VSS(299)!!!!
S!GND!U2D1!DA30!@baseboard_fab2_lib.baseboard_fab2(sch_1):page75_i18@chpset_lib.skx_ext_b(chips)!SKX_EXT_B_BGA1-IC,TBD!!!F104!VSS(300)!!!!
S!GND!U2D1!DA28!@baseboard_fab2_lib.baseboard_fab2(sch_1):page75_i18@chpset_lib.skx_ext_b(chips)!SKX_EXT_B_BGA1-IC,TBD!!!F104!VSS(301)!!!!
S!GND!U2D1!DA26!@baseboard_fab2_lib.baseboard_fab2(sch_1):page75_i18@chpset_lib.skx_ext_b(chips)!SKX_EXT_B_BGA1-IC,TBD!!!F104!VSS(302)!!!!
S!GND!U2D1!DA18!@baseboard_fab2_lib.baseboard_fab2(sch_1):page75_i18@chpset_lib.skx_ext_b(chips)!SKX_EXT_B_BGA1-IC,TBD!!!F104!VSS(303)!!!!
S!GND!U2D1!H53!@baseboard_fab2_lib.baseboard_fab2(sch_1):page75_i18@chpset_lib.skx_ext_b(chips)!SKX_EXT_B_BGA1-IC,TBD!!!F104!VSS(304)!!!!
S!GND!U2D1!DA6!@baseboard_fab2_lib.baseboard_fab2(sch_1):page75_i18@chpset_lib.skx_ext_b(chips)!SKX_EXT_B_BGA1-IC,TBD!!!F104!VSS(305)!!!!
S!GND!U2D1!CY85!@baseboard_fab2_lib.baseboard_fab2(sch_1):page75_i18@chpset_lib.skx_ext_b(chips)!SKX_EXT_B_BGA1-IC,TBD!!!F104!VSS(306)!!!!
S!GND!U2D1!CY83!@baseboard_fab2_lib.baseboard_fab2(sch_1):page75_i18@chpset_lib.skx_ext_b(chips)!SKX_EXT_B_BGA1-IC,TBD!!!F104!VSS(307)!!!!
S!GND!U2D1!CY77!@baseboard_fab2_lib.baseboard_fab2(sch_1):page75_i18@chpset_lib.skx_ext_b(chips)!SKX_EXT_B_BGA1-IC,TBD!!!F104!VSS(308)!!!!
S!GND!U2D1!CY75!@baseboard_fab2_lib.baseboard_fab2(sch_1):page75_i18@chpset_lib.skx_ext_b(chips)!SKX_EXT_B_BGA1-IC,TBD!!!F104!VSS(309)!!!!
S!GND!U2D1!CY69!@baseboard_fab2_lib.baseboard_fab2(sch_1):page75_i18@chpset_lib.skx_ext_b(chips)!SKX_EXT_B_BGA1-IC,TBD!!!F104!VSS(310)!!!!
S!GND!U2D1!CY65!@baseboard_fab2_lib.baseboard_fab2(sch_1):page75_i18@chpset_lib.skx_ext_b(chips)!SKX_EXT_B_BGA1-IC,TBD!!!F104!VSS(311)!!!!
S!GND!U2D1!CY61!@baseboard_fab2_lib.baseboard_fab2(sch_1):page75_i18@chpset_lib.skx_ext_b(chips)!SKX_EXT_B_BGA1-IC,TBD!!!F104!VSS(312)!!!!
S!GND!U2D1!CY59!@baseboard_fab2_lib.baseboard_fab2(sch_1):page75_i18@chpset_lib.skx_ext_b(chips)!SKX_EXT_B_BGA1-IC,TBD!!!F104!VSS(313)!!!!
S!GND!U2D1!CY51!@baseboard_fab2_lib.baseboard_fab2(sch_1):page75_i18@chpset_lib.skx_ext_b(chips)!SKX_EXT_B_BGA1-IC,TBD!!!F104!VSS(314)!!!!
S!GND!U2D1!CY45!@baseboard_fab2_lib.baseboard_fab2(sch_1):page75_i18@chpset_lib.skx_ext_b(chips)!SKX_EXT_B_BGA1-IC,TBD!!!F104!VSS(315)!!!!
S!GND!U2D1!CY41!@baseboard_fab2_lib.baseboard_fab2(sch_1):page75_i18@chpset_lib.skx_ext_b(chips)!SKX_EXT_B_BGA1-IC,TBD!!!F104!VSS(316)!!!!
S!GND!U2D1!CY21!@baseboard_fab2_lib.baseboard_fab2(sch_1):page75_i18@chpset_lib.skx_ext_b(chips)!SKX_EXT_B_BGA1-IC,TBD!!!F104!VSS(317)!!!!
S!GND!U2D1!CY15!@baseboard_fab2_lib.baseboard_fab2(sch_1):page75_i18@chpset_lib.skx_ext_b(chips)!SKX_EXT_B_BGA1-IC,TBD!!!F104!VSS(318)!!!!
S!GND!U2D1!CY13!@baseboard_fab2_lib.baseboard_fab2(sch_1):page75_i18@chpset_lib.skx_ext_b(chips)!SKX_EXT_B_BGA1-IC,TBD!!!F104!VSS(319)!!!!
S!GND!U2D1!CY9!@baseboard_fab2_lib.baseboard_fab2(sch_1):page75_i18@chpset_lib.skx_ext_b(chips)!SKX_EXT_B_BGA1-IC,TBD!!!F104!VSS(320)!!!!
S!GND!U2D1!CY1!@baseboard_fab2_lib.baseboard_fab2(sch_1):page75_i18@chpset_lib.skx_ext_b(chips)!SKX_EXT_B_BGA1-IC,TBD!!!F104!VSS(321)!!!!
S!GND!U2D1!CW82!@baseboard_fab2_lib.baseboard_fab2(sch_1):page75_i18@chpset_lib.skx_ext_b(chips)!SKX_EXT_B_BGA1-IC,TBD!!!F104!VSS(322)!!!!
S!GND!U2D1!CW78!@baseboard_fab2_lib.baseboard_fab2(sch_1):page75_i18@chpset_lib.skx_ext_b(chips)!SKX_EXT_B_BGA1-IC,TBD!!!F104!VSS(323)!!!!
S!GND!U2D1!CW74!@baseboard_fab2_lib.baseboard_fab2(sch_1):page75_i18@chpset_lib.skx_ext_b(chips)!SKX_EXT_B_BGA1-IC,TBD!!!F104!VSS(324)!!!!
S!GND!U2D1!CW68!@baseboard_fab2_lib.baseboard_fab2(sch_1):page75_i18@chpset_lib.skx_ext_b(chips)!SKX_EXT_B_BGA1-IC,TBD!!!F104!VSS(325)!!!!
S!GND!U2D1!CW66!@baseboard_fab2_lib.baseboard_fab2(sch_1):page75_i18@chpset_lib.skx_ext_b(chips)!SKX_EXT_B_BGA1-IC,TBD!!!F104!VSS(326)!!!!
S!GND!U2D1!CW64!@baseboard_fab2_lib.baseboard_fab2(sch_1):page75_i18@chpset_lib.skx_ext_b(chips)!SKX_EXT_B_BGA1-IC,TBD!!!F104!VSS(327)!!!!
S!GND!U2D1!CW54!@baseboard_fab2_lib.baseboard_fab2(sch_1):page75_i18@chpset_lib.skx_ext_b(chips)!SKX_EXT_B_BGA1-IC,TBD!!!F104!VSS(328)!!!!
S!GND!U2D1!CW52!@baseboard_fab2_lib.baseboard_fab2(sch_1):page75_i18@chpset_lib.skx_ext_b(chips)!SKX_EXT_B_BGA1-IC,TBD!!!F104!VSS(329)!!!!
S!GND!U2D1!CW42!@baseboard_fab2_lib.baseboard_fab2(sch_1):page75_i18@chpset_lib.skx_ext_b(chips)!SKX_EXT_B_BGA1-IC,TBD!!!F104!VSS(330)!!!!
S!GND!U2D1!CW40!@baseboard_fab2_lib.baseboard_fab2(sch_1):page75_i18@chpset_lib.skx_ext_b(chips)!SKX_EXT_B_BGA1-IC,TBD!!!F104!VSS(331)!!!!
S!GND!U2D1!CW38!@baseboard_fab2_lib.baseboard_fab2(sch_1):page75_i18@chpset_lib.skx_ext_b(chips)!SKX_EXT_B_BGA1-IC,TBD!!!F104!VSS(332)!!!!
S!GND!U2D1!CW32!@baseboard_fab2_lib.baseboard_fab2(sch_1):page75_i18@chpset_lib.skx_ext_b(chips)!SKX_EXT_B_BGA1-IC,TBD!!!F104!VSS(333)!!!!
S!GND!U2D1!CW26!@baseboard_fab2_lib.baseboard_fab2(sch_1):page75_i18@chpset_lib.skx_ext_b(chips)!SKX_EXT_B_BGA1-IC,TBD!!!F104!VSS(334)!!!!
S!GND!U2D1!CW12!@baseboard_fab2_lib.baseboard_fab2(sch_1):page75_i18@chpset_lib.skx_ext_b(chips)!SKX_EXT_B_BGA1-IC,TBD!!!F104!VSS(335)!!!!
S!GND!U2D1!CV83!@baseboard_fab2_lib.baseboard_fab2(sch_1):page75_i18@chpset_lib.skx_ext_b(chips)!SKX_EXT_B_BGA1-IC,TBD!!!F104!VSS(336)!!!!
S!GND!U2D1!CV81!@baseboard_fab2_lib.baseboard_fab2(sch_1):page75_i18@chpset_lib.skx_ext_b(chips)!SKX_EXT_B_BGA1-IC,TBD!!!F104!VSS(337)!!!!
S!GND!U2D1!CV79!@baseboard_fab2_lib.baseboard_fab2(sch_1):page75_i18@chpset_lib.skx_ext_b(chips)!SKX_EXT_B_BGA1-IC,TBD!!!F104!VSS(338)!!!!
S!GND!U2D1!CV73!@baseboard_fab2_lib.baseboard_fab2(sch_1):page75_i18@chpset_lib.skx_ext_b(chips)!SKX_EXT_B_BGA1-IC,TBD!!!F104!VSS(339)!!!!
S!GND!U2D1!CV67!@baseboard_fab2_lib.baseboard_fab2(sch_1):page75_i18@chpset_lib.skx_ext_b(chips)!SKX_EXT_B_BGA1-IC,TBD!!!F104!VSS(340)!!!!
S!GND!U2D1!CV63!@baseboard_fab2_lib.baseboard_fab2(sch_1):page75_i18@chpset_lib.skx_ext_b(chips)!SKX_EXT_B_BGA1-IC,TBD!!!F104!VSS(341)!!!!
S!GND!U2D1!CV55!@baseboard_fab2_lib.baseboard_fab2(sch_1):page75_i18@chpset_lib.skx_ext_b(chips)!SKX_EXT_B_BGA1-IC,TBD!!!F104!VSS(342)!!!!
S!GND!U2D1!CV53!@baseboard_fab2_lib.baseboard_fab2(sch_1):page75_i18@chpset_lib.skx_ext_b(chips)!SKX_EXT_B_BGA1-IC,TBD!!!F104!VSS(343)!!!!
S!GND!U2D1!CV41!@baseboard_fab2_lib.baseboard_fab2(sch_1):page75_i18@chpset_lib.skx_ext_b(chips)!SKX_EXT_B_BGA1-IC,TBD!!!F104!VSS(344)!!!!
S!GND!U2D1!CV39!@baseboard_fab2_lib.baseboard_fab2(sch_1):page75_i18@chpset_lib.skx_ext_b(chips)!SKX_EXT_B_BGA1-IC,TBD!!!F104!VSS(345)!!!!
S!GND!U2D1!CV37!@baseboard_fab2_lib.baseboard_fab2(sch_1):page75_i18@chpset_lib.skx_ext_b(chips)!SKX_EXT_B_BGA1-IC,TBD!!!F104!VSS(346)!!!!
S!GND!U2D1!CV33!@baseboard_fab2_lib.baseboard_fab2(sch_1):page75_i18@chpset_lib.skx_ext_b(chips)!SKX_EXT_B_BGA1-IC,TBD!!!F104!VSS(347)!!!!
S!GND!U2D1!CV31!@baseboard_fab2_lib.baseboard_fab2(sch_1):page75_i18@chpset_lib.skx_ext_b(chips)!SKX_EXT_B_BGA1-IC,TBD!!!F104!VSS(348)!!!!
S!GND!U2D1!CV27!@baseboard_fab2_lib.baseboard_fab2(sch_1):page75_i18@chpset_lib.skx_ext_b(chips)!SKX_EXT_B_BGA1-IC,TBD!!!F104!VSS(349)!!!!
S!GND!U2D1!CV25!@baseboard_fab2_lib.baseboard_fab2(sch_1):page75_i18@chpset_lib.skx_ext_b(chips)!SKX_EXT_B_BGA1-IC,TBD!!!F104!VSS(350)!!!!
S!GND!U2D1!CV17!@baseboard_fab2_lib.baseboard_fab2(sch_1):page75_i18@chpset_lib.skx_ext_b(chips)!SKX_EXT_B_BGA1-IC,TBD!!!F104!VSS(351)!!!!
S!GND!U2D1!H55!@baseboard_fab2_lib.baseboard_fab2(sch_1):page75_i18@chpset_lib.skx_ext_b(chips)!SKX_EXT_B_BGA1-IC,TBD!!!F104!VSS(352)!!!!
S!GND!U2D1!CV1!@baseboard_fab2_lib.baseboard_fab2(sch_1):page75_i18@chpset_lib.skx_ext_b(chips)!SKX_EXT_B_BGA1-IC,TBD!!!F104!VSS(353)!!!!
S!GND!U2D1!CU86!@baseboard_fab2_lib.baseboard_fab2(sch_1):page75_i18@chpset_lib.skx_ext_b(chips)!SKX_EXT_B_BGA1-IC,TBD!!!F104!VSS(354)!!!!
S!GND!U2D1!CU82!@baseboard_fab2_lib.baseboard_fab2(sch_1):page75_i18@chpset_lib.skx_ext_b(chips)!SKX_EXT_B_BGA1-IC,TBD!!!F104!VSS(355)!!!!
S!GND!U2D1!CU80!@baseboard_fab2_lib.baseboard_fab2(sch_1):page75_i18@chpset_lib.skx_ext_b(chips)!SKX_EXT_B_BGA1-IC,TBD!!!F104!VSS(356)!!!!
S!GND!U2D1!CU78!@baseboard_fab2_lib.baseboard_fab2(sch_1):page75_i18@chpset_lib.skx_ext_b(chips)!SKX_EXT_B_BGA1-IC,TBD!!!F104!VSS(357)!!!!
S!GND!U2D1!CU76!@baseboard_fab2_lib.baseboard_fab2(sch_1):page75_i18@chpset_lib.skx_ext_b(chips)!SKX_EXT_B_BGA1-IC,TBD!!!F104!VSS(358)!!!!
S!GND!U2D1!CU68!@baseboard_fab2_lib.baseboard_fab2(sch_1):page75_i18@chpset_lib.skx_ext_b(chips)!SKX_EXT_B_BGA1-IC,TBD!!!F104!VSS(359)!!!!
S!GND!U2D1!CU62!@baseboard_fab2_lib.baseboard_fab2(sch_1):page75_i18@chpset_lib.skx_ext_b(chips)!SKX_EXT_B_BGA1-IC,TBD!!!F104!VSS(360)!!!!
S!GND!U2D1!CU56!@baseboard_fab2_lib.baseboard_fab2(sch_1):page75_i18@chpset_lib.skx_ext_b(chips)!SKX_EXT_B_BGA1-IC,TBD!!!F104!VSS(361)!!!!
S!GND!U2D1!CU36!@baseboard_fab2_lib.baseboard_fab2(sch_1):page75_i18@chpset_lib.skx_ext_b(chips)!SKX_EXT_B_BGA1-IC,TBD!!!F104!VSS(362)!!!!
S!GND!U2D1!CU34!@baseboard_fab2_lib.baseboard_fab2(sch_1):page75_i18@chpset_lib.skx_ext_b(chips)!SKX_EXT_B_BGA1-IC,TBD!!!F104!VSS(363)!!!!
S!GND!U2D1!CU30!@baseboard_fab2_lib.baseboard_fab2(sch_1):page75_i18@chpset_lib.skx_ext_b(chips)!SKX_EXT_B_BGA1-IC,TBD!!!F104!VSS(364)!!!!
S!GND!U2D1!CU28!@baseboard_fab2_lib.baseboard_fab2(sch_1):page75_i18@chpset_lib.skx_ext_b(chips)!SKX_EXT_B_BGA1-IC,TBD!!!F104!VSS(365)!!!!
S!GND!U2D1!CU22!@baseboard_fab2_lib.baseboard_fab2(sch_1):page75_i18@chpset_lib.skx_ext_b(chips)!SKX_EXT_B_BGA1-IC,TBD!!!F104!VSS(366)!!!!
S!GND!U2D1!CU4!@baseboard_fab2_lib.baseboard_fab2(sch_1):page75_i18@chpset_lib.skx_ext_b(chips)!SKX_EXT_B_BGA1-IC,TBD!!!F104!VSS(367)!!!!
S!GND!U2D1!CT85!@baseboard_fab2_lib.baseboard_fab2(sch_1):page75_i18@chpset_lib.skx_ext_b(chips)!SKX_EXT_B_BGA1-IC,TBD!!!F104!VSS(368)!!!!
S!GND!U2D1!CT83!@baseboard_fab2_lib.baseboard_fab2(sch_1):page75_i18@chpset_lib.skx_ext_b(chips)!SKX_EXT_B_BGA1-IC,TBD!!!F104!VSS(369)!!!!
S!GND!U2D1!CT79!@baseboard_fab2_lib.baseboard_fab2(sch_1):page75_i18@chpset_lib.skx_ext_b(chips)!SKX_EXT_B_BGA1-IC,TBD!!!F104!VSS(370)!!!!
S!GND!U2D1!CT73!@baseboard_fab2_lib.baseboard_fab2(sch_1):page75_i18@chpset_lib.skx_ext_b(chips)!SKX_EXT_B_BGA1-IC,TBD!!!F104!VSS(371)!!!!
S!GND!U2D1!CT57!@baseboard_fab2_lib.baseboard_fab2(sch_1):page75_i18@chpset_lib.skx_ext_b(chips)!SKX_EXT_B_BGA1-IC,TBD!!!F104!VSS(372)!!!!
S!GND!U2D1!CT35!@baseboard_fab2_lib.baseboard_fab2(sch_1):page75_i18@chpset_lib.skx_ext_b(chips)!SKX_EXT_B_BGA1-IC,TBD!!!F104!VSS(373)!!!!
S!GND!U2D1!CT33!@baseboard_fab2_lib.baseboard_fab2(sch_1):page75_i18@chpset_lib.skx_ext_b(chips)!SKX_EXT_B_BGA1-IC,TBD!!!F104!VSS(374)!!!!
S!GND!U2D1!CT29!@baseboard_fab2_lib.baseboard_fab2(sch_1):page75_i18@chpset_lib.skx_ext_b(chips)!SKX_EXT_B_BGA1-IC,TBD!!!F104!VSS(375)!!!!
S!GND!U2D1!CT27!@baseboard_fab2_lib.baseboard_fab2(sch_1):page75_i18@chpset_lib.skx_ext_b(chips)!SKX_EXT_B_BGA1-IC,TBD!!!F104!VSS(376)!!!!
S!GND!U2D1!CT19!@baseboard_fab2_lib.baseboard_fab2(sch_1):page75_i18@chpset_lib.skx_ext_b(chips)!SKX_EXT_B_BGA1-IC,TBD!!!F104!VSS(377)!!!!
S!GND!U2D1!CT13!@baseboard_fab2_lib.baseboard_fab2(sch_1):page75_i18@chpset_lib.skx_ext_b(chips)!SKX_EXT_B_BGA1-IC,TBD!!!F104!VSS(378)!!!!
S!GND!U2D1!H57!@baseboard_fab2_lib.baseboard_fab2(sch_1):page75_i18@chpset_lib.skx_ext_b(chips)!SKX_EXT_B_BGA1-IC,TBD!!!F104!VSS(379)!!!!
S!GND!U2D1!CR86!@baseboard_fab2_lib.baseboard_fab2(sch_1):page75_i18@chpset_lib.skx_ext_b(chips)!SKX_EXT_B_BGA1-IC,TBD!!!F104!VSS(380)!!!!
S!GND!U2D1!CR78!@baseboard_fab2_lib.baseboard_fab2(sch_1):page75_i18@chpset_lib.skx_ext_b(chips)!SKX_EXT_B_BGA1-IC,TBD!!!F104!VSS(381)!!!!
S!GND!U2D1!CR68!@baseboard_fab2_lib.baseboard_fab2(sch_1):page75_i18@chpset_lib.skx_ext_b(chips)!SKX_EXT_B_BGA1-IC,TBD!!!F104!VSS(382)!!!!
S!GND!U2D1!CR66!@baseboard_fab2_lib.baseboard_fab2(sch_1):page75_i18@chpset_lib.skx_ext_b(chips)!SKX_EXT_B_BGA1-IC,TBD!!!F104!VSS(383)!!!!
S!GND!U2D1!CR64!@baseboard_fab2_lib.baseboard_fab2(sch_1):page75_i18@chpset_lib.skx_ext_b(chips)!SKX_EXT_B_BGA1-IC,TBD!!!F104!VSS(384)!!!!
S!GND!U2D1!CR62!@baseboard_fab2_lib.baseboard_fab2(sch_1):page75_i18@chpset_lib.skx_ext_b(chips)!SKX_EXT_B_BGA1-IC,TBD!!!F104!VSS(385)!!!!
S!GND!U2D1!CR58!@baseboard_fab2_lib.baseboard_fab2(sch_1):page75_i18@chpset_lib.skx_ext_b(chips)!SKX_EXT_B_BGA1-IC,TBD!!!F104!VSS(386)!!!!
S!GND!U2D1!CR32!@baseboard_fab2_lib.baseboard_fab2(sch_1):page75_i18@chpset_lib.skx_ext_b(chips)!SKX_EXT_B_BGA1-IC,TBD!!!F104!VSS(387)!!!!
S!GND!U2D1!CR24!@baseboard_fab2_lib.baseboard_fab2(sch_1):page75_i18@chpset_lib.skx_ext_b(chips)!SKX_EXT_B_BGA1-IC,TBD!!!F104!VSS(388)!!!!
S!GND!U2D1!CR22!@baseboard_fab2_lib.baseboard_fab2(sch_1):page75_i18@chpset_lib.skx_ext_b(chips)!SKX_EXT_B_BGA1-IC,TBD!!!F104!VSS(389)!!!!
S!GND!U2D1!CR10!@baseboard_fab2_lib.baseboard_fab2(sch_1):page75_i18@chpset_lib.skx_ext_b(chips)!SKX_EXT_B_BGA1-IC,TBD!!!F104!VSS(390)!!!!
S!GND!U2D1!CR6!@baseboard_fab2_lib.baseboard_fab2(sch_1):page75_i18@chpset_lib.skx_ext_b(chips)!SKX_EXT_B_BGA1-IC,TBD!!!F104!VSS(391)!!!!
S!GND!U2D1!CP83!@baseboard_fab2_lib.baseboard_fab2(sch_1):page75_i18@chpset_lib.skx_ext_b(chips)!SKX_EXT_B_BGA1-IC,TBD!!!F104!VSS(392)!!!!
S!GND!U2D1!CP81!@baseboard_fab2_lib.baseboard_fab2(sch_1):page75_i18@chpset_lib.skx_ext_b(chips)!SKX_EXT_B_BGA1-IC,TBD!!!F104!VSS(393)!!!!
S!GND!U2D1!CP75!@baseboard_fab2_lib.baseboard_fab2(sch_1):page75_i18@chpset_lib.skx_ext_b(chips)!SKX_EXT_B_BGA1-IC,TBD!!!F104!VSS(394)!!!!
S!GND!U2D1!CP73!@baseboard_fab2_lib.baseboard_fab2(sch_1):page75_i18@chpset_lib.skx_ext_b(chips)!SKX_EXT_B_BGA1-IC,TBD!!!F104!VSS(395)!!!!
S!GND!U2D1!CP69!@baseboard_fab2_lib.baseboard_fab2(sch_1):page75_i18@chpset_lib.skx_ext_b(chips)!SKX_EXT_B_BGA1-IC,TBD!!!F104!VSS(396)!!!!
S!GND!U2D1!CP59!@baseboard_fab2_lib.baseboard_fab2(sch_1):page75_i18@chpset_lib.skx_ext_b(chips)!SKX_EXT_B_BGA1-IC,TBD!!!F104!VSS(397)!!!!
S!GND!U2D1!CP25!@baseboard_fab2_lib.baseboard_fab2(sch_1):page75_i18@chpset_lib.skx_ext_b(chips)!SKX_EXT_B_BGA1-IC,TBD!!!F104!VSS(398)!!!!
S!GND!U2D1!H59!@baseboard_fab2_lib.baseboard_fab2(sch_1):page75_i18@chpset_lib.skx_ext_b(chips)!SKX_EXT_B_BGA1-IC,TBD!!!F104!VSS(399)!!!!
S!GND!U2D1!CP1!@baseboard_fab2_lib.baseboard_fab2(sch_1):page75_i18@chpset_lib.skx_ext_b(chips)!SKX_EXT_B_BGA1-IC,TBD!!!F104!VSS(400)!!!!
S!GND!U2D1!CN78!@baseboard_fab2_lib.baseboard_fab2(sch_1):page75_i18@chpset_lib.skx_ext_b(chips)!SKX_EXT_B_BGA1-IC,TBD!!!F104!VSS(401)!!!!
S!GND!U2D1!CN68!@baseboard_fab2_lib.baseboard_fab2(sch_1):page75_i18@chpset_lib.skx_ext_b(chips)!SKX_EXT_B_BGA1-IC,TBD!!!F104!VSS(402)!!!!
S!GND!U2D1!CN62!@baseboard_fab2_lib.baseboard_fab2(sch_1):page75_i18@chpset_lib.skx_ext_b(chips)!SKX_EXT_B_BGA1-IC,TBD!!!F104!VSS(403)!!!!
S!GND!U2D1!CN60!@baseboard_fab2_lib.baseboard_fab2(sch_1):page75_i18@chpset_lib.skx_ext_b(chips)!SKX_EXT_B_BGA1-IC,TBD!!!F104!VSS(404)!!!!
S!GND!U2D1!CN32!@baseboard_fab2_lib.baseboard_fab2(sch_1):page75_i18@chpset_lib.skx_ext_b(chips)!SKX_EXT_B_BGA1-IC,TBD!!!F104!VSS(405)!!!!
S!GND!U2D1!CN26!@baseboard_fab2_lib.baseboard_fab2(sch_1):page75_i18@chpset_lib.skx_ext_b(chips)!SKX_EXT_B_BGA1-IC,TBD!!!F104!VSS(406)!!!!
S!GND!U2D1!H61!@baseboard_fab2_lib.baseboard_fab2(sch_1):page75_i18@chpset_lib.skx_ext_b(chips)!SKX_EXT_B_BGA1-IC,TBD!!!F104!VSS(407)!!!!
S!GND!U2D1!CN12!@baseboard_fab2_lib.baseboard_fab2(sch_1):page75_i18@chpset_lib.skx_ext_b(chips)!SKX_EXT_B_BGA1-IC,TBD!!!F104!VSS(408)!!!!
S!GND!U2D1!CN2!@baseboard_fab2_lib.baseboard_fab2(sch_1):page75_i18@chpset_lib.skx_ext_b(chips)!SKX_EXT_B_BGA1-IC,TBD!!!F104!VSS(409)!!!!
S!GND!U2D1!CM85!@baseboard_fab2_lib.baseboard_fab2(sch_1):page75_i18@chpset_lib.skx_ext_b(chips)!SKX_EXT_B_BGA1-IC,TBD!!!F104!VSS(410)!!!!
S!GND!U2D1!CM83!@baseboard_fab2_lib.baseboard_fab2(sch_1):page75_i18@chpset_lib.skx_ext_b(chips)!SKX_EXT_B_BGA1-IC,TBD!!!F104!VSS(411)!!!!
S!GND!U2D1!CM77!@baseboard_fab2_lib.baseboard_fab2(sch_1):page75_i18@chpset_lib.skx_ext_b(chips)!SKX_EXT_B_BGA1-IC,TBD!!!F104!VSS(412)!!!!
S!GND!U2D1!CM73!@baseboard_fab2_lib.baseboard_fab2(sch_1):page75_i18@chpset_lib.skx_ext_b(chips)!SKX_EXT_B_BGA1-IC,TBD!!!F104!VSS(413)!!!!
S!GND!U2D1!CM67!@baseboard_fab2_lib.baseboard_fab2(sch_1):page75_i18@chpset_lib.skx_ext_b(chips)!SKX_EXT_B_BGA1-IC,TBD!!!F104!VSS(414)!!!!
S!GND!U2D1!CM63!@baseboard_fab2_lib.baseboard_fab2(sch_1):page75_i18@chpset_lib.skx_ext_b(chips)!SKX_EXT_B_BGA1-IC,TBD!!!F104!VSS(415)!!!!
S!GND!U2D1!CM61!@baseboard_fab2_lib.baseboard_fab2(sch_1):page75_i18@chpset_lib.skx_ext_b(chips)!SKX_EXT_B_BGA1-IC,TBD!!!F104!VSS(416)!!!!
S!GND!U2D1!CM31!@baseboard_fab2_lib.baseboard_fab2(sch_1):page75_i18@chpset_lib.skx_ext_b(chips)!SKX_EXT_B_BGA1-IC,TBD!!!F104!VSS(417)!!!!
S!GND!U2D1!CM5!@baseboard_fab2_lib.baseboard_fab2(sch_1):page75_i18@chpset_lib.skx_ext_b(chips)!SKX_EXT_B_BGA1-IC,TBD!!!F104!VSS(418)!!!!
S!GND!U2D1!CM29!@baseboard_fab2_lib.baseboard_fab2(sch_1):page75_i18@chpset_lib.skx_ext_b(chips)!SKX_EXT_B_BGA1-IC,TBD!!!F104!VSS(419)!!!!
S!GND!U2D1!CM19!@baseboard_fab2_lib.baseboard_fab2(sch_1):page75_i18@chpset_lib.skx_ext_b(chips)!SKX_EXT_B_BGA1-IC,TBD!!!F104!VSS(420)!!!!
S!GND!U2D1!CL80!@baseboard_fab2_lib.baseboard_fab2(sch_1):page75_i18@chpset_lib.skx_ext_b(chips)!SKX_EXT_B_BGA1-IC,TBD!!!F104!VSS(421)!!!!
S!GND!U2D1!CL78!@baseboard_fab2_lib.baseboard_fab2(sch_1):page75_i18@chpset_lib.skx_ext_b(chips)!SKX_EXT_B_BGA1-IC,TBD!!!F104!VSS(422)!!!!
S!GND!U2D1!CL76!@baseboard_fab2_lib.baseboard_fab2(sch_1):page75_i18@chpset_lib.skx_ext_b(chips)!SKX_EXT_B_BGA1-IC,TBD!!!F104!VSS(423)!!!!
S!GND!U2D1!CL74!@baseboard_fab2_lib.baseboard_fab2(sch_1):page75_i18@chpset_lib.skx_ext_b(chips)!SKX_EXT_B_BGA1-IC,TBD!!!F104!VSS(424)!!!!
S!GND!U2D1!CL66!@baseboard_fab2_lib.baseboard_fab2(sch_1):page75_i18@chpset_lib.skx_ext_b(chips)!SKX_EXT_B_BGA1-IC,TBD!!!F104!VSS(425)!!!!
S!GND!U2D1!CL64!@baseboard_fab2_lib.baseboard_fab2(sch_1):page75_i18@chpset_lib.skx_ext_b(chips)!SKX_EXT_B_BGA1-IC,TBD!!!F104!VSS(426)!!!!
S!GND!U2D1!CL62!@baseboard_fab2_lib.baseboard_fab2(sch_1):page75_i18@chpset_lib.skx_ext_b(chips)!SKX_EXT_B_BGA1-IC,TBD!!!F104!VSS(427)!!!!
S!GND!U2D1!DR72!@baseboard_fab2_lib.baseboard_fab2(sch_1):page75_i20@chpset_lib.skx_ext_b(chips)!SKX_EXT_B_BGA1-IC,TBD!!!F102!VSS(108)!!!!
S!GND!U2D1!DR70!@baseboard_fab2_lib.baseboard_fab2(sch_1):page75_i20@chpset_lib.skx_ext_b(chips)!SKX_EXT_B_BGA1-IC,TBD!!!F102!VSS(109)!!!!
S!GND!U2D1!DR68!@baseboard_fab2_lib.baseboard_fab2(sch_1):page75_i20@chpset_lib.skx_ext_b(chips)!SKX_EXT_B_BGA1-IC,TBD!!!F102!VSS(110)!!!!
S!GND!U2D1!DR66!@baseboard_fab2_lib.baseboard_fab2(sch_1):page75_i20@chpset_lib.skx_ext_b(chips)!SKX_EXT_B_BGA1-IC,TBD!!!F102!VSS(111)!!!!
S!GND!U2D1!DR42!@baseboard_fab2_lib.baseboard_fab2(sch_1):page75_i20@chpset_lib.skx_ext_b(chips)!SKX_EXT_B_BGA1-IC,TBD!!!F102!VSS(112)!!!!
S!GND!U2D1!DR40!@baseboard_fab2_lib.baseboard_fab2(sch_1):page75_i20@chpset_lib.skx_ext_b(chips)!SKX_EXT_B_BGA1-IC,TBD!!!F102!VSS(113)!!!!
S!GND!U2D1!DR38!@baseboard_fab2_lib.baseboard_fab2(sch_1):page75_i20@chpset_lib.skx_ext_b(chips)!SKX_EXT_B_BGA1-IC,TBD!!!F102!VSS(114)!!!!
S!GND!U2D1!DR36!@baseboard_fab2_lib.baseboard_fab2(sch_1):page75_i20@chpset_lib.skx_ext_b(chips)!SKX_EXT_B_BGA1-IC,TBD!!!F102!VSS(115)!!!!
S!GND!U2D1!DR34!@baseboard_fab2_lib.baseboard_fab2(sch_1):page75_i20@chpset_lib.skx_ext_b(chips)!SKX_EXT_B_BGA1-IC,TBD!!!F102!VSS(116)!!!!
S!GND!U2D1!DR32!@baseboard_fab2_lib.baseboard_fab2(sch_1):page75_i20@chpset_lib.skx_ext_b(chips)!SKX_EXT_B_BGA1-IC,TBD!!!F102!VSS(117)!!!!
S!GND!U2D1!DR30!@baseboard_fab2_lib.baseboard_fab2(sch_1):page75_i20@chpset_lib.skx_ext_b(chips)!SKX_EXT_B_BGA1-IC,TBD!!!F102!VSS(118)!!!!
S!GND!U2D1!DR28!@baseboard_fab2_lib.baseboard_fab2(sch_1):page75_i20@chpset_lib.skx_ext_b(chips)!SKX_EXT_B_BGA1-IC,TBD!!!F102!VSS(119)!!!!
S!GND!U2D1!DR26!@baseboard_fab2_lib.baseboard_fab2(sch_1):page75_i20@chpset_lib.skx_ext_b(chips)!SKX_EXT_B_BGA1-IC,TBD!!!F102!VSS(120)!!!!
S!GND!U2D1!DR24!@baseboard_fab2_lib.baseboard_fab2(sch_1):page75_i20@chpset_lib.skx_ext_b(chips)!SKX_EXT_B_BGA1-IC,TBD!!!F102!VSS(121)!!!!
S!GND!U2D1!DR22!@baseboard_fab2_lib.baseboard_fab2(sch_1):page75_i20@chpset_lib.skx_ext_b(chips)!SKX_EXT_B_BGA1-IC,TBD!!!F102!VSS(122)!!!!
S!GND!U2D1!DR20!@baseboard_fab2_lib.baseboard_fab2(sch_1):page75_i20@chpset_lib.skx_ext_b(chips)!SKX_EXT_B_BGA1-IC,TBD!!!F102!VSS(123)!!!!
S!GND!U2D1!CL22!@baseboard_fab2_lib.baseboard_fab2(sch_1):page75_i20@chpset_lib.skx_ext_b(chips)!SKX_EXT_B_BGA1-IC,TBD!!!F102!VSS(124)!!!!
S!GND!U2D1!CA20!@baseboard_fab2_lib.baseboard_fab2(sch_1):page75_i20@chpset_lib.skx_ext_b(chips)!SKX_EXT_B_BGA1-IC,TBD!!!F102!VSS(125)!!!!
S!GND!U2D1!DR6!@baseboard_fab2_lib.baseboard_fab2(sch_1):page75_i20@chpset_lib.skx_ext_b(chips)!SKX_EXT_B_BGA1-IC,TBD!!!F102!VSS(126)!!!!
S!GND!U2D1!BR26!@baseboard_fab2_lib.baseboard_fab2(sch_1):page75_i20@chpset_lib.skx_ext_b(chips)!SKX_EXT_B_BGA1-IC,TBD!!!F102!VSS(127)!!!!
S!GND!U2D1!DP83!@baseboard_fab2_lib.baseboard_fab2(sch_1):page75_i20@chpset_lib.skx_ext_b(chips)!SKX_EXT_B_BGA1-IC,TBD!!!F102!VSS(128)!!!!
S!GND!U2D1!DP81!@baseboard_fab2_lib.baseboard_fab2(sch_1):page75_i20@chpset_lib.skx_ext_b(chips)!SKX_EXT_B_BGA1-IC,TBD!!!F102!VSS(129)!!!!
S!GND!U2D1!DP71!@baseboard_fab2_lib.baseboard_fab2(sch_1):page75_i20@chpset_lib.skx_ext_b(chips)!SKX_EXT_B_BGA1-IC,TBD!!!F102!VSS(130)!!!!
S!GND!U2D1!DP69!@baseboard_fab2_lib.baseboard_fab2(sch_1):page75_i20@chpset_lib.skx_ext_b(chips)!SKX_EXT_B_BGA1-IC,TBD!!!F102!VSS(131)!!!!
S!GND!U2D1!DP67!@baseboard_fab2_lib.baseboard_fab2(sch_1):page75_i20@chpset_lib.skx_ext_b(chips)!SKX_EXT_B_BGA1-IC,TBD!!!F102!VSS(132)!!!!
S!GND!U2D1!DN78!@baseboard_fab2_lib.baseboard_fab2(sch_1):page75_i20@chpset_lib.skx_ext_b(chips)!SKX_EXT_B_BGA1-IC,TBD!!!F102!VSS(133)!!!!
S!GND!U2D1!DN72!@baseboard_fab2_lib.baseboard_fab2(sch_1):page75_i19@chpset_lib.skx_ext_b(chips)!SKX_EXT_B_BGA1-IC,TBD!!!F103!VSS(134)!!!!
S!GND!U2D1!DN68!@baseboard_fab2_lib.baseboard_fab2(sch_1):page75_i19@chpset_lib.skx_ext_b(chips)!SKX_EXT_B_BGA1-IC,TBD!!!F103!VSS(135)!!!!
S!GND!U2D1!DN38!@baseboard_fab2_lib.baseboard_fab2(sch_1):page75_i19@chpset_lib.skx_ext_b(chips)!SKX_EXT_B_BGA1-IC,TBD!!!F103!VSS(136)!!!!
S!GND!U2D1!DN32!@baseboard_fab2_lib.baseboard_fab2(sch_1):page75_i19@chpset_lib.skx_ext_b(chips)!SKX_EXT_B_BGA1-IC,TBD!!!F103!VSS(137)!!!!
S!GND!U2D1!DN26!@baseboard_fab2_lib.baseboard_fab2(sch_1):page75_i19@chpset_lib.skx_ext_b(chips)!SKX_EXT_B_BGA1-IC,TBD!!!F103!VSS(138)!!!!
S!GND!U2D1!DN22!@baseboard_fab2_lib.baseboard_fab2(sch_1):page75_i19@chpset_lib.skx_ext_b(chips)!SKX_EXT_B_BGA1-IC,TBD!!!F103!VSS(139)!!!!
S!GND!U2D1!DN12!@baseboard_fab2_lib.baseboard_fab2(sch_1):page75_i19@chpset_lib.skx_ext_b(chips)!SKX_EXT_B_BGA1-IC,TBD!!!F103!VSS(140)!!!!
S!GND!U2D1!BH17!@baseboard_fab2_lib.baseboard_fab2(sch_1):page75_i19@chpset_lib.skx_ext_b(chips)!SKX_EXT_B_BGA1-IC,TBD!!!F103!VSS(141)!!!!
S!GND!U2D1!DN2!@baseboard_fab2_lib.baseboard_fab2(sch_1):page75_i19@chpset_lib.skx_ext_b(chips)!SKX_EXT_B_BGA1-IC,TBD!!!F103!VSS(142)!!!!
S!GND!U2D1!DM83!@baseboard_fab2_lib.baseboard_fab2(sch_1):page75_i19@chpset_lib.skx_ext_b(chips)!SKX_EXT_B_BGA1-IC,TBD!!!F103!VSS(143)!!!!
S!GND!U2D1!DM77!@baseboard_fab2_lib.baseboard_fab2(sch_1):page75_i19@chpset_lib.skx_ext_b(chips)!SKX_EXT_B_BGA1-IC,TBD!!!F103!VSS(144)!!!!
S!GND!U2D1!DM73!@baseboard_fab2_lib.baseboard_fab2(sch_1):page75_i19@chpset_lib.skx_ext_b(chips)!SKX_EXT_B_BGA1-IC,TBD!!!F103!VSS(145)!!!!
S!GND!U2D1!DM65!@baseboard_fab2_lib.baseboard_fab2(sch_1):page75_i19@chpset_lib.skx_ext_b(chips)!SKX_EXT_B_BGA1-IC,TBD!!!F103!VSS(146)!!!!
S!GND!U2D1!DM39!@baseboard_fab2_lib.baseboard_fab2(sch_1):page75_i19@chpset_lib.skx_ext_b(chips)!SKX_EXT_B_BGA1-IC,TBD!!!F103!VSS(147)!!!!
S!GND!U2D1!DM37!@baseboard_fab2_lib.baseboard_fab2(sch_1):page75_i19@chpset_lib.skx_ext_b(chips)!SKX_EXT_B_BGA1-IC,TBD!!!F103!VSS(148)!!!!
S!GND!U2D1!DM33!@baseboard_fab2_lib.baseboard_fab2(sch_1):page75_i19@chpset_lib.skx_ext_b(chips)!SKX_EXT_B_BGA1-IC,TBD!!!F103!VSS(149)!!!!
S!GND!U2D1!DM31!@baseboard_fab2_lib.baseboard_fab2(sch_1):page75_i19@chpset_lib.skx_ext_b(chips)!SKX_EXT_B_BGA1-IC,TBD!!!F103!VSS(150)!!!!
S!GND!U2D1!DM27!@baseboard_fab2_lib.baseboard_fab2(sch_1):page75_i19@chpset_lib.skx_ext_b(chips)!SKX_EXT_B_BGA1-IC,TBD!!!F103!VSS(151)!!!!
S!GND!U2D1!DM25!@baseboard_fab2_lib.baseboard_fab2(sch_1):page75_i19@chpset_lib.skx_ext_b(chips)!SKX_EXT_B_BGA1-IC,TBD!!!F103!VSS(152)!!!!
S!GND!U2D1!H45!@baseboard_fab2_lib.baseboard_fab2(sch_1):page75_i19@chpset_lib.skx_ext_b(chips)!SKX_EXT_B_BGA1-IC,TBD!!!F103!VSS(153)!!!!
S!GND!U2D1!DM15!@baseboard_fab2_lib.baseboard_fab2(sch_1):page75_i19@chpset_lib.skx_ext_b(chips)!SKX_EXT_B_BGA1-IC,TBD!!!F103!VSS(154)!!!!
S!GND!U2D1!DL80!@baseboard_fab2_lib.baseboard_fab2(sch_1):page75_i19@chpset_lib.skx_ext_b(chips)!SKX_EXT_B_BGA1-IC,TBD!!!F103!VSS(155)!!!!
S!GND!U2D1!DL78!@baseboard_fab2_lib.baseboard_fab2(sch_1):page75_i19@chpset_lib.skx_ext_b(chips)!SKX_EXT_B_BGA1-IC,TBD!!!F103!VSS(156)!!!!
S!GND!U2D1!DL76!@baseboard_fab2_lib.baseboard_fab2(sch_1):page75_i19@chpset_lib.skx_ext_b(chips)!SKX_EXT_B_BGA1-IC,TBD!!!F103!VSS(157)!!!!
S!GND!U2D1!DL74!@baseboard_fab2_lib.baseboard_fab2(sch_1):page75_i19@chpset_lib.skx_ext_b(chips)!SKX_EXT_B_BGA1-IC,TBD!!!F103!VSS(158)!!!!
S!GND!U2D1!DL70!@baseboard_fab2_lib.baseboard_fab2(sch_1):page75_i19@chpset_lib.skx_ext_b(chips)!SKX_EXT_B_BGA1-IC,TBD!!!F103!VSS(159)!!!!
S!GND!U2D1!DL68!@baseboard_fab2_lib.baseboard_fab2(sch_1):page75_i19@chpset_lib.skx_ext_b(chips)!SKX_EXT_B_BGA1-IC,TBD!!!F103!VSS(160)!!!!
S!GND!U2D1!DL40!@baseboard_fab2_lib.baseboard_fab2(sch_1):page75_i19@chpset_lib.skx_ext_b(chips)!SKX_EXT_B_BGA1-IC,TBD!!!F103!VSS(161)!!!!
S!GND!U2D1!DL36!@baseboard_fab2_lib.baseboard_fab2(sch_1):page75_i19@chpset_lib.skx_ext_b(chips)!SKX_EXT_B_BGA1-IC,TBD!!!F103!VSS(162)!!!!
S!GND!U2D1!DL34!@baseboard_fab2_lib.baseboard_fab2(sch_1):page75_i19@chpset_lib.skx_ext_b(chips)!SKX_EXT_B_BGA1-IC,TBD!!!F103!VSS(163)!!!!
S!GND!U2D1!DL30!@baseboard_fab2_lib.baseboard_fab2(sch_1):page75_i19@chpset_lib.skx_ext_b(chips)!SKX_EXT_B_BGA1-IC,TBD!!!F103!VSS(164)!!!!
S!GND!U2D1!DL28!@baseboard_fab2_lib.baseboard_fab2(sch_1):page75_i19@chpset_lib.skx_ext_b(chips)!SKX_EXT_B_BGA1-IC,TBD!!!F103!VSS(165)!!!!
S!GND!U2D1!DL24!@baseboard_fab2_lib.baseboard_fab2(sch_1):page75_i19@chpset_lib.skx_ext_b(chips)!SKX_EXT_B_BGA1-IC,TBD!!!F103!VSS(166)!!!!
S!GND!U2D1!DL22!@baseboard_fab2_lib.baseboard_fab2(sch_1):page75_i19@chpset_lib.skx_ext_b(chips)!SKX_EXT_B_BGA1-IC,TBD!!!F103!VSS(167)!!!!
S!GND!U2D1!DL4!@baseboard_fab2_lib.baseboard_fab2(sch_1):page75_i19@chpset_lib.skx_ext_b(chips)!SKX_EXT_B_BGA1-IC,TBD!!!F103!VSS(168)!!!!
S!GND!U2D1!DL18!@baseboard_fab2_lib.baseboard_fab2(sch_1):page75_i19@chpset_lib.skx_ext_b(chips)!SKX_EXT_B_BGA1-IC,TBD!!!F103!VSS(169)!!!!
S!GND!U2D1!DL16!@baseboard_fab2_lib.baseboard_fab2(sch_1):page75_i19@chpset_lib.skx_ext_b(chips)!SKX_EXT_B_BGA1-IC,TBD!!!F103!VSS(170)!!!!
S!GND!U2D1!DK85!@baseboard_fab2_lib.baseboard_fab2(sch_1):page75_i19@chpset_lib.skx_ext_b(chips)!SKX_EXT_B_BGA1-IC,TBD!!!F103!VSS(171)!!!!
S!GND!U2D1!DK83!@baseboard_fab2_lib.baseboard_fab2(sch_1):page75_i19@chpset_lib.skx_ext_b(chips)!SKX_EXT_B_BGA1-IC,TBD!!!F103!VSS(172)!!!!
S!GND!U2D1!DK77!@baseboard_fab2_lib.baseboard_fab2(sch_1):page75_i19@chpset_lib.skx_ext_b(chips)!SKX_EXT_B_BGA1-IC,TBD!!!F103!VSS(173)!!!!
S!GND!U2D1!DK75!@baseboard_fab2_lib.baseboard_fab2(sch_1):page75_i19@chpset_lib.skx_ext_b(chips)!SKX_EXT_B_BGA1-IC,TBD!!!F103!VSS(174)!!!!
S!GND!U2D1!DK73!@baseboard_fab2_lib.baseboard_fab2(sch_1):page75_i19@chpset_lib.skx_ext_b(chips)!SKX_EXT_B_BGA1-IC,TBD!!!F103!VSS(175)!!!!
S!GND!U2D1!DK41!@baseboard_fab2_lib.baseboard_fab2(sch_1):page75_i19@chpset_lib.skx_ext_b(chips)!SKX_EXT_B_BGA1-IC,TBD!!!F103!VSS(176)!!!!
S!GND!U2D1!DK39!@baseboard_fab2_lib.baseboard_fab2(sch_1):page75_i19@chpset_lib.skx_ext_b(chips)!SKX_EXT_B_BGA1-IC,TBD!!!F103!VSS(177)!!!!
S!GND!U2D1!DK35!@baseboard_fab2_lib.baseboard_fab2(sch_1):page75_i19@chpset_lib.skx_ext_b(chips)!SKX_EXT_B_BGA1-IC,TBD!!!F103!VSS(178)!!!!
S!GND!U2D1!DK29!@baseboard_fab2_lib.baseboard_fab2(sch_1):page75_i19@chpset_lib.skx_ext_b(chips)!SKX_EXT_B_BGA1-IC,TBD!!!F103!VSS(179)!!!!
S!GND!U2D1!DK23!@baseboard_fab2_lib.baseboard_fab2(sch_1):page75_i19@chpset_lib.skx_ext_b(chips)!SKX_EXT_B_BGA1-IC,TBD!!!F103!VSS(180)!!!!
S!GND!U2D1!DK7!@baseboard_fab2_lib.baseboard_fab2(sch_1):page75_i19@chpset_lib.skx_ext_b(chips)!SKX_EXT_B_BGA1-IC,TBD!!!F103!VSS(181)!!!!
S!GND!U2D1!DJ84!@baseboard_fab2_lib.baseboard_fab2(sch_1):page75_i19@chpset_lib.skx_ext_b(chips)!SKX_EXT_B_BGA1-IC,TBD!!!F103!VSS(182)!!!!
S!GND!U2D1!DJ82!@baseboard_fab2_lib.baseboard_fab2(sch_1):page75_i19@chpset_lib.skx_ext_b(chips)!SKX_EXT_B_BGA1-IC,TBD!!!F103!VSS(183)!!!!
S!GND!U2D1!DJ78!@baseboard_fab2_lib.baseboard_fab2(sch_1):page75_i19@chpset_lib.skx_ext_b(chips)!SKX_EXT_B_BGA1-IC,TBD!!!F103!VSS(184)!!!!
S!GND!U2D1!DJ74!@baseboard_fab2_lib.baseboard_fab2(sch_1):page75_i19@chpset_lib.skx_ext_b(chips)!SKX_EXT_B_BGA1-IC,TBD!!!F103!VSS(185)!!!!
S!GND!U2D1!DJ68!@baseboard_fab2_lib.baseboard_fab2(sch_1):page75_i19@chpset_lib.skx_ext_b(chips)!SKX_EXT_B_BGA1-IC,TBD!!!F103!VSS(186)!!!!
S!GND!U2D1!DJ42!@baseboard_fab2_lib.baseboard_fab2(sch_1):page75_i19@chpset_lib.skx_ext_b(chips)!SKX_EXT_B_BGA1-IC,TBD!!!F103!VSS(187)!!!!
S!GND!U2D1!DJ38!@baseboard_fab2_lib.baseboard_fab2(sch_1):page75_i19@chpset_lib.skx_ext_b(chips)!SKX_EXT_B_BGA1-IC,TBD!!!F103!VSS(188)!!!!
S!GND!U2D1!DJ22!@baseboard_fab2_lib.baseboard_fab2(sch_1):page75_i19@chpset_lib.skx_ext_b(chips)!SKX_EXT_B_BGA1-IC,TBD!!!F103!VSS(189)!!!!
S!GND!U2D1!H47!@baseboard_fab2_lib.baseboard_fab2(sch_1):page75_i19@chpset_lib.skx_ext_b(chips)!SKX_EXT_B_BGA1-IC,TBD!!!F103!VSS(190)!!!!
S!GND!U2D1!DJ10!@baseboard_fab2_lib.baseboard_fab2(sch_1):page75_i19@chpset_lib.skx_ext_b(chips)!SKX_EXT_B_BGA1-IC,TBD!!!F103!VSS(191)!!!!
S!GND!U2D1!DJ2!@baseboard_fab2_lib.baseboard_fab2(sch_1):page75_i19@chpset_lib.skx_ext_b(chips)!SKX_EXT_B_BGA1-IC,TBD!!!F103!VSS(192)!!!!
S!GND!U2D1!DH83!@baseboard_fab2_lib.baseboard_fab2(sch_1):page75_i19@chpset_lib.skx_ext_b(chips)!SKX_EXT_B_BGA1-IC,TBD!!!F103!VSS(193)!!!!
S!GND!U2D1!DH81!@baseboard_fab2_lib.baseboard_fab2(sch_1):page75_i19@chpset_lib.skx_ext_b(chips)!SKX_EXT_B_BGA1-IC,TBD!!!F103!VSS(194)!!!!
S!GND!U2D1!DH79!@baseboard_fab2_lib.baseboard_fab2(sch_1):page75_i19@chpset_lib.skx_ext_b(chips)!SKX_EXT_B_BGA1-IC,TBD!!!F103!VSS(195)!!!!
S!GND!U2D1!DH73!@baseboard_fab2_lib.baseboard_fab2(sch_1):page75_i19@chpset_lib.skx_ext_b(chips)!SKX_EXT_B_BGA1-IC,TBD!!!F103!VSS(196)!!!!
S!GND!U2D1!DH71!@baseboard_fab2_lib.baseboard_fab2(sch_1):page75_i19@chpset_lib.skx_ext_b(chips)!SKX_EXT_B_BGA1-IC,TBD!!!F103!VSS(197)!!!!
S!GND!U2D1!DH67!@baseboard_fab2_lib.baseboard_fab2(sch_1):page75_i19@chpset_lib.skx_ext_b(chips)!SKX_EXT_B_BGA1-IC,TBD!!!F103!VSS(198)!!!!
S!GND!U2D1!DH41!@baseboard_fab2_lib.baseboard_fab2(sch_1):page75_i19@chpset_lib.skx_ext_b(chips)!SKX_EXT_B_BGA1-IC,TBD!!!F103!VSS(199)!!!!
S!GND!U2D1!DH37!@baseboard_fab2_lib.baseboard_fab2(sch_1):page75_i19@chpset_lib.skx_ext_b(chips)!SKX_EXT_B_BGA1-IC,TBD!!!F103!VSS(200)!!!!
S!GND!U2D1!DH35!@baseboard_fab2_lib.baseboard_fab2(sch_1):page75_i19@chpset_lib.skx_ext_b(chips)!SKX_EXT_B_BGA1-IC,TBD!!!F103!VSS(201)!!!!
S!GND!U2D1!DH33!@baseboard_fab2_lib.baseboard_fab2(sch_1):page75_i19@chpset_lib.skx_ext_b(chips)!SKX_EXT_B_BGA1-IC,TBD!!!F103!VSS(202)!!!!
S!GND!U2D1!DH31!@baseboard_fab2_lib.baseboard_fab2(sch_1):page75_i19@chpset_lib.skx_ext_b(chips)!SKX_EXT_B_BGA1-IC,TBD!!!F103!VSS(203)!!!!
S!GND!U2D1!DH29!@baseboard_fab2_lib.baseboard_fab2(sch_1):page75_i19@chpset_lib.skx_ext_b(chips)!SKX_EXT_B_BGA1-IC,TBD!!!F103!VSS(204)!!!!
S!GND!U2D1!DH27!@baseboard_fab2_lib.baseboard_fab2(sch_1):page75_i19@chpset_lib.skx_ext_b(chips)!SKX_EXT_B_BGA1-IC,TBD!!!F103!VSS(205)!!!!
S!GND!U2D1!DH25!@baseboard_fab2_lib.baseboard_fab2(sch_1):page75_i19@chpset_lib.skx_ext_b(chips)!SKX_EXT_B_BGA1-IC,TBD!!!F103!VSS(206)!!!!
S!GND!U2D1!DH23!@baseboard_fab2_lib.baseboard_fab2(sch_1):page75_i19@chpset_lib.skx_ext_b(chips)!SKX_EXT_B_BGA1-IC,TBD!!!F103!VSS(207)!!!!
S!GND!U2D1!DH15!@baseboard_fab2_lib.baseboard_fab2(sch_1):page75_i19@chpset_lib.skx_ext_b(chips)!SKX_EXT_B_BGA1-IC,TBD!!!F103!VSS(208)!!!!
S!GND!U2D1!DH13!@baseboard_fab2_lib.baseboard_fab2(sch_1):page75_i19@chpset_lib.skx_ext_b(chips)!SKX_EXT_B_BGA1-IC,TBD!!!F103!VSS(209)!!!!
S!GND!U2D1!DG82!@baseboard_fab2_lib.baseboard_fab2(sch_1):page75_i19@chpset_lib.skx_ext_b(chips)!SKX_EXT_B_BGA1-IC,TBD!!!F103!VSS(210)!!!!
S!GND!U2D1!DG80!@baseboard_fab2_lib.baseboard_fab2(sch_1):page75_i19@chpset_lib.skx_ext_b(chips)!SKX_EXT_B_BGA1-IC,TBD!!!F103!VSS(211)!!!!
S!GND!U2D1!DG78!@baseboard_fab2_lib.baseboard_fab2(sch_1):page75_i19@chpset_lib.skx_ext_b(chips)!SKX_EXT_B_BGA1-IC,TBD!!!F103!VSS(212)!!!!
S!GND!U2D1!DG76!@baseboard_fab2_lib.baseboard_fab2(sch_1):page75_i19@chpset_lib.skx_ext_b(chips)!SKX_EXT_B_BGA1-IC,TBD!!!F103!VSS(213)!!!!
S!GND!U2D1!DG68!@baseboard_fab2_lib.baseboard_fab2(sch_1):page75_i19@chpset_lib.skx_ext_b(chips)!SKX_EXT_B_BGA1-IC,TBD!!!F103!VSS(214)!!!!
S!GND!U2D1!DG66!@baseboard_fab2_lib.baseboard_fab2(sch_1):page75_i19@chpset_lib.skx_ext_b(chips)!SKX_EXT_B_BGA1-IC,TBD!!!F103!VSS(215)!!!!
S!GND!U2D1!DG24!@baseboard_fab2_lib.baseboard_fab2(sch_1):page75_i19@chpset_lib.skx_ext_b(chips)!SKX_EXT_B_BGA1-IC,TBD!!!F103!VSS(216)!!!!
S!GND!U2D1!DG16!@baseboard_fab2_lib.baseboard_fab2(sch_1):page75_i19@chpset_lib.skx_ext_b(chips)!SKX_EXT_B_BGA1-IC,TBD!!!F103!VSS(217)!!!!
S!GND!U2D1!DG14!@baseboard_fab2_lib.baseboard_fab2(sch_1):page75_i19@chpset_lib.skx_ext_b(chips)!SKX_EXT_B_BGA1-IC,TBD!!!F103!VSS(218)!!!!
S!GND!U2D1!H49!@baseboard_fab2_lib.baseboard_fab2(sch_1):page75_i19@chpset_lib.skx_ext_b(chips)!SKX_EXT_B_BGA1-IC,TBD!!!F103!VSS(219)!!!!
S!GND!U2D1!DG2!@baseboard_fab2_lib.baseboard_fab2(sch_1):page75_i19@chpset_lib.skx_ext_b(chips)!SKX_EXT_B_BGA1-IC,TBD!!!F103!VSS(220)!!!!
S!GND!U2D1!DF85!@baseboard_fab2_lib.baseboard_fab2(sch_1):page75_i19@chpset_lib.skx_ext_b(chips)!SKX_EXT_B_BGA1-IC,TBD!!!F103!VSS(221)!!!!
S!GND!U2D1!DF83!@baseboard_fab2_lib.baseboard_fab2(sch_1):page75_i19@chpset_lib.skx_ext_b(chips)!SKX_EXT_B_BGA1-IC,TBD!!!F103!VSS(222)!!!!
S!GND!U2D1!DF79!@baseboard_fab2_lib.baseboard_fab2(sch_1):page75_i19@chpset_lib.skx_ext_b(chips)!SKX_EXT_B_BGA1-IC,TBD!!!F103!VSS(223)!!!!
S!GND!U2D1!DF73!@baseboard_fab2_lib.baseboard_fab2(sch_1):page75_i19@chpset_lib.skx_ext_b(chips)!SKX_EXT_B_BGA1-IC,TBD!!!F103!VSS(224)!!!!
S!GND!U2D1!DF69!@baseboard_fab2_lib.baseboard_fab2(sch_1):page75_i19@chpset_lib.skx_ext_b(chips)!SKX_EXT_B_BGA1-IC,TBD!!!F103!VSS(225)!!!!
S!GND!U2D1!DF65!@baseboard_fab2_lib.baseboard_fab2(sch_1):page75_i19@chpset_lib.skx_ext_b(chips)!SKX_EXT_B_BGA1-IC,TBD!!!F103!VSS(226)!!!!
S!GND!U2D1!DF41!@baseboard_fab2_lib.baseboard_fab2(sch_1):page75_i19@chpset_lib.skx_ext_b(chips)!SKX_EXT_B_BGA1-IC,TBD!!!F103!VSS(227)!!!!
S!GND!U2D1!DF39!@baseboard_fab2_lib.baseboard_fab2(sch_1):page75_i19@chpset_lib.skx_ext_b(chips)!SKX_EXT_B_BGA1-IC,TBD!!!F103!VSS(228)!!!!
S!GND!U2D1!DF37!@baseboard_fab2_lib.baseboard_fab2(sch_1):page75_i19@chpset_lib.skx_ext_b(chips)!SKX_EXT_B_BGA1-IC,TBD!!!F103!VSS(229)!!!!
S!GND!U2D1!DF35!@baseboard_fab2_lib.baseboard_fab2(sch_1):page75_i19@chpset_lib.skx_ext_b(chips)!SKX_EXT_B_BGA1-IC,TBD!!!F103!VSS(230)!!!!
S!GND!U2D1!DF29!@baseboard_fab2_lib.baseboard_fab2(sch_1):page75_i19@chpset_lib.skx_ext_b(chips)!SKX_EXT_B_BGA1-IC,TBD!!!F103!VSS(231)!!!!
S!GND!U2D1!DF19!@baseboard_fab2_lib.baseboard_fab2(sch_1):page75_i19@chpset_lib.skx_ext_b(chips)!SKX_EXT_B_BGA1-IC,TBD!!!F103!VSS(232)!!!!
S!GND!U2D1!H51!@baseboard_fab2_lib.baseboard_fab2(sch_1):page75_i19@chpset_lib.skx_ext_b(chips)!SKX_EXT_B_BGA1-IC,TBD!!!F103!VSS(233)!!!!
S!GND!U2D1!DF7!@baseboard_fab2_lib.baseboard_fab2(sch_1):page75_i19@chpset_lib.skx_ext_b(chips)!SKX_EXT_B_BGA1-IC,TBD!!!F103!VSS(234)!!!!
S!GND!U2D1!DF5!@baseboard_fab2_lib.baseboard_fab2(sch_1):page75_i19@chpset_lib.skx_ext_b(chips)!SKX_EXT_B_BGA1-IC,TBD!!!F103!VSS(235)!!!!
S!GND!U2D1!DE78!@baseboard_fab2_lib.baseboard_fab2(sch_1):page75_i19@chpset_lib.skx_ext_b(chips)!SKX_EXT_B_BGA1-IC,TBD!!!F103!VSS(236)!!!!
S!GND!U2D1!DE72!@baseboard_fab2_lib.baseboard_fab2(sch_1):page75_i19@chpset_lib.skx_ext_b(chips)!SKX_EXT_B_BGA1-IC,TBD!!!F103!VSS(237)!!!!
S!GND!U2D1!DE70!@baseboard_fab2_lib.baseboard_fab2(sch_1):page75_i19@chpset_lib.skx_ext_b(chips)!SKX_EXT_B_BGA1-IC,TBD!!!F103!VSS(238)!!!!
S!GND!U2D1!DE64!@baseboard_fab2_lib.baseboard_fab2(sch_1):page75_i19@chpset_lib.skx_ext_b(chips)!SKX_EXT_B_BGA1-IC,TBD!!!F103!VSS(239)!!!!
S!GND!U2D1!DE36!@baseboard_fab2_lib.baseboard_fab2(sch_1):page75_i19@chpset_lib.skx_ext_b(chips)!SKX_EXT_B_BGA1-IC,TBD!!!F103!VSS(240)!!!!
S!GND!U2D1!DE34!@baseboard_fab2_lib.baseboard_fab2(sch_1):page75_i19@chpset_lib.skx_ext_b(chips)!SKX_EXT_B_BGA1-IC,TBD!!!F103!VSS(241)!!!!
S!GND!U2D1!DE30!@baseboard_fab2_lib.baseboard_fab2(sch_1):page75_i19@chpset_lib.skx_ext_b(chips)!SKX_EXT_B_BGA1-IC,TBD!!!F103!VSS(242)!!!!
S!GND!U2D1!DE28!@baseboard_fab2_lib.baseboard_fab2(sch_1):page75_i19@chpset_lib.skx_ext_b(chips)!SKX_EXT_B_BGA1-IC,TBD!!!F103!VSS(243)!!!!
S!GND!U2D1!DE24!@baseboard_fab2_lib.baseboard_fab2(sch_1):page75_i19@chpset_lib.skx_ext_b(chips)!SKX_EXT_B_BGA1-IC,TBD!!!F103!VSS(244)!!!!
S!GND!U2D1!DE20!@baseboard_fab2_lib.baseboard_fab2(sch_1):page75_i19@chpset_lib.skx_ext_b(chips)!SKX_EXT_B_BGA1-IC,TBD!!!F103!VSS(245)!!!!
S!GND!U2D1!DE18!@baseboard_fab2_lib.baseboard_fab2(sch_1):page75_i19@chpset_lib.skx_ext_b(chips)!SKX_EXT_B_BGA1-IC,TBD!!!F103!VSS(246)!!!!
S!GND!U2D1!DE8!@baseboard_fab2_lib.baseboard_fab2(sch_1):page75_i19@chpset_lib.skx_ext_b(chips)!SKX_EXT_B_BGA1-IC,TBD!!!F103!VSS(247)!!!!
S!GND!U2D1!DE6!@baseboard_fab2_lib.baseboard_fab2(sch_1):page75_i19@chpset_lib.skx_ext_b(chips)!SKX_EXT_B_BGA1-IC,TBD!!!F103!VSS(248)!!!!
S!GND!U2D1!DD83!@baseboard_fab2_lib.baseboard_fab2(sch_1):page75_i19@chpset_lib.skx_ext_b(chips)!SKX_EXT_B_BGA1-IC,TBD!!!F103!VSS(249)!!!!
S!GND!U2D1!DD81!@baseboard_fab2_lib.baseboard_fab2(sch_1):page75_i19@chpset_lib.skx_ext_b(chips)!SKX_EXT_B_BGA1-IC,TBD!!!F103!VSS(250)!!!!
S!GND!U2D1!DD75!@baseboard_fab2_lib.baseboard_fab2(sch_1):page75_i19@chpset_lib.skx_ext_b(chips)!SKX_EXT_B_BGA1-IC,TBD!!!F103!VSS(251)!!!!
S!GND!U2D1!DD73!@baseboard_fab2_lib.baseboard_fab2(sch_1):page75_i19@chpset_lib.skx_ext_b(chips)!SKX_EXT_B_BGA1-IC,TBD!!!F103!VSS(252)!!!!
S!GND!U2D1!DD71!@baseboard_fab2_lib.baseboard_fab2(sch_1):page75_i19@chpset_lib.skx_ext_b(chips)!SKX_EXT_B_BGA1-IC,TBD!!!F103!VSS(253)!!!!
S!GND!U2D1!DD37!@baseboard_fab2_lib.baseboard_fab2(sch_1):page75_i19@chpset_lib.skx_ext_b(chips)!SKX_EXT_B_BGA1-IC,TBD!!!F103!VSS(254)!!!!
S!GND!U2D1!DD33!@baseboard_fab2_lib.baseboard_fab2(sch_1):page75_i19@chpset_lib.skx_ext_b(chips)!SKX_EXT_B_BGA1-IC,TBD!!!F103!VSS(255)!!!!
S!GND!U2D1!DD31!@baseboard_fab2_lib.baseboard_fab2(sch_1):page75_i19@chpset_lib.skx_ext_b(chips)!SKX_EXT_B_BGA1-IC,TBD!!!F103!VSS(256)!!!!
S!GND!U2D1!DD27!@baseboard_fab2_lib.baseboard_fab2(sch_1):page75_i19@chpset_lib.skx_ext_b(chips)!SKX_EXT_B_BGA1-IC,TBD!!!F103!VSS(257)!!!!
S!GND!U2D1!DD23!@baseboard_fab2_lib.baseboard_fab2(sch_1):page75_i19@chpset_lib.skx_ext_b(chips)!SKX_EXT_B_BGA1-IC,TBD!!!F103!VSS(258)!!!!
S!GND!U2D1!DD11!@baseboard_fab2_lib.baseboard_fab2(sch_1):page75_i19@chpset_lib.skx_ext_b(chips)!SKX_EXT_B_BGA1-IC,TBD!!!F103!VSS(259)!!!!
S!GND!U2D1!DC86!@baseboard_fab2_lib.baseboard_fab2(sch_1):page75_i19@chpset_lib.skx_ext_b(chips)!SKX_EXT_B_BGA1-IC,TBD!!!F103!VSS(260)!!!!
S!GND!U2D1!DC84!@baseboard_fab2_lib.baseboard_fab2(sch_1):page75_i19@chpset_lib.skx_ext_b(chips)!SKX_EXT_B_BGA1-IC,TBD!!!F103!VSS(261)!!!!
S!GND!U2D1!DC78!@baseboard_fab2_lib.baseboard_fab2(sch_1):page75_i19@chpset_lib.skx_ext_b(chips)!SKX_EXT_B_BGA1-IC,TBD!!!F103!VSS(262)!!!!
S!GND!U2D1!DC70!@baseboard_fab2_lib.baseboard_fab2(sch_1):page75_i19@chpset_lib.skx_ext_b(chips)!SKX_EXT_B_BGA1-IC,TBD!!!F103!VSS(263)!!!!
S!GND!U2D1!DC68!@baseboard_fab2_lib.baseboard_fab2(sch_1):page75_i19@chpset_lib.skx_ext_b(chips)!SKX_EXT_B_BGA1-IC,TBD!!!F103!VSS(264)!!!!
S!GND!U2D1!DC66!@baseboard_fab2_lib.baseboard_fab2(sch_1):page75_i19@chpset_lib.skx_ext_b(chips)!SKX_EXT_B_BGA1-IC,TBD!!!F103!VSS(265)!!!!
S!GND!U2D1!DC64!@baseboard_fab2_lib.baseboard_fab2(sch_1):page75_i19@chpset_lib.skx_ext_b(chips)!SKX_EXT_B_BGA1-IC,TBD!!!F103!VSS(266)!!!!
S!GND!U2D1!DC42!@baseboard_fab2_lib.baseboard_fab2(sch_1):page75_i19@chpset_lib.skx_ext_b(chips)!SKX_EXT_B_BGA1-IC,TBD!!!F103!VSS(267)!!!!
S!GND!U2D1!EF79!@baseboard_fab2_lib.baseboard_fab2(sch_1):page75_i20@chpset_lib.skx_ext_b(chips)!SKX_EXT_B_BGA1-IC,TBD!!!F102!VSS(0)!!!!
S!GND!U2D1!DT69!@baseboard_fab2_lib.baseboard_fab2(sch_1):page75_i20@chpset_lib.skx_ext_b(chips)!SKX_EXT_B_BGA1-IC,TBD!!!F102!VSS(100)!!!!
S!GND!U2D1!DT65!@baseboard_fab2_lib.baseboard_fab2(sch_1):page75_i20@chpset_lib.skx_ext_b(chips)!SKX_EXT_B_BGA1-IC,TBD!!!F102!VSS(101)!!!!
S!GND!U2D1!DH21!@baseboard_fab2_lib.baseboard_fab2(sch_1):page75_i20@chpset_lib.skx_ext_b(chips)!SKX_EXT_B_BGA1-IC,TBD!!!F102!VSS(102)!!!!
S!GND!U2D1!DT17!@baseboard_fab2_lib.baseboard_fab2(sch_1):page75_i20@chpset_lib.skx_ext_b(chips)!SKX_EXT_B_BGA1-IC,TBD!!!F102!VSS(103)!!!!
S!GND!U2D1!DT3!@baseboard_fab2_lib.baseboard_fab2(sch_1):page75_i20@chpset_lib.skx_ext_b(chips)!SKX_EXT_B_BGA1-IC,TBD!!!F102!VSS(104)!!!!
S!GND!U2D1!DR78!@baseboard_fab2_lib.baseboard_fab2(sch_1):page75_i20@chpset_lib.skx_ext_b(chips)!SKX_EXT_B_BGA1-IC,TBD!!!F102!VSS(105)!!!!
S!GND!U2D1!DR76!@baseboard_fab2_lib.baseboard_fab2(sch_1):page75_i20@chpset_lib.skx_ext_b(chips)!SKX_EXT_B_BGA1-IC,TBD!!!F102!VSS(106)!!!!
S!GND!U2D1!DR74!@baseboard_fab2_lib.baseboard_fab2(sch_1):page75_i20@chpset_lib.skx_ext_b(chips)!SKX_EXT_B_BGA1-IC,TBD!!!F102!VSS(107)!!!!
S!GND!U2D1!EE24!@baseboard_fab2_lib.baseboard_fab2(sch_1):page75_i20@chpset_lib.skx_ext_b(chips)!SKX_EXT_B_BGA1-IC,TBD!!!F102!VSS(10)!!!!
S!GND!U2D1!ED77!@baseboard_fab2_lib.baseboard_fab2(sch_1):page75_i20@chpset_lib.skx_ext_b(chips)!SKX_EXT_B_BGA1-IC,TBD!!!F102!VSS(11)!!!!
S!GND!U2D1!ED35!@baseboard_fab2_lib.baseboard_fab2(sch_1):page75_i20@chpset_lib.skx_ext_b(chips)!SKX_EXT_B_BGA1-IC,TBD!!!F102!VSS(12)!!!!
S!GND!U2D1!ED29!@baseboard_fab2_lib.baseboard_fab2(sch_1):page75_i20@chpset_lib.skx_ext_b(chips)!SKX_EXT_B_BGA1-IC,TBD!!!F102!VSS(13)!!!!
S!GND!U2D1!ED23!@baseboard_fab2_lib.baseboard_fab2(sch_1):page75_i20@chpset_lib.skx_ext_b(chips)!SKX_EXT_B_BGA1-IC,TBD!!!F102!VSS(14)!!!!
S!GND!U2D1!ED15!@baseboard_fab2_lib.baseboard_fab2(sch_1):page75_i20@chpset_lib.skx_ext_b(chips)!SKX_EXT_B_BGA1-IC,TBD!!!F102!VSS(15)!!!!
S!GND!U2D1!ED11!@baseboard_fab2_lib.baseboard_fab2(sch_1):page75_i20@chpset_lib.skx_ext_b(chips)!SKX_EXT_B_BGA1-IC,TBD!!!F102!VSS(16)!!!!
S!GND!U2D1!EC76!@baseboard_fab2_lib.baseboard_fab2(sch_1):page75_i20@chpset_lib.skx_ext_b(chips)!SKX_EXT_B_BGA1-IC,TBD!!!F102!VSS(17)!!!!
S!GND!U2D1!EC74!@baseboard_fab2_lib.baseboard_fab2(sch_1):page75_i20@chpset_lib.skx_ext_b(chips)!SKX_EXT_B_BGA1-IC,TBD!!!F102!VSS(18)!!!!
S!GND!U2D1!EC72!@baseboard_fab2_lib.baseboard_fab2(sch_1):page75_i20@chpset_lib.skx_ext_b(chips)!SKX_EXT_B_BGA1-IC,TBD!!!F102!VSS(19)!!!!
S!GND!U2D1!EF75!@baseboard_fab2_lib.baseboard_fab2(sch_1):page75_i20@chpset_lib.skx_ext_b(chips)!SKX_EXT_B_BGA1-IC,TBD!!!F102!VSS(1)!!!!
S!GND!U2D1!EC70!@baseboard_fab2_lib.baseboard_fab2(sch_1):page75_i20@chpset_lib.skx_ext_b(chips)!SKX_EXT_B_BGA1-IC,TBD!!!F102!VSS(20)!!!!
S!GND!U2D1!EC10!@baseboard_fab2_lib.baseboard_fab2(sch_1):page75_i20@chpset_lib.skx_ext_b(chips)!SKX_EXT_B_BGA1-IC,TBD!!!F102!VSS(21)!!!!
S!GND!U2D1!EB69!@baseboard_fab2_lib.baseboard_fab2(sch_1):page75_i20@chpset_lib.skx_ext_b(chips)!SKX_EXT_B_BGA1-IC,TBD!!!F102!VSS(22)!!!!
S!GND!U2D1!EB65!@baseboard_fab2_lib.baseboard_fab2(sch_1):page75_i20@chpset_lib.skx_ext_b(chips)!SKX_EXT_B_BGA1-IC,TBD!!!F102!VSS(23)!!!!
S!GND!U2D1!EB41!@baseboard_fab2_lib.baseboard_fab2(sch_1):page75_i20@chpset_lib.skx_ext_b(chips)!SKX_EXT_B_BGA1-IC,TBD!!!F102!VSS(24)!!!!
S!GND!U2D1!EB39!@baseboard_fab2_lib.baseboard_fab2(sch_1):page75_i20@chpset_lib.skx_ext_b(chips)!SKX_EXT_B_BGA1-IC,TBD!!!F102!VSS(25)!!!!
S!GND!U2D1!EB37!@baseboard_fab2_lib.baseboard_fab2(sch_1):page75_i20@chpset_lib.skx_ext_b(chips)!SKX_EXT_B_BGA1-IC,TBD!!!F102!VSS(26)!!!!
S!GND!U2D1!EB35!@baseboard_fab2_lib.baseboard_fab2(sch_1):page75_i20@chpset_lib.skx_ext_b(chips)!SKX_EXT_B_BGA1-IC,TBD!!!F102!VSS(27)!!!!
S!GND!U2D1!EB33!@baseboard_fab2_lib.baseboard_fab2(sch_1):page75_i20@chpset_lib.skx_ext_b(chips)!SKX_EXT_B_BGA1-IC,TBD!!!F102!VSS(28)!!!!
S!GND!U2D1!EB31!@baseboard_fab2_lib.baseboard_fab2(sch_1):page75_i20@chpset_lib.skx_ext_b(chips)!SKX_EXT_B_BGA1-IC,TBD!!!F102!VSS(29)!!!!
S!GND!U2D1!EF71!@baseboard_fab2_lib.baseboard_fab2(sch_1):page75_i20@chpset_lib.skx_ext_b(chips)!SKX_EXT_B_BGA1-IC,TBD!!!F102!VSS(2)!!!!
S!GND!U2D1!EB29!@baseboard_fab2_lib.baseboard_fab2(sch_1):page75_i20@chpset_lib.skx_ext_b(chips)!SKX_EXT_B_BGA1-IC,TBD!!!F102!VSS(30)!!!!
S!GND!U2D1!EB27!@baseboard_fab2_lib.baseboard_fab2(sch_1):page75_i20@chpset_lib.skx_ext_b(chips)!SKX_EXT_B_BGA1-IC,TBD!!!F102!VSS(31)!!!!
S!GND!U2D1!EB25!@baseboard_fab2_lib.baseboard_fab2(sch_1):page75_i20@chpset_lib.skx_ext_b(chips)!SKX_EXT_B_BGA1-IC,TBD!!!F102!VSS(32)!!!!
S!GND!U2D1!EB23!@baseboard_fab2_lib.baseboard_fab2(sch_1):page75_i20@chpset_lib.skx_ext_b(chips)!SKX_EXT_B_BGA1-IC,TBD!!!F102!VSS(33)!!!!
S!GND!U2D1!BR18!@baseboard_fab2_lib.baseboard_fab2(sch_1):page75_i20@chpset_lib.skx_ext_b(chips)!SKX_EXT_B_BGA1-IC,TBD!!!F102!VSS(34)!!!!
S!GND!U2D1!EB13!@baseboard_fab2_lib.baseboard_fab2(sch_1):page75_i20@chpset_lib.skx_ext_b(chips)!SKX_EXT_B_BGA1-IC,TBD!!!F102!VSS(35)!!!!
S!GND!U2D1!EA82!@baseboard_fab2_lib.baseboard_fab2(sch_1):page75_i20@chpset_lib.skx_ext_b(chips)!SKX_EXT_B_BGA1-IC,TBD!!!F102!VSS(36)!!!!
S!GND!U2D1!EA80!@baseboard_fab2_lib.baseboard_fab2(sch_1):page75_i20@chpset_lib.skx_ext_b(chips)!SKX_EXT_B_BGA1-IC,TBD!!!F102!VSS(37)!!!!
S!GND!U2D1!EA78!@baseboard_fab2_lib.baseboard_fab2(sch_1):page75_i20@chpset_lib.skx_ext_b(chips)!SKX_EXT_B_BGA1-IC,TBD!!!F102!VSS(38)!!!!
S!GND!U2D1!EA76!@baseboard_fab2_lib.baseboard_fab2(sch_1):page75_i20@chpset_lib.skx_ext_b(chips)!SKX_EXT_B_BGA1-IC,TBD!!!F102!VSS(39)!!!!
S!GND!U2D1!EE78!@baseboard_fab2_lib.baseboard_fab2(sch_1):page75_i20@chpset_lib.skx_ext_b(chips)!SKX_EXT_B_BGA1-IC,TBD!!!F102!VSS(3)!!!!
S!GND!U2D1!EA70!@baseboard_fab2_lib.baseboard_fab2(sch_1):page75_i20@chpset_lib.skx_ext_b(chips)!SKX_EXT_B_BGA1-IC,TBD!!!F102!VSS(40)!!!!
S!GND!U2D1!EA64!@baseboard_fab2_lib.baseboard_fab2(sch_1):page75_i20@chpset_lib.skx_ext_b(chips)!SKX_EXT_B_BGA1-IC,TBD!!!F102!VSS(41)!!!!
S!GND!U2D1!EA42!@baseboard_fab2_lib.baseboard_fab2(sch_1):page75_i20@chpset_lib.skx_ext_b(chips)!SKX_EXT_B_BGA1-IC,TBD!!!F102!VSS(42)!!!!
S!GND!U2D1!EA22!@baseboard_fab2_lib.baseboard_fab2(sch_1):page75_i20@chpset_lib.skx_ext_b(chips)!SKX_EXT_B_BGA1-IC,TBD!!!F102!VSS(43)!!!!
S!GND!U2D1!EA20!@baseboard_fab2_lib.baseboard_fab2(sch_1):page75_i20@chpset_lib.skx_ext_b(chips)!SKX_EXT_B_BGA1-IC,TBD!!!F102!VSS(44)!!!!
S!GND!U2D1!EA16!@baseboard_fab2_lib.baseboard_fab2(sch_1):page75_i20@chpset_lib.skx_ext_b(chips)!SKX_EXT_B_BGA1-IC,TBD!!!F102!VSS(45)!!!!
S!GND!U2D1!J16!@baseboard_fab2_lib.baseboard_fab2(sch_1):page75_i20@chpset_lib.skx_ext_b(chips)!SKX_EXT_B_BGA1-IC,TBD!!!F102!VSS(46)!!!!
S!GND!U2D1!EA6!@baseboard_fab2_lib.baseboard_fab2(sch_1):page75_i20@chpset_lib.skx_ext_b(chips)!SKX_EXT_B_BGA1-IC,TBD!!!F102!VSS(47)!!!!
S!GND!U2D1!DY75!@baseboard_fab2_lib.baseboard_fab2(sch_1):page75_i20@chpset_lib.skx_ext_b(chips)!SKX_EXT_B_BGA1-IC,TBD!!!F102!VSS(48)!!!!
S!GND!U2D1!DY71!@baseboard_fab2_lib.baseboard_fab2(sch_1):page75_i20@chpset_lib.skx_ext_b(chips)!SKX_EXT_B_BGA1-IC,TBD!!!F102!VSS(49)!!!!
S!GND!U2D1!EE76!@baseboard_fab2_lib.baseboard_fab2(sch_1):page75_i20@chpset_lib.skx_ext_b(chips)!SKX_EXT_B_BGA1-IC,TBD!!!F102!VSS(4)!!!!
S!GND!U2D1!DY41!@baseboard_fab2_lib.baseboard_fab2(sch_1):page75_i20@chpset_lib.skx_ext_b(chips)!SKX_EXT_B_BGA1-IC,TBD!!!F102!VSS(50)!!!!
S!GND!U2D1!DY35!@baseboard_fab2_lib.baseboard_fab2(sch_1):page75_i20@chpset_lib.skx_ext_b(chips)!SKX_EXT_B_BGA1-IC,TBD!!!F102!VSS(51)!!!!
S!GND!U2D1!DY29!@baseboard_fab2_lib.baseboard_fab2(sch_1):page75_i20@chpset_lib.skx_ext_b(chips)!SKX_EXT_B_BGA1-IC,TBD!!!F102!VSS(52)!!!!
S!GND!U2D1!DY23!@baseboard_fab2_lib.baseboard_fab2(sch_1):page75_i20@chpset_lib.skx_ext_b(chips)!SKX_EXT_B_BGA1-IC,TBD!!!F102!VSS(53)!!!!
S!GND!U2D1!DY19!@baseboard_fab2_lib.baseboard_fab2(sch_1):page75_i20@chpset_lib.skx_ext_b(chips)!SKX_EXT_B_BGA1-IC,TBD!!!F102!VSS(54)!!!!
S!GND!U2D1!DY5!@baseboard_fab2_lib.baseboard_fab2(sch_1):page75_i20@chpset_lib.skx_ext_b(chips)!SKX_EXT_B_BGA1-IC,TBD!!!F102!VSS(55)!!!!
S!GND!U2D1!DW84!@baseboard_fab2_lib.baseboard_fab2(sch_1):page75_i20@chpset_lib.skx_ext_b(chips)!SKX_EXT_B_BGA1-IC,TBD!!!F102!VSS(56)!!!!
S!GND!U2D1!DW82!@baseboard_fab2_lib.baseboard_fab2(sch_1):page75_i20@chpset_lib.skx_ext_b(chips)!SKX_EXT_B_BGA1-IC,TBD!!!F102!VSS(57)!!!!
S!GND!U2D1!DW8!@baseboard_fab2_lib.baseboard_fab2(sch_1):page75_i20@chpset_lib.skx_ext_b(chips)!SKX_EXT_B_BGA1-IC,TBD!!!F102!VSS(58)!!!!
S!GND!U2D1!DW76!@baseboard_fab2_lib.baseboard_fab2(sch_1):page75_i20@chpset_lib.skx_ext_b(chips)!SKX_EXT_B_BGA1-IC,TBD!!!F102!VSS(59)!!!!
S!GND!U2D1!EE70!@baseboard_fab2_lib.baseboard_fab2(sch_1):page75_i20@chpset_lib.skx_ext_b(chips)!SKX_EXT_B_BGA1-IC,TBD!!!F102!VSS(5)!!!!
S!GND!U2D1!DW74!@baseboard_fab2_lib.baseboard_fab2(sch_1):page75_i20@chpset_lib.skx_ext_b(chips)!SKX_EXT_B_BGA1-IC,TBD!!!F102!VSS(60)!!!!
S!GND!U2D1!DW72!@baseboard_fab2_lib.baseboard_fab2(sch_1):page75_i20@chpset_lib.skx_ext_b(chips)!SKX_EXT_B_BGA1-IC,TBD!!!F102!VSS(61)!!!!
S!GND!U2D1!DW70!@baseboard_fab2_lib.baseboard_fab2(sch_1):page75_i20@chpset_lib.skx_ext_b(chips)!SKX_EXT_B_BGA1-IC,TBD!!!F102!VSS(62)!!!!
S!GND!U2D1!DW68!@baseboard_fab2_lib.baseboard_fab2(sch_1):page75_i20@chpset_lib.skx_ext_b(chips)!SKX_EXT_B_BGA1-IC,TBD!!!F102!VSS(63)!!!!
S!GND!U2D1!DW66!@baseboard_fab2_lib.baseboard_fab2(sch_1):page75_i20@chpset_lib.skx_ext_b(chips)!SKX_EXT_B_BGA1-IC,TBD!!!F102!VSS(64)!!!!
S!GND!U2D1!DW64!@baseboard_fab2_lib.baseboard_fab2(sch_1):page75_i20@chpset_lib.skx_ext_b(chips)!SKX_EXT_B_BGA1-IC,TBD!!!F102!VSS(65)!!!!
S!GND!U2D1!DW40!@baseboard_fab2_lib.baseboard_fab2(sch_1):page75_i20@chpset_lib.skx_ext_b(chips)!SKX_EXT_B_BGA1-IC,TBD!!!F102!VSS(66)!!!!
S!GND!U2D1!DW36!@baseboard_fab2_lib.baseboard_fab2(sch_1):page75_i20@chpset_lib.skx_ext_b(chips)!SKX_EXT_B_BGA1-IC,TBD!!!F102!VSS(67)!!!!
S!GND!U2D1!DW34!@baseboard_fab2_lib.baseboard_fab2(sch_1):page75_i20@chpset_lib.skx_ext_b(chips)!SKX_EXT_B_BGA1-IC,TBD!!!F102!VSS(68)!!!!
S!GND!U2D1!DW30!@baseboard_fab2_lib.baseboard_fab2(sch_1):page75_i20@chpset_lib.skx_ext_b(chips)!SKX_EXT_B_BGA1-IC,TBD!!!F102!VSS(69)!!!!
S!GND!U2D1!EE36!@baseboard_fab2_lib.baseboard_fab2(sch_1):page75_i20@chpset_lib.skx_ext_b(chips)!SKX_EXT_B_BGA1-IC,TBD!!!F102!VSS(6)!!!!
S!GND!U2D1!DW28!@baseboard_fab2_lib.baseboard_fab2(sch_1):page75_i20@chpset_lib.skx_ext_b(chips)!SKX_EXT_B_BGA1-IC,TBD!!!F102!VSS(70)!!!!
S!GND!U2D1!DW24!@baseboard_fab2_lib.baseboard_fab2(sch_1):page75_i20@chpset_lib.skx_ext_b(chips)!SKX_EXT_B_BGA1-IC,TBD!!!F102!VSS(71)!!!!
S!GND!U2D1!DW20!@baseboard_fab2_lib.baseboard_fab2(sch_1):page75_i20@chpset_lib.skx_ext_b(chips)!SKX_EXT_B_BGA1-IC,TBD!!!F102!VSS(72)!!!!
S!GND!U2D1!DW12!@baseboard_fab2_lib.baseboard_fab2(sch_1):page75_i20@chpset_lib.skx_ext_b(chips)!SKX_EXT_B_BGA1-IC,TBD!!!F102!VSS(73)!!!!
S!GND!U2D1!DV81!@baseboard_fab2_lib.baseboard_fab2(sch_1):page75_i20@chpset_lib.skx_ext_b(chips)!SKX_EXT_B_BGA1-IC,TBD!!!F102!VSS(74)!!!!
S!GND!U2D1!DV77!@baseboard_fab2_lib.baseboard_fab2(sch_1):page75_i20@chpset_lib.skx_ext_b(chips)!SKX_EXT_B_BGA1-IC,TBD!!!F102!VSS(75)!!!!
S!GND!U2D1!DV73!@baseboard_fab2_lib.baseboard_fab2(sch_1):page75_i20@chpset_lib.skx_ext_b(chips)!SKX_EXT_B_BGA1-IC,TBD!!!F102!VSS(76)!!!!
S!GND!U2D1!DV39!@baseboard_fab2_lib.baseboard_fab2(sch_1):page75_i20@chpset_lib.skx_ext_b(chips)!SKX_EXT_B_BGA1-IC,TBD!!!F102!VSS(77)!!!!
S!GND!U2D1!DV37!@baseboard_fab2_lib.baseboard_fab2(sch_1):page75_i20@chpset_lib.skx_ext_b(chips)!SKX_EXT_B_BGA1-IC,TBD!!!F102!VSS(78)!!!!
S!GND!U2D1!DV33!@baseboard_fab2_lib.baseboard_fab2(sch_1):page75_i20@chpset_lib.skx_ext_b(chips)!SKX_EXT_B_BGA1-IC,TBD!!!F102!VSS(79)!!!!
S!GND!U2D1!EE34!@baseboard_fab2_lib.baseboard_fab2(sch_1):page75_i20@chpset_lib.skx_ext_b(chips)!SKX_EXT_B_BGA1-IC,TBD!!!F102!VSS(7)!!!!
S!GND!U2D1!DV31!@baseboard_fab2_lib.baseboard_fab2(sch_1):page75_i20@chpset_lib.skx_ext_b(chips)!SKX_EXT_B_BGA1-IC,TBD!!!F102!VSS(80)!!!!
S!GND!U2D1!DV27!@baseboard_fab2_lib.baseboard_fab2(sch_1):page75_i20@chpset_lib.skx_ext_b(chips)!SKX_EXT_B_BGA1-IC,TBD!!!F102!VSS(81)!!!!
S!GND!U2D1!DV25!@baseboard_fab2_lib.baseboard_fab2(sch_1):page75_i20@chpset_lib.skx_ext_b(chips)!SKX_EXT_B_BGA1-IC,TBD!!!F102!VSS(82)!!!!
S!GND!U2D1!DV21!@baseboard_fab2_lib.baseboard_fab2(sch_1):page75_i20@chpset_lib.skx_ext_b(chips)!SKX_EXT_B_BGA1-IC,TBD!!!F102!VSS(83)!!!!
S!GND!U2D1!DU84!@baseboard_fab2_lib.baseboard_fab2(sch_1):page75_i20@chpset_lib.skx_ext_b(chips)!SKX_EXT_B_BGA1-IC,TBD!!!F102!VSS(84)!!!!
S!GND!U2D1!DU82!@baseboard_fab2_lib.baseboard_fab2(sch_1):page75_i20@chpset_lib.skx_ext_b(chips)!SKX_EXT_B_BGA1-IC,TBD!!!F102!VSS(85)!!!!
S!GND!U2D1!DU80!@baseboard_fab2_lib.baseboard_fab2(sch_1):page75_i20@chpset_lib.skx_ext_b(chips)!SKX_EXT_B_BGA1-IC,TBD!!!F102!VSS(86)!!!!
S!GND!U2D1!DU78!@baseboard_fab2_lib.baseboard_fab2(sch_1):page75_i20@chpset_lib.skx_ext_b(chips)!SKX_EXT_B_BGA1-IC,TBD!!!F102!VSS(87)!!!!
S!GND!U2D1!DU72!@baseboard_fab2_lib.baseboard_fab2(sch_1):page75_i20@chpset_lib.skx_ext_b(chips)!SKX_EXT_B_BGA1-IC,TBD!!!F102!VSS(88)!!!!
S!GND!U2D1!DU70!@baseboard_fab2_lib.baseboard_fab2(sch_1):page75_i20@chpset_lib.skx_ext_b(chips)!SKX_EXT_B_BGA1-IC,TBD!!!F102!VSS(89)!!!!
S!GND!U2D1!EE30!@baseboard_fab2_lib.baseboard_fab2(sch_1):page75_i20@chpset_lib.skx_ext_b(chips)!SKX_EXT_B_BGA1-IC,TBD!!!F102!VSS(8)!!!!
S!GND!U2D1!DU38!@baseboard_fab2_lib.baseboard_fab2(sch_1):page75_i20@chpset_lib.skx_ext_b(chips)!SKX_EXT_B_BGA1-IC,TBD!!!F102!VSS(90)!!!!
S!GND!U2D1!DU32!@baseboard_fab2_lib.baseboard_fab2(sch_1):page75_i20@chpset_lib.skx_ext_b(chips)!SKX_EXT_B_BGA1-IC,TBD!!!F102!VSS(91)!!!!
S!GND!U2D1!DU26!@baseboard_fab2_lib.baseboard_fab2(sch_1):page75_i20@chpset_lib.skx_ext_b(chips)!SKX_EXT_B_BGA1-IC,TBD!!!F102!VSS(92)!!!!
S!GND!U2D1!DU22!@baseboard_fab2_lib.baseboard_fab2(sch_1):page75_i20@chpset_lib.skx_ext_b(chips)!SKX_EXT_B_BGA1-IC,TBD!!!F102!VSS(93)!!!!
S!GND!U2D1!CN14!@baseboard_fab2_lib.baseboard_fab2(sch_1):page75_i20@chpset_lib.skx_ext_b(chips)!SKX_EXT_B_BGA1-IC,TBD!!!F102!VSS(94)!!!!
S!GND!U2D1!DU14!@baseboard_fab2_lib.baseboard_fab2(sch_1):page75_i20@chpset_lib.skx_ext_b(chips)!SKX_EXT_B_BGA1-IC,TBD!!!F102!VSS(95)!!!!
S!GND!U2D1!DU10!@baseboard_fab2_lib.baseboard_fab2(sch_1):page75_i20@chpset_lib.skx_ext_b(chips)!SKX_EXT_B_BGA1-IC,TBD!!!F102!VSS(96)!!!!
S!GND!U2D1!DT85!@baseboard_fab2_lib.baseboard_fab2(sch_1):page75_i20@chpset_lib.skx_ext_b(chips)!SKX_EXT_B_BGA1-IC,TBD!!!F102!VSS(97)!!!!
S!GND!U2D1!DT83!@baseboard_fab2_lib.baseboard_fab2(sch_1):page75_i20@chpset_lib.skx_ext_b(chips)!SKX_EXT_B_BGA1-IC,TBD!!!F102!VSS(98)!!!!
S!GND!U2D1!DT79!@baseboard_fab2_lib.baseboard_fab2(sch_1):page75_i20@chpset_lib.skx_ext_b(chips)!SKX_EXT_B_BGA1-IC,TBD!!!F102!VSS(99)!!!!
S!GND!U2D1!EE28!@baseboard_fab2_lib.baseboard_fab2(sch_1):page75_i20@chpset_lib.skx_ext_b(chips)!SKX_EXT_B_BGA1-IC,TBD!!!F102!VSS(9)!!!!
S!GND!U2D1!EE80!@baseboard_fab2_lib.baseboard_fab2(sch_1):page74_i20@chpset_lib.skx_ext_b(chips)!SKX_EXT_B_BGA1-IC,TBD!!!F109!VSS(1230)!!!!
S!GND!U2D1!EB83!@baseboard_fab2_lib.baseboard_fab2(sch_1):page74_i20@chpset_lib.skx_ext_b(chips)!SKX_EXT_B_BGA1-IC,TBD!!!F109!VSS(1240)!!!!
S!GND!U2D1!EA84!@baseboard_fab2_lib.baseboard_fab2(sch_1):page74_i20@chpset_lib.skx_ext_b(chips)!SKX_EXT_B_BGA1-IC,TBD!!!F109!VSS(1241)!!!!
S!GND!U2D1!DY85!@baseboard_fab2_lib.baseboard_fab2(sch_1):page74_i20@chpset_lib.skx_ext_b(chips)!SKX_EXT_B_BGA1-IC,TBD!!!F109!VSS(1242)!!!!
S!GND!U2D1!J86!@baseboard_fab2_lib.baseboard_fab2(sch_1):page74_i20@chpset_lib.skx_ext_b(chips)!SKX_EXT_B_BGA1-IC,TBD!!!F109!VSS(1243)!!!!
S!GND!U2D1!E82!@baseboard_fab2_lib.baseboard_fab2(sch_1):page74_i20@chpset_lib.skx_ext_b(chips)!SKX_EXT_B_BGA1-IC,TBD!!!F109!VSS(1244)!!!!
S!GND!U2D1!D81!@baseboard_fab2_lib.baseboard_fab2(sch_1):page74_i20@chpset_lib.skx_ext_b(chips)!SKX_EXT_B_BGA1-IC,TBD!!!F109!VSS(1245)!!!!
S!GND!U2D1!D3!@baseboard_fab2_lib.baseboard_fab2(sch_1):page74_i20@chpset_lib.skx_ext_b(chips)!SKX_EXT_B_BGA1-IC,TBD!!!F109!VSS(1246)!!!!
S!GND!U2D1!C80!@baseboard_fab2_lib.baseboard_fab2(sch_1):page74_i20@chpset_lib.skx_ext_b(chips)!SKX_EXT_B_BGA1-IC,TBD!!!F109!VSS(1247)!!!!
S!GND!U2D1!C4!@baseboard_fab2_lib.baseboard_fab2(sch_1):page74_i20@chpset_lib.skx_ext_b(chips)!SKX_EXT_B_BGA1-IC,TBD!!!F109!VSS(1248)!!!!
S!GND!U2D1!B79!@baseboard_fab2_lib.baseboard_fab2(sch_1):page74_i20@chpset_lib.skx_ext_b(chips)!SKX_EXT_B_BGA1-IC,TBD!!!F109!VSS(1249)!!!!
S!GND!U2D1!EE8!@baseboard_fab2_lib.baseboard_fab2(sch_1):page74_i20@chpset_lib.skx_ext_b(chips)!SKX_EXT_B_BGA1-IC,TBD!!!F109!VSS(1231)!!!!
S!GND!U2D1!B5!@baseboard_fab2_lib.baseboard_fab2(sch_1):page74_i20@chpset_lib.skx_ext_b(chips)!SKX_EXT_B_BGA1-IC,TBD!!!F109!VSS(1250)!!!!
S!GND!U2D1!B43!@baseboard_fab2_lib.baseboard_fab2(sch_1):page74_i20@chpset_lib.skx_ext_b(chips)!SKX_EXT_B_BGA1-IC,TBD!!!F109!VSS(1251)!!!!
S!GND!U2D1!A42!@baseboard_fab2_lib.baseboard_fab2(sch_1):page74_i20@chpset_lib.skx_ext_b(chips)!SKX_EXT_B_BGA1-IC,TBD!!!F109!VSS(1252)!!!!
S!GND!U2D1!EE40!@baseboard_fab2_lib.baseboard_fab2(sch_1):page74_i20@chpset_lib.skx_ext_b(chips)!SKX_EXT_B_BGA1-IC,TBD!!!F109!VSS(1232)!!!!
S!GND!U2D1!ED81!@baseboard_fab2_lib.baseboard_fab2(sch_1):page74_i20@chpset_lib.skx_ext_b(chips)!SKX_EXT_B_BGA1-IC,TBD!!!F109!VSS(1233)!!!!
S!GND!U2D1!ED7!@baseboard_fab2_lib.baseboard_fab2(sch_1):page74_i20@chpset_lib.skx_ext_b(chips)!SKX_EXT_B_BGA1-IC,TBD!!!F109!VSS(1234)!!!!
S!GND!U2D1!ED41!@baseboard_fab2_lib.baseboard_fab2(sch_1):page74_i20@chpset_lib.skx_ext_b(chips)!SKX_EXT_B_BGA1-IC,TBD!!!F109!VSS(1235)!!!!
S!GND!U2D1!EC82!@baseboard_fab2_lib.baseboard_fab2(sch_1):page74_i20@chpset_lib.skx_ext_b(chips)!SKX_EXT_B_BGA1-IC,TBD!!!F109!VSS(1236)!!!!
S!GND!U2D1!EC6!@baseboard_fab2_lib.baseboard_fab2(sch_1):page74_i20@chpset_lib.skx_ext_b(chips)!SKX_EXT_B_BGA1-IC,TBD!!!F109!VSS(1237)!!!!
S!GND!U2D1!EC42!@baseboard_fab2_lib.baseboard_fab2(sch_1):page74_i20@chpset_lib.skx_ext_b(chips)!SKX_EXT_B_BGA1-IC,TBD!!!F109!VSS(1238)!!!!
S!GND!U2D1!DW2!@baseboard_fab2_lib.baseboard_fab2(sch_1):page74_i20@chpset_lib.skx_ext_b(chips)!SKX_EXT_B_BGA1-IC,TBD!!!F109!VSS(1239)!!!!
S!P3V3_STBY!EU2T1!5!@baseboard_fab2_lib.baseboard_fab2(sch_1):page198_i1@mstr_vreg.slg55021(chips)!SLG55021_SM-IC,G56246-001!!!F71!D!!!!
S!P3V3_SWITCH_G!EU2T1!7!@baseboard_fab2_lib.baseboard_fab2(sch_1):page198_i1@mstr_vreg.slg55021(chips)!SLG55021_SM-IC,G56246-001!!!F71!G!!!!
S!GND!EU2T1!4!@baseboard_fab2_lib.baseboard_fab2(sch_1):page198_i1@mstr_vreg.slg55021(chips)!SLG55021_SM-IC,G56246-001!!!F71!GND!!!!
S!FM_P3V3_CPLD_EN!EU2T1!2!@baseboard_fab2_lib.baseboard_fab2(sch_1):page198_i1@mstr_vreg.slg55021(chips)!SLG55021_SM-IC,G56246-001!!!F71!\on\!!!!
S!TP_SLG55021_P3V3_8!EU2T1!8!@baseboard_fab2_lib.baseboard_fab2(sch_1):page198_i1@mstr_vreg.slg55021(chips)!SLG55021_SM-IC,G56246-001!!!F71!PG!!!!
S!P3V3!EU2T1!6!@baseboard_fab2_lib.baseboard_fab2(sch_1):page198_i1@mstr_vreg.slg55021(chips)!SLG55021_SM-IC,G56246-001!!!F71!S!!!!
S!P5V_STBY!EU2T1!3!@baseboard_fab2_lib.baseboard_fab2(sch_1):page198_i1@mstr_vreg.slg55021(chips)!SLG55021_SM-IC,G56246-001!!!F71!SHDN_N!!!!
S!GND!EU2T1!9!@baseboard_fab2_lib.baseboard_fab2(sch_1):page198_i1@mstr_vreg.slg55021(chips)!SLG55021_SM-IC,G56246-001!!!F71!THPAD!!!!
S!P5V_STBY!EU2T1!1!@baseboard_fab2_lib.baseboard_fab2(sch_1):page198_i1@mstr_vreg.slg55021(chips)!SLG55021_SM-IC,G56246-001!!!F71!VCC!!!!
S!P12V_STBY!EU7E1!5!@baseboard_fab2_lib.baseboard_fab2(sch_1):page198_i19@mstr_vreg.slg55021(chips)!SLG55021_SM-IC,G56246-001!!!F70!D!!!!
S!P12V_SWITCH_G!EU7E1!7!@baseboard_fab2_lib.baseboard_fab2(sch_1):page198_i19@mstr_vreg.slg55021(chips)!SLG55021_SM-IC,G56246-001!!!F70!G!!!!
S!GND!EU7E1!4!@baseboard_fab2_lib.baseboard_fab2(sch_1):page198_i19@mstr_vreg.slg55021(chips)!SLG55021_SM-IC,G56246-001!!!F70!GND!!!!
S!FM_P12V_MAIN_SW_EN!EU7E1!2!@baseboard_fab2_lib.baseboard_fab2(sch_1):page198_i19@mstr_vreg.slg55021(chips)!SLG55021_SM-IC,G56246-001!!!F70!\on\!!!!
S!TP_SLG55021_P12V_MAIN_8!EU7E1!8!@baseboard_fab2_lib.baseboard_fab2(sch_1):page198_i19@mstr_vreg.slg55021(chips)!SLG55021_SM-IC,G56246-001!!!F70!PG!!!!
S!P12V!EU7E1!6!@baseboard_fab2_lib.baseboard_fab2(sch_1):page198_i19@mstr_vreg.slg55021(chips)!SLG55021_SM-IC,G56246-001!!!F70!S!!!!
S!P5V_STBY!EU7E1!3!@baseboard_fab2_lib.baseboard_fab2(sch_1):page198_i19@mstr_vreg.slg55021(chips)!SLG55021_SM-IC,G56246-001!!!F70!SHDN_N!!!!
S!GND!EU7E1!9!@baseboard_fab2_lib.baseboard_fab2(sch_1):page198_i19@mstr_vreg.slg55021(chips)!SLG55021_SM-IC,G56246-001!!!F70!THPAD!!!!
S!P5V_STBY!EU7E1!1!@baseboard_fab2_lib.baseboard_fab2(sch_1):page198_i19@mstr_vreg.slg55021(chips)!SLG55021_SM-IC,G56246-001!!!F70!VCC!!!!
S!P5V_STBY!EU8B1!5!@baseboard_fab2_lib.baseboard_fab2(sch_1):page198_i13@mstr_vreg.slg55021(chips)!SLG55021_SM-IC,G56246-001!!!F69!D!!!!
S!P5V_SWITCH_G!EU8B1!7!@baseboard_fab2_lib.baseboard_fab2(sch_1):page198_i13@mstr_vreg.slg55021(chips)!SLG55021_SM-IC,G56246-001!!!F69!G!!!!
S!GND!EU8B1!4!@baseboard_fab2_lib.baseboard_fab2(sch_1):page198_i13@mstr_vreg.slg55021(chips)!SLG55021_SM-IC,G56246-001!!!F69!GND!!!!
S!FM_CTNR_PS_ON!EU8B1!2!@baseboard_fab2_lib.baseboard_fab2(sch_1):page198_i13@mstr_vreg.slg55021(chips)!SLG55021_SM-IC,G56246-001!!!F69!\on\!!!!
S!TP_SLG55021_P5V_8!EU8B1!8!@baseboard_fab2_lib.baseboard_fab2(sch_1):page198_i13@mstr_vreg.slg55021(chips)!SLG55021_SM-IC,G56246-001!!!F69!PG!!!!
S!P5V!EU8B1!6!@baseboard_fab2_lib.baseboard_fab2(sch_1):page198_i13@mstr_vreg.slg55021(chips)!SLG55021_SM-IC,G56246-001!!!F69!S!!!!
S!P5V_STBY!EU8B1!3!@baseboard_fab2_lib.baseboard_fab2(sch_1):page198_i13@mstr_vreg.slg55021(chips)!SLG55021_SM-IC,G56246-001!!!F69!SHDN_N!!!!
S!GND!EU8B1!9!@baseboard_fab2_lib.baseboard_fab2(sch_1):page198_i13@mstr_vreg.slg55021(chips)!SLG55021_SM-IC,G56246-001!!!F69!THPAD!!!!
S!P5V_STBY!EU8B1!1!@baseboard_fab2_lib.baseboard_fab2(sch_1):page198_i13@mstr_vreg.slg55021(chips)!SLG55021_SM-IC,G56246-001!!!F69!VCC!!!!
S!P12V_STBY!EU9M1!5!@baseboard_fab2_lib.baseboard_fab2(sch_1):page198_i69@mstr_vreg.slg55021(chips)!SLG55021_SM-IC,G56246-001!!!F68!D!!!!
S!P12V_FAN_SWITCH_G!EU9M1!7!@baseboard_fab2_lib.baseboard_fab2(sch_1):page198_i69@mstr_vreg.slg55021(chips)!SLG55021_SM-IC,G56246-001!!!F68!G!!!!
S!GND!EU9M1!4!@baseboard_fab2_lib.baseboard_fab2(sch_1):page198_i69@mstr_vreg.slg55021(chips)!SLG55021_SM-IC,G56246-001!!!F68!GND!!!!
S!FM_ENABLE_FAN_POWER!EU9M1!2!@baseboard_fab2_lib.baseboard_fab2(sch_1):page198_i69@mstr_vreg.slg55021(chips)!SLG55021_SM-IC,G56246-001!!!F68!\on\!!!!
S!TP_SLG55021_P12V_FAN_8!EU9M1!8!@baseboard_fab2_lib.baseboard_fab2(sch_1):page198_i69@mstr_vreg.slg55021(chips)!SLG55021_SM-IC,G56246-001!!!F68!PG!!!!
S!P12V_FAN!EU9M1!6!@baseboard_fab2_lib.baseboard_fab2(sch_1):page198_i69@mstr_vreg.slg55021(chips)!SLG55021_SM-IC,G56246-001!!!F68!S!!!!
S!P5V_STBY!EU9M1!3!@baseboard_fab2_lib.baseboard_fab2(sch_1):page198_i69@mstr_vreg.slg55021(chips)!SLG55021_SM-IC,G56246-001!!!F68!SHDN_N!!!!
S!GND!EU9M1!9!@baseboard_fab2_lib.baseboard_fab2(sch_1):page198_i69@mstr_vreg.slg55021(chips)!SLG55021_SM-IC,G56246-001!!!F68!THPAD!!!!
S!P5V_STBY!EU9M1!1!@baseboard_fab2_lib.baseboard_fab2(sch_1):page198_i69@mstr_vreg.slg55021(chips)!SLG55021_SM-IC,G56246-001!!!F68!VCC!!!!
S!GND!Y9E1!4!!CRYSTAL_2013-25.000MHZ,IC,D717A!!!!!!!!
S!GND!Y9E1!2!!CRYSTAL_2013-25.000MHZ,IC,D717A!!!!!!!!
S!XTAL_25MHZ_IN!Y9E1!1!@baseboard_fab2_lib.baseboard_fab2(sch_1):page139_i109@mstr_discrete.crystal(chips)!CRYSTAL_2013-25.000MHZ,IC,D717A!!!F2232!A!!!!
S!XTAL_25MHZ_OUT_R!Y9E1!3!@baseboard_fab2_lib.baseboard_fab2(sch_1):page139_i109@mstr_discrete.crystal(chips)!CRYSTAL_2013-25.000MHZ,IC,D717A!!!F2232!B!!!!
S!P12V_STBY!R3P48!1!@baseboard_fab2_lib.baseboard_fab2(sch_1):page196_i74@mstr_discrete.res(chips)!RES_0402-90.9K,1%,1/16W,CHIP,GA!!!F282!A!!!!
S!VSENSE_P12V_ADM1085!R3P48!2!@baseboard_fab2_lib.baseboard_fab2(sch_1):page196_i74@mstr_discrete.res(chips)!RES_0402-90.9K,1%,1/16W,CHIP,GA!!!F282!B!!!!
S!A_HSC_ISET_S!R1D13!1!@baseboard_fab2_lib.baseboard_fab2(sch_1):page199_i84@mstr_discrete.res(chips)!RES_0402-90.9K,1%,1/16W,CHIP,GA!!!F283!A!!!!
S!A_HSC_ISET!R1D13!2!@baseboard_fab2_lib.baseboard_fab2(sch_1):page199_i84@mstr_discrete.res(chips)!RES_0402-90.9K,1%,1/16W,CHIP,GA!!!F283!B!!!!
S!VR_PVCCIO_CPU0_PH1_SW!L7C2!1!@baseboard_fab2_lib.baseboard_fab2(sch_1):page212_i25@mstr_discrete.inductor(chips)!INDUCTOR_SM-150NH,IND,D92183-0A!!!F2083!INA!!!!
S!PVCCIO_CPU0!L7C2!2!@baseboard_fab2_lib.baseboard_fab2(sch_1):page212_i25@mstr_discrete.inductor(chips)!INDUCTOR_SM-150NH,IND,D92183-0A!!!F2083!INB!!!!
S!VR_PVCCIO_CPU1_PH1_SW!L4E2!1!@baseboard_fab2_lib.baseboard_fab2(sch_1):page214_i67@mstr_discrete.inductor(chips)!INDUCTOR_SM-150NH,IND,D92183-0A!!!F2084!INA!!!!
S!PVCCIO_CPU1!L4E2!2!@baseboard_fab2_lib.baseboard_fab2(sch_1):page214_i67@mstr_discrete.inductor(chips)!INDUCTOR_SM-150NH,IND,D92183-0A!!!F2084!INB!!!!
S!P12V_STBY!C2P10!1!@baseboard_fab2_lib.baseboard_fab2(sch_1):page188_i41@mstr_discrete.cap(chips)!CAP_1206LF-22UF,16V,10%,X6S,D3A!!!F2285!A!!!!
S!GND!C2P10!2!@baseboard_fab2_lib.baseboard_fab2(sch_1):page188_i41@mstr_discrete.cap(chips)!CAP_1206LF-22UF,16V,10%,X6S,D3A!!!F2285!B!!!!
S!VR_FET_SW_P12V_STBY_P3V3_STBY!C8E10!1!@baseboard_fab2_lib.baseboard_fab2(sch_1):page240_i137@mstr_discrete.cap(chips)!CAP_1206LF-22UF,16V,10%,X6S,D3A!!!F2283!A!!!!
S!GND!C8E10!2!@baseboard_fab2_lib.baseboard_fab2(sch_1):page240_i137@mstr_discrete.cap(chips)!CAP_1206LF-22UF,16V,10%,X6S,D3A!!!F2283!B!!!!
S!VR_FET_SW_P5V_STBY_PVIN!C7E11!1!@baseboard_fab2_lib.baseboard_fab2(sch_1):page241_i39@mstr_discrete.cap(chips)!CAP_1206LF-22UF,16V,10%,X6S,D3A!!!F2284!A!!!!
S!GND!C7E11!2!@baseboard_fab2_lib.baseboard_fab2(sch_1):page241_i39@mstr_discrete.cap(chips)!CAP_1206LF-22UF,16V,10%,X6S,D3A!!!F2284!B!!!!
S!P5V_HDD_SATA!J2L1!1!@baseboard_fab2_lib.baseboard_fab2(sch_1):page172_i53@mstr_conn.conn4_h73295001(chips)!CONN4_H73295001_PIP-EMPTY,H732A!!!F2243!IO1!!!!
S!GND!J2L1!2!@baseboard_fab2_lib.baseboard_fab2(sch_1):page172_i53@mstr_conn.conn4_h73295001(chips)!CONN4_H73295001_PIP-EMPTY,H732A!!!F2243!IO2!!!!
S!GND!J2L1!3!@baseboard_fab2_lib.baseboard_fab2(sch_1):page172_i53@mstr_conn.conn4_h73295001(chips)!CONN4_H73295001_PIP-EMPTY,H732A!!!F2243!IO3!!!!
S!P12V_HDD_SATA!J2L1!4!@baseboard_fab2_lib.baseboard_fab2(sch_1):page172_i53@mstr_conn.conn4_h73295001(chips)!CONN4_H73295001_PIP-EMPTY,H732A!!!F2243!IO4!!!!
S!M_A_MA<0>!J4G1!79!@baseboard_fab2_lib.baseboard_fab2(sch_1):page43_i1@mstr_sconn.sconn288_h44441004(chips)!SCONN288_H44441004_PIP-SCONN,HA!!!F148!A0!!!!
S!M_A_MA<1>!J4G1!72!@baseboard_fab2_lib.baseboard_fab2(sch_1):page43_i1@mstr_sconn.sconn288_h44441004(chips)!SCONN288_H44441004_PIP-SCONN,HA!!!F148!A1!!!!
S!M_A_MA<10>!J4G1!225!@baseboard_fab2_lib.baseboard_fab2(sch_1):page43_i1@mstr_sconn.sconn288_h44441004(chips)!SCONN288_H44441004_PIP-SCONN,HA!!!F148!A10!!!!
S!M_A_MA<11>!J4G1!210!@baseboard_fab2_lib.baseboard_fab2(sch_1):page43_i1@mstr_sconn.sconn288_h44441004(chips)!SCONN288_H44441004_PIP-SCONN,HA!!!F148!A11!!!!
S!M_A_MA<12>!J4G1!65!@baseboard_fab2_lib.baseboard_fab2(sch_1):page43_i1@mstr_sconn.sconn288_h44441004(chips)!SCONN288_H44441004_PIP-SCONN,HA!!!F148!A12!!!!
S!M_A_MA<13>!J4G1!232!@baseboard_fab2_lib.baseboard_fab2(sch_1):page43_i1@mstr_sconn.sconn288_h44441004(chips)!SCONN288_H44441004_PIP-SCONN,HA!!!F148!A13!!!!
S!M_A_MA<14>!J4G1!228!@baseboard_fab2_lib.baseboard_fab2(sch_1):page43_i1@mstr_sconn.sconn288_h44441004(chips)!SCONN288_H44441004_PIP-SCONN,HA!!!F148!A14_WE_N!!!!
S!M_A_MA<15>!J4G1!86!@baseboard_fab2_lib.baseboard_fab2(sch_1):page43_i1@mstr_sconn.sconn288_h44441004(chips)!SCONN288_H44441004_PIP-SCONN,HA!!!F148!A15_CAS_N!!!!
S!M_A_MA<16>!J4G1!82!@baseboard_fab2_lib.baseboard_fab2(sch_1):page43_i1@mstr_sconn.sconn288_h44441004(chips)!SCONN288_H44441004_PIP-SCONN,HA!!!F148!A16_RAS_N!!!!
S!M_A_MA<17>!J4G1!234!@baseboard_fab2_lib.baseboard_fab2(sch_1):page43_i1@mstr_sconn.sconn288_h44441004(chips)!SCONN288_H44441004_PIP-SCONN,HA!!!F148!A17!!!!
S!M_A_MA<2>!J4G1!216!@baseboard_fab2_lib.baseboard_fab2(sch_1):page43_i1@mstr_sconn.sconn288_h44441004(chips)!SCONN288_H44441004_PIP-SCONN,HA!!!F148!A2!!!!
S!M_A_MA<3>!J4G1!71!@baseboard_fab2_lib.baseboard_fab2(sch_1):page43_i1@mstr_sconn.sconn288_h44441004(chips)!SCONN288_H44441004_PIP-SCONN,HA!!!F148!A3!!!!
S!M_A_MA<4>!J4G1!214!@baseboard_fab2_lib.baseboard_fab2(sch_1):page43_i1@mstr_sconn.sconn288_h44441004(chips)!SCONN288_H44441004_PIP-SCONN,HA!!!F148!A4!!!!
S!M_A_MA<5>!J4G1!213!@baseboard_fab2_lib.baseboard_fab2(sch_1):page43_i1@mstr_sconn.sconn288_h44441004(chips)!SCONN288_H44441004_PIP-SCONN,HA!!!F148!A5!!!!
S!M_A_MA<6>!J4G1!69!@baseboard_fab2_lib.baseboard_fab2(sch_1):page43_i1@mstr_sconn.sconn288_h44441004(chips)!SCONN288_H44441004_PIP-SCONN,HA!!!F148!A6!!!!
S!M_A_MA<7>!J4G1!211!@baseboard_fab2_lib.baseboard_fab2(sch_1):page43_i1@mstr_sconn.sconn288_h44441004(chips)!SCONN288_H44441004_PIP-SCONN,HA!!!F148!A7!!!!
S!M_A_MA<8>!J4G1!68!@baseboard_fab2_lib.baseboard_fab2(sch_1):page43_i1@mstr_sconn.sconn288_h44441004(chips)!SCONN288_H44441004_PIP-SCONN,HA!!!F148!A8!!!!
S!M_A_MA<9>!J4G1!66!@baseboard_fab2_lib.baseboard_fab2(sch_1):page43_i1@mstr_sconn.sconn288_h44441004(chips)!SCONN288_H44441004_PIP-SCONN,HA!!!F148!A9!!!!
S!M_A_ACT_N!J4G1!62!@baseboard_fab2_lib.baseboard_fab2(sch_1):page43_i1@mstr_sconn.sconn288_h44441004(chips)!SCONN288_H44441004_PIP-SCONN,HA!!!F148!ACT_N!!!!
S!M_A_ALERT_N!J4G1!208!@baseboard_fab2_lib.baseboard_fab2(sch_1):page43_i1@mstr_sconn.sconn288_h44441004(chips)!SCONN288_H44441004_PIP-SCONN,HA!!!F148!ALERT_N!!!!
S!M_A_BA<0>!J4G1!81!@baseboard_fab2_lib.baseboard_fab2(sch_1):page43_i1@mstr_sconn.sconn288_h44441004(chips)!SCONN288_H44441004_PIP-SCONN,HA!!!F148!BA(0)!!!!
S!M_A_BA<1>!J4G1!224!@baseboard_fab2_lib.baseboard_fab2(sch_1):page43_i1@mstr_sconn.sconn288_h44441004(chips)!SCONN288_H44441004_PIP-SCONN,HA!!!F148!BA(1)!!!!
S!M_A_BG<0>!J4G1!63!@baseboard_fab2_lib.baseboard_fab2(sch_1):page43_i1@mstr_sconn.sconn288_h44441004(chips)!SCONN288_H44441004_PIP-SCONN,HA!!!F148!BG(0)!!!!
S!M_A_BG<1>!J4G1!207!@baseboard_fab2_lib.baseboard_fab2(sch_1):page43_i1@mstr_sconn.sconn288_h44441004(chips)!SCONN288_H44441004_PIP-SCONN,HA!!!F148!BG(1)!!!!
S!M_A_C<2>!J4G1!235!@baseboard_fab2_lib.baseboard_fab2(sch_1):page43_i1@mstr_sconn.sconn288_h44441004(chips)!SCONN288_H44441004_PIP-SCONN,HA!!!F148!C(2)!!!!
S!M_A_ECC<1>!J4G1!49!@baseboard_fab2_lib.baseboard_fab2(sch_1):page43_i1@mstr_sconn.sconn288_h44441004(chips)!SCONN288_H44441004_PIP-SCONN,HA!!!F148!CB(0)!!!!
S!M_A_ECC<0>!J4G1!194!@baseboard_fab2_lib.baseboard_fab2(sch_1):page43_i1@mstr_sconn.sconn288_h44441004(chips)!SCONN288_H44441004_PIP-SCONN,HA!!!F148!CB(1)!!!!
S!M_A_ECC<3>!J4G1!56!@baseboard_fab2_lib.baseboard_fab2(sch_1):page43_i1@mstr_sconn.sconn288_h44441004(chips)!SCONN288_H44441004_PIP-SCONN,HA!!!F148!CB(2)!!!!
S!M_A_ECC<2>!J4G1!201!@baseboard_fab2_lib.baseboard_fab2(sch_1):page43_i1@mstr_sconn.sconn288_h44441004(chips)!SCONN288_H44441004_PIP-SCONN,HA!!!F148!CB(3)!!!!
S!M_A_ECC<5>!J4G1!47!@baseboard_fab2_lib.baseboard_fab2(sch_1):page43_i1@mstr_sconn.sconn288_h44441004(chips)!SCONN288_H44441004_PIP-SCONN,HA!!!F148!CB(4)!!!!
S!M_A_ECC<4>!J4G1!192!@baseboard_fab2_lib.baseboard_fab2(sch_1):page43_i1@mstr_sconn.sconn288_h44441004(chips)!SCONN288_H44441004_PIP-SCONN,HA!!!F148!CB(5)!!!!
S!M_A_ECC<7>!J4G1!54!@baseboard_fab2_lib.baseboard_fab2(sch_1):page43_i1@mstr_sconn.sconn288_h44441004(chips)!SCONN288_H44441004_PIP-SCONN,HA!!!F148!CB(6)!!!!
S!M_A_ECC<6>!J4G1!199!@baseboard_fab2_lib.baseboard_fab2(sch_1):page43_i1@mstr_sconn.sconn288_h44441004(chips)!SCONN288_H44441004_PIP-SCONN,HA!!!F148!CB(7)!!!!
S!M_A_CLK_DN<0>!J4G1!75!@baseboard_fab2_lib.baseboard_fab2(sch_1):page43_i1@mstr_sconn.sconn288_h44441004(chips)!SCONN288_H44441004_PIP-SCONN,HA!!!F148!CK0N!!!!
S!M_A_CLK_DP<0>!J4G1!74!@baseboard_fab2_lib.baseboard_fab2(sch_1):page43_i1@mstr_sconn.sconn288_h44441004(chips)!SCONN288_H44441004_PIP-SCONN,HA!!!F148!CK0P!!!!
S!M_A_CLK_DN<1>!J4G1!219!@baseboard_fab2_lib.baseboard_fab2(sch_1):page43_i1@mstr_sconn.sconn288_h44441004(chips)!SCONN288_H44441004_PIP-SCONN,HA!!!F148!CK1N!!!!
S!M_A_CLK_DP<1>!J4G1!218!@baseboard_fab2_lib.baseboard_fab2(sch_1):page43_i1@mstr_sconn.sconn288_h44441004(chips)!SCONN288_H44441004_PIP-SCONN,HA!!!F148!CK1P!!!!
S!M_A_CKE<0>!J4G1!60!@baseboard_fab2_lib.baseboard_fab2(sch_1):page43_i1@mstr_sconn.sconn288_h44441004(chips)!SCONN288_H44441004_PIP-SCONN,HA!!!F148!CKE(0)!!!!
S!M_A_CKE<1>!J4G1!203!@baseboard_fab2_lib.baseboard_fab2(sch_1):page43_i1@mstr_sconn.sconn288_h44441004(chips)!SCONN288_H44441004_PIP-SCONN,HA!!!F148!CKE(1)!!!!
S!M_A_DQ<1>!J4G1!5!@baseboard_fab2_lib.baseboard_fab2(sch_1):page43_i1@mstr_sconn.sconn288_h44441004(chips)!SCONN288_H44441004_PIP-SCONN,HA!!!F148!DQ(0)!!!!
S!M_A_DQ<11>!J4G1!23!@baseboard_fab2_lib.baseboard_fab2(sch_1):page43_i1@mstr_sconn.sconn288_h44441004(chips)!SCONN288_H44441004_PIP-SCONN,HA!!!F148!DQ(10)!!!!
S!M_A_DQ<10>!J4G1!168!@baseboard_fab2_lib.baseboard_fab2(sch_1):page43_i1@mstr_sconn.sconn288_h44441004(chips)!SCONN288_H44441004_PIP-SCONN,HA!!!F148!DQ(11)!!!!
S!M_A_DQ<13>!J4G1!14!@baseboard_fab2_lib.baseboard_fab2(sch_1):page43_i1@mstr_sconn.sconn288_h44441004(chips)!SCONN288_H44441004_PIP-SCONN,HA!!!F148!DQ(12)!!!!
S!M_A_DQ<12>!J4G1!159!@baseboard_fab2_lib.baseboard_fab2(sch_1):page43_i1@mstr_sconn.sconn288_h44441004(chips)!SCONN288_H44441004_PIP-SCONN,HA!!!F148!DQ(13)!!!!
S!M_A_DQ<15>!J4G1!21!@baseboard_fab2_lib.baseboard_fab2(sch_1):page43_i1@mstr_sconn.sconn288_h44441004(chips)!SCONN288_H44441004_PIP-SCONN,HA!!!F148!DQ(14)!!!!
S!M_A_DQ<14>!J4G1!166!@baseboard_fab2_lib.baseboard_fab2(sch_1):page43_i1@mstr_sconn.sconn288_h44441004(chips)!SCONN288_H44441004_PIP-SCONN,HA!!!F148!DQ(15)!!!!
S!M_A_DQ<17>!J4G1!27!@baseboard_fab2_lib.baseboard_fab2(sch_1):page43_i1@mstr_sconn.sconn288_h44441004(chips)!SCONN288_H44441004_PIP-SCONN,HA!!!F148!DQ(16)!!!!
S!M_A_DQ<16>!J4G1!172!@baseboard_fab2_lib.baseboard_fab2(sch_1):page43_i1@mstr_sconn.sconn288_h44441004(chips)!SCONN288_H44441004_PIP-SCONN,HA!!!F148!DQ(17)!!!!
S!M_A_DQ<19>!J4G1!34!@baseboard_fab2_lib.baseboard_fab2(sch_1):page43_i1@mstr_sconn.sconn288_h44441004(chips)!SCONN288_H44441004_PIP-SCONN,HA!!!F148!DQ(18)!!!!
S!M_A_DQ<18>!J4G1!179!@baseboard_fab2_lib.baseboard_fab2(sch_1):page43_i1@mstr_sconn.sconn288_h44441004(chips)!SCONN288_H44441004_PIP-SCONN,HA!!!F148!DQ(19)!!!!
S!M_A_DQ<0>!J4G1!150!@baseboard_fab2_lib.baseboard_fab2(sch_1):page43_i1@mstr_sconn.sconn288_h44441004(chips)!SCONN288_H44441004_PIP-SCONN,HA!!!F148!DQ(1)!!!!
S!M_A_DQ<21>!J4G1!25!@baseboard_fab2_lib.baseboard_fab2(sch_1):page43_i1@mstr_sconn.sconn288_h44441004(chips)!SCONN288_H44441004_PIP-SCONN,HA!!!F148!DQ(20)!!!!
S!M_A_DQ<20>!J4G1!170!@baseboard_fab2_lib.baseboard_fab2(sch_1):page43_i1@mstr_sconn.sconn288_h44441004(chips)!SCONN288_H44441004_PIP-SCONN,HA!!!F148!DQ(21)!!!!
S!M_A_DQ<23>!J4G1!32!@baseboard_fab2_lib.baseboard_fab2(sch_1):page43_i1@mstr_sconn.sconn288_h44441004(chips)!SCONN288_H44441004_PIP-SCONN,HA!!!F148!DQ(22)!!!!
S!M_A_DQ<22>!J4G1!177!@baseboard_fab2_lib.baseboard_fab2(sch_1):page43_i1@mstr_sconn.sconn288_h44441004(chips)!SCONN288_H44441004_PIP-SCONN,HA!!!F148!DQ(23)!!!!
S!M_A_DQ<25>!J4G1!38!@baseboard_fab2_lib.baseboard_fab2(sch_1):page43_i1@mstr_sconn.sconn288_h44441004(chips)!SCONN288_H44441004_PIP-SCONN,HA!!!F148!DQ(24)!!!!
S!M_A_DQ<24>!J4G1!183!@baseboard_fab2_lib.baseboard_fab2(sch_1):page43_i1@mstr_sconn.sconn288_h44441004(chips)!SCONN288_H44441004_PIP-SCONN,HA!!!F148!DQ(25)!!!!
S!M_A_DQ<27>!J4G1!45!@baseboard_fab2_lib.baseboard_fab2(sch_1):page43_i1@mstr_sconn.sconn288_h44441004(chips)!SCONN288_H44441004_PIP-SCONN,HA!!!F148!DQ(26)!!!!
S!M_A_DQ<26>!J4G1!190!@baseboard_fab2_lib.baseboard_fab2(sch_1):page43_i1@mstr_sconn.sconn288_h44441004(chips)!SCONN288_H44441004_PIP-SCONN,HA!!!F148!DQ(27)!!!!
S!M_A_DQ<29>!J4G1!36!@baseboard_fab2_lib.baseboard_fab2(sch_1):page43_i1@mstr_sconn.sconn288_h44441004(chips)!SCONN288_H44441004_PIP-SCONN,HA!!!F148!DQ(28)!!!!
S!M_A_DQ<28>!J4G1!181!@baseboard_fab2_lib.baseboard_fab2(sch_1):page43_i1@mstr_sconn.sconn288_h44441004(chips)!SCONN288_H44441004_PIP-SCONN,HA!!!F148!DQ(29)!!!!
S!M_A_DQ<3>!J4G1!12!@baseboard_fab2_lib.baseboard_fab2(sch_1):page43_i1@mstr_sconn.sconn288_h44441004(chips)!SCONN288_H44441004_PIP-SCONN,HA!!!F148!DQ(2)!!!!
S!M_A_DQ<31>!J4G1!43!@baseboard_fab2_lib.baseboard_fab2(sch_1):page43_i1@mstr_sconn.sconn288_h44441004(chips)!SCONN288_H44441004_PIP-SCONN,HA!!!F148!DQ(30)!!!!
S!M_A_DQ<30>!J4G1!188!@baseboard_fab2_lib.baseboard_fab2(sch_1):page43_i1@mstr_sconn.sconn288_h44441004(chips)!SCONN288_H44441004_PIP-SCONN,HA!!!F148!DQ(31)!!!!
S!M_A_DQ<33>!J4G1!97!@baseboard_fab2_lib.baseboard_fab2(sch_1):page43_i1@mstr_sconn.sconn288_h44441004(chips)!SCONN288_H44441004_PIP-SCONN,HA!!!F148!DQ(32)!!!!
S!M_A_DQ<32>!J4G1!242!@baseboard_fab2_lib.baseboard_fab2(sch_1):page43_i1@mstr_sconn.sconn288_h44441004(chips)!SCONN288_H44441004_PIP-SCONN,HA!!!F148!DQ(33)!!!!
S!M_A_DQ<35>!J4G1!104!@baseboard_fab2_lib.baseboard_fab2(sch_1):page43_i1@mstr_sconn.sconn288_h44441004(chips)!SCONN288_H44441004_PIP-SCONN,HA!!!F148!DQ(34)!!!!
S!M_A_DQ<34>!J4G1!249!@baseboard_fab2_lib.baseboard_fab2(sch_1):page43_i1@mstr_sconn.sconn288_h44441004(chips)!SCONN288_H44441004_PIP-SCONN,HA!!!F148!DQ(35)!!!!
S!M_A_DQ<37>!J4G1!95!@baseboard_fab2_lib.baseboard_fab2(sch_1):page43_i1@mstr_sconn.sconn288_h44441004(chips)!SCONN288_H44441004_PIP-SCONN,HA!!!F148!DQ(36)!!!!
S!M_A_DQ<36>!J4G1!240!@baseboard_fab2_lib.baseboard_fab2(sch_1):page43_i1@mstr_sconn.sconn288_h44441004(chips)!SCONN288_H44441004_PIP-SCONN,HA!!!F148!DQ(37)!!!!
S!M_A_DQ<39>!J4G1!102!@baseboard_fab2_lib.baseboard_fab2(sch_1):page43_i1@mstr_sconn.sconn288_h44441004(chips)!SCONN288_H44441004_PIP-SCONN,HA!!!F148!DQ(38)!!!!
S!M_A_DQ<38>!J4G1!247!@baseboard_fab2_lib.baseboard_fab2(sch_1):page43_i1@mstr_sconn.sconn288_h44441004(chips)!SCONN288_H44441004_PIP-SCONN,HA!!!F148!DQ(39)!!!!
S!M_A_DQ<2>!J4G1!157!@baseboard_fab2_lib.baseboard_fab2(sch_1):page43_i1@mstr_sconn.sconn288_h44441004(chips)!SCONN288_H44441004_PIP-SCONN,HA!!!F148!DQ(3)!!!!
S!M_A_DQ<41>!J4G1!108!@baseboard_fab2_lib.baseboard_fab2(sch_1):page43_i1@mstr_sconn.sconn288_h44441004(chips)!SCONN288_H44441004_PIP-SCONN,HA!!!F148!DQ(40)!!!!
S!M_A_DQ<40>!J4G1!253!@baseboard_fab2_lib.baseboard_fab2(sch_1):page43_i1@mstr_sconn.sconn288_h44441004(chips)!SCONN288_H44441004_PIP-SCONN,HA!!!F148!DQ(41)!!!!
S!M_A_DQ<43>!J4G1!115!@baseboard_fab2_lib.baseboard_fab2(sch_1):page43_i1@mstr_sconn.sconn288_h44441004(chips)!SCONN288_H44441004_PIP-SCONN,HA!!!F148!DQ(42)!!!!
S!M_A_DQ<42>!J4G1!260!@baseboard_fab2_lib.baseboard_fab2(sch_1):page43_i1@mstr_sconn.sconn288_h44441004(chips)!SCONN288_H44441004_PIP-SCONN,HA!!!F148!DQ(43)!!!!
S!M_A_DQ<45>!J4G1!106!@baseboard_fab2_lib.baseboard_fab2(sch_1):page43_i1@mstr_sconn.sconn288_h44441004(chips)!SCONN288_H44441004_PIP-SCONN,HA!!!F148!DQ(44)!!!!
S!M_A_DQ<44>!J4G1!251!@baseboard_fab2_lib.baseboard_fab2(sch_1):page43_i1@mstr_sconn.sconn288_h44441004(chips)!SCONN288_H44441004_PIP-SCONN,HA!!!F148!DQ(45)!!!!
S!M_A_DQ<47>!J4G1!113!@baseboard_fab2_lib.baseboard_fab2(sch_1):page43_i1@mstr_sconn.sconn288_h44441004(chips)!SCONN288_H44441004_PIP-SCONN,HA!!!F148!DQ(46)!!!!
S!M_A_DQ<46>!J4G1!258!@baseboard_fab2_lib.baseboard_fab2(sch_1):page43_i1@mstr_sconn.sconn288_h44441004(chips)!SCONN288_H44441004_PIP-SCONN,HA!!!F148!DQ(47)!!!!
S!M_A_DQ<49>!J4G1!119!@baseboard_fab2_lib.baseboard_fab2(sch_1):page43_i1@mstr_sconn.sconn288_h44441004(chips)!SCONN288_H44441004_PIP-SCONN,HA!!!F148!DQ(48)!!!!
S!M_A_DQ<48>!J4G1!264!@baseboard_fab2_lib.baseboard_fab2(sch_1):page43_i1@mstr_sconn.sconn288_h44441004(chips)!SCONN288_H44441004_PIP-SCONN,HA!!!F148!DQ(49)!!!!
S!M_A_DQ<5>!J4G1!3!@baseboard_fab2_lib.baseboard_fab2(sch_1):page43_i1@mstr_sconn.sconn288_h44441004(chips)!SCONN288_H44441004_PIP-SCONN,HA!!!F148!DQ(4)!!!!
S!M_A_DQ<51>!J4G1!126!@baseboard_fab2_lib.baseboard_fab2(sch_1):page43_i1@mstr_sconn.sconn288_h44441004(chips)!SCONN288_H44441004_PIP-SCONN,HA!!!F148!DQ(50)!!!!
S!M_A_DQ<50>!J4G1!271!@baseboard_fab2_lib.baseboard_fab2(sch_1):page43_i1@mstr_sconn.sconn288_h44441004(chips)!SCONN288_H44441004_PIP-SCONN,HA!!!F148!DQ(51)!!!!
S!M_A_DQ<53>!J4G1!117!@baseboard_fab2_lib.baseboard_fab2(sch_1):page43_i1@mstr_sconn.sconn288_h44441004(chips)!SCONN288_H44441004_PIP-SCONN,HA!!!F148!DQ(52)!!!!
S!M_A_DQ<52>!J4G1!262!@baseboard_fab2_lib.baseboard_fab2(sch_1):page43_i1@mstr_sconn.sconn288_h44441004(chips)!SCONN288_H44441004_PIP-SCONN,HA!!!F148!DQ(53)!!!!
S!M_A_DQ<55>!J4G1!124!@baseboard_fab2_lib.baseboard_fab2(sch_1):page43_i1@mstr_sconn.sconn288_h44441004(chips)!SCONN288_H44441004_PIP-SCONN,HA!!!F148!DQ(54)!!!!
S!M_A_DQ<54>!J4G1!269!@baseboard_fab2_lib.baseboard_fab2(sch_1):page43_i1@mstr_sconn.sconn288_h44441004(chips)!SCONN288_H44441004_PIP-SCONN,HA!!!F148!DQ(55)!!!!
S!M_A_DQ<57>!J4G1!130!@baseboard_fab2_lib.baseboard_fab2(sch_1):page43_i1@mstr_sconn.sconn288_h44441004(chips)!SCONN288_H44441004_PIP-SCONN,HA!!!F148!DQ(56)!!!!
S!M_A_DQ<56>!J4G1!275!@baseboard_fab2_lib.baseboard_fab2(sch_1):page43_i1@mstr_sconn.sconn288_h44441004(chips)!SCONN288_H44441004_PIP-SCONN,HA!!!F148!DQ(57)!!!!
S!M_A_DQ<59>!J4G1!137!@baseboard_fab2_lib.baseboard_fab2(sch_1):page43_i1@mstr_sconn.sconn288_h44441004(chips)!SCONN288_H44441004_PIP-SCONN,HA!!!F148!DQ(58)!!!!
S!M_A_DQ<58>!J4G1!282!@baseboard_fab2_lib.baseboard_fab2(sch_1):page43_i1@mstr_sconn.sconn288_h44441004(chips)!SCONN288_H44441004_PIP-SCONN,HA!!!F148!DQ(59)!!!!
S!M_A_DQ<4>!J4G1!148!@baseboard_fab2_lib.baseboard_fab2(sch_1):page43_i1@mstr_sconn.sconn288_h44441004(chips)!SCONN288_H44441004_PIP-SCONN,HA!!!F148!DQ(5)!!!!
S!M_A_DQ<61>!J4G1!128!@baseboard_fab2_lib.baseboard_fab2(sch_1):page43_i1@mstr_sconn.sconn288_h44441004(chips)!SCONN288_H44441004_PIP-SCONN,HA!!!F148!DQ(60)!!!!
S!M_A_DQ<60>!J4G1!273!@baseboard_fab2_lib.baseboard_fab2(sch_1):page43_i1@mstr_sconn.sconn288_h44441004(chips)!SCONN288_H44441004_PIP-SCONN,HA!!!F148!DQ(61)!!!!
S!M_A_DQ<63>!J4G1!135!@baseboard_fab2_lib.baseboard_fab2(sch_1):page43_i1@mstr_sconn.sconn288_h44441004(chips)!SCONN288_H44441004_PIP-SCONN,HA!!!F148!DQ(62)!!!!
S!M_A_DQ<62>!J4G1!280!@baseboard_fab2_lib.baseboard_fab2(sch_1):page43_i1@mstr_sconn.sconn288_h44441004(chips)!SCONN288_H44441004_PIP-SCONN,HA!!!F148!DQ(63)!!!!
S!M_A_DQ<7>!J4G1!10!@baseboard_fab2_lib.baseboard_fab2(sch_1):page43_i1@mstr_sconn.sconn288_h44441004(chips)!SCONN288_H44441004_PIP-SCONN,HA!!!F148!DQ(6)!!!!
S!M_A_DQ<6>!J4G1!155!@baseboard_fab2_lib.baseboard_fab2(sch_1):page43_i1@mstr_sconn.sconn288_h44441004(chips)!SCONN288_H44441004_PIP-SCONN,HA!!!F148!DQ(7)!!!!
S!M_A_DQ<9>!J4G1!16!@baseboard_fab2_lib.baseboard_fab2(sch_1):page43_i1@mstr_sconn.sconn288_h44441004(chips)!SCONN288_H44441004_PIP-SCONN,HA!!!F148!DQ(8)!!!!
S!M_A_DQ<8>!J4G1!161!@baseboard_fab2_lib.baseboard_fab2(sch_1):page43_i1@mstr_sconn.sconn288_h44441004(chips)!SCONN288_H44441004_PIP-SCONN,HA!!!F148!DQ(9)!!!!
S!FM_DIMM_EVENT_COD_N!J4G1!78!@baseboard_fab2_lib.baseboard_fab2(sch_1):page43_i1@mstr_sconn.sconn288_h44441004(chips)!SCONN288_H44441004_PIP-SCONN,HA!!!F148!EVENT_N!!!!
S!M_A_ODT<0>!J4G1!87!@baseboard_fab2_lib.baseboard_fab2(sch_1):page43_i1@mstr_sconn.sconn288_h44441004(chips)!SCONN288_H44441004_PIP-SCONN,HA!!!F148!ODT(0)!!!!
S!M_A_ODT<1>!J4G1!91!@baseboard_fab2_lib.baseboard_fab2(sch_1):page43_i1@mstr_sconn.sconn288_h44441004(chips)!SCONN288_H44441004_PIP-SCONN,HA!!!F148!ODT(1)!!!!
S!M_A_PAR!J4G1!222!@baseboard_fab2_lib.baseboard_fab2(sch_1):page43_i1@mstr_sconn.sconn288_h44441004(chips)!SCONN288_H44441004_PIP-SCONN,HA!!!F148!PAR!!!!
S!M_ABC_RST_N!J4G1!58!@baseboard_fab2_lib.baseboard_fab2(sch_1):page43_i1@mstr_sconn.sconn288_h44441004(chips)!SCONN288_H44441004_PIP-SCONN,HA!!!F148!RESET_N!!!!
S!TP_CH_A_DIMM_A0_RFU_0!J4G1!205!@baseboard_fab2_lib.baseboard_fab2(sch_1):page43_i1@mstr_sconn.sconn288_h44441004(chips)!SCONN288_H44441004_PIP-SCONN,HA!!!F148!RFU(0)!!!!
S!TP_CH_A_DIMM_A0_RFU_1!J4G1!227!@baseboard_fab2_lib.baseboard_fab2(sch_1):page43_i1@mstr_sconn.sconn288_h44441004(chips)!SCONN288_H44441004_PIP-SCONN,HA!!!F148!RFU(1)!!!!
S!TP_CH_A_DIMM_A0_RFU_2!J4G1!144!@baseboard_fab2_lib.baseboard_fab2(sch_1):page43_i1@mstr_sconn.sconn288_h44441004(chips)!SCONN288_H44441004_PIP-SCONN,HA!!!F148!RFU(2)!!!!
S!M_A_CS_N<0>!J4G1!84!@baseboard_fab2_lib.baseboard_fab2(sch_1):page43_i1@mstr_sconn.sconn288_h44441004(chips)!SCONN288_H44441004_PIP-SCONN,HA!!!F148!S0_N!!!!
S!M_A_CS_N<1>!J4G1!89!@baseboard_fab2_lib.baseboard_fab2(sch_1):page43_i1@mstr_sconn.sconn288_h44441004(chips)!SCONN288_H44441004_PIP-SCONN,HA!!!F148!S1_N!!!!
S!M_A_CS_N<2>!J4G1!93!@baseboard_fab2_lib.baseboard_fab2(sch_1):page43_i1@mstr_sconn.sconn288_h44441004(chips)!SCONN288_H44441004_PIP-SCONN,HA!!!F148!S2_N_C(0)!!!!
S!M_A_CS_N<3>!J4G1!237!@baseboard_fab2_lib.baseboard_fab2(sch_1):page43_i1@mstr_sconn.sconn288_h44441004(chips)!SCONN288_H44441004_PIP-SCONN,HA!!!F148!S3_N_C(1)!!!!
S!GND!J4G1!139!@baseboard_fab2_lib.baseboard_fab2(sch_1):page43_i1@mstr_sconn.sconn288_h44441004(chips)!SCONN288_H44441004_PIP-SCONN,HA!!!F148!SA(0)!!!!
S!GND!J4G1!140!@baseboard_fab2_lib.baseboard_fab2(sch_1):page43_i1@mstr_sconn.sconn288_h44441004(chips)!SCONN288_H44441004_PIP-SCONN,HA!!!F148!SA(1)!!!!
S!GND!J4G1!238!@baseboard_fab2_lib.baseboard_fab2(sch_1):page43_i1@mstr_sconn.sconn288_h44441004(chips)!SCONN288_H44441004_PIP-SCONN,HA!!!F148!SA(2)!!!!
S!FM_ADR_COMPLETE_ABC_N!J4G1!230!@baseboard_fab2_lib.baseboard_fab2(sch_1):page43_i1@mstr_sconn.sconn288_h44441004(chips)!SCONN288_H44441004_PIP-SCONN,HA!!!F148!SAVE_N_NC!!!!
S!SMB_DDR_ABC_VPP_SCL!J4G1!141!@baseboard_fab2_lib.baseboard_fab2(sch_1):page43_i1@mstr_sconn.sconn288_h44441004(chips)!SCONN288_H44441004_PIP-SCONN,HA!!!F148!SCL!!!!
S!SMB_DDR_ABC_VPP_SDA!J4G1!285!@baseboard_fab2_lib.baseboard_fab2(sch_1):page43_i1@mstr_sconn.sconn288_h44441004(chips)!SCONN288_H44441004_PIP-SCONN,HA!!!F148!SDA!!!!
S!PVPP_ABC!J4G1!284!@baseboard_fab2_lib.baseboard_fab2(sch_1):page43_i1@mstr_sconn.sconn288_h44441004(chips)!SCONN288_H44441004_PIP-SCONN,HA!!!F148!VDDSPD!!!!
S!M_A_VREF!J4G1!146!@baseboard_fab2_lib.baseboard_fab2(sch_1):page43_i1@mstr_sconn.sconn288_h44441004(chips)!SCONN288_H44441004_PIP-SCONN,HA!!!F148!VREFCA!!!!
S!M_A_DQS_DN<0>!J4G1!152!@baseboard_fab2_lib.baseboard_fab2(sch_1):page43_i2@mstr_sconn.sconn288_h44441004(chips)!SCONN288_H44441004_PIP-SCONN,HA!!!F147!DQS0N!!!!
S!M_A_DQS_DP<0>!J4G1!153!@baseboard_fab2_lib.baseboard_fab2(sch_1):page43_i2@mstr_sconn.sconn288_h44441004(chips)!SCONN288_H44441004_PIP-SCONN,HA!!!F147!DQS0P!!!!
S!M_A_DQS_DN<10>!J4G1!19!@baseboard_fab2_lib.baseboard_fab2(sch_1):page43_i2@mstr_sconn.sconn288_h44441004(chips)!SCONN288_H44441004_PIP-SCONN,HA!!!F147!DQS10N!!!!
S!M_A_DQS_DP<10>!J4G1!18!@baseboard_fab2_lib.baseboard_fab2(sch_1):page43_i2@mstr_sconn.sconn288_h44441004(chips)!SCONN288_H44441004_PIP-SCONN,HA!!!F147!DQS10P!!!!
S!M_A_DQS_DN<11>!J4G1!30!@baseboard_fab2_lib.baseboard_fab2(sch_1):page43_i2@mstr_sconn.sconn288_h44441004(chips)!SCONN288_H44441004_PIP-SCONN,HA!!!F147!DQS11N!!!!
S!M_A_DQS_DP<11>!J4G1!29!@baseboard_fab2_lib.baseboard_fab2(sch_1):page43_i2@mstr_sconn.sconn288_h44441004(chips)!SCONN288_H44441004_PIP-SCONN,HA!!!F147!DQS11P!!!!
S!M_A_DQS_DN<12>!J4G1!41!@baseboard_fab2_lib.baseboard_fab2(sch_1):page43_i2@mstr_sconn.sconn288_h44441004(chips)!SCONN288_H44441004_PIP-SCONN,HA!!!F147!DQS12N!!!!
S!M_A_DQS_DP<12>!J4G1!40!@baseboard_fab2_lib.baseboard_fab2(sch_1):page43_i2@mstr_sconn.sconn288_h44441004(chips)!SCONN288_H44441004_PIP-SCONN,HA!!!F147!DQS12P!!!!
S!M_A_DQS_DN<13>!J4G1!100!@baseboard_fab2_lib.baseboard_fab2(sch_1):page43_i2@mstr_sconn.sconn288_h44441004(chips)!SCONN288_H44441004_PIP-SCONN,HA!!!F147!DQS13N!!!!
S!M_A_DQS_DP<13>!J4G1!99!@baseboard_fab2_lib.baseboard_fab2(sch_1):page43_i2@mstr_sconn.sconn288_h44441004(chips)!SCONN288_H44441004_PIP-SCONN,HA!!!F147!DQS13P!!!!
S!M_A_DQS_DN<14>!J4G1!111!@baseboard_fab2_lib.baseboard_fab2(sch_1):page43_i2@mstr_sconn.sconn288_h44441004(chips)!SCONN288_H44441004_PIP-SCONN,HA!!!F147!DQS14N!!!!
S!M_A_DQS_DP<14>!J4G1!110!@baseboard_fab2_lib.baseboard_fab2(sch_1):page43_i2@mstr_sconn.sconn288_h44441004(chips)!SCONN288_H44441004_PIP-SCONN,HA!!!F147!DQS14P!!!!
S!M_A_DQS_DN<15>!J4G1!122!@baseboard_fab2_lib.baseboard_fab2(sch_1):page43_i2@mstr_sconn.sconn288_h44441004(chips)!SCONN288_H44441004_PIP-SCONN,HA!!!F147!DQS15N!!!!
S!M_A_DQS_DP<15>!J4G1!121!@baseboard_fab2_lib.baseboard_fab2(sch_1):page43_i2@mstr_sconn.sconn288_h44441004(chips)!SCONN288_H44441004_PIP-SCONN,HA!!!F147!DQS15P!!!!
S!M_A_DQS_DN<16>!J4G1!133!@baseboard_fab2_lib.baseboard_fab2(sch_1):page43_i2@mstr_sconn.sconn288_h44441004(chips)!SCONN288_H44441004_PIP-SCONN,HA!!!F147!DQS16N!!!!
S!M_A_DQS_DP<16>!J4G1!132!@baseboard_fab2_lib.baseboard_fab2(sch_1):page43_i2@mstr_sconn.sconn288_h44441004(chips)!SCONN288_H44441004_PIP-SCONN,HA!!!F147!DQS16P!!!!
S!M_A_DQS_DN<17>!J4G1!52!@baseboard_fab2_lib.baseboard_fab2(sch_1):page43_i2@mstr_sconn.sconn288_h44441004(chips)!SCONN288_H44441004_PIP-SCONN,HA!!!F147!DQS17N!!!!
S!M_A_DQS_DP<17>!J4G1!51!@baseboard_fab2_lib.baseboard_fab2(sch_1):page43_i2@mstr_sconn.sconn288_h44441004(chips)!SCONN288_H44441004_PIP-SCONN,HA!!!F147!DQS17P!!!!
S!M_A_DQS_DN<1>!J4G1!163!@baseboard_fab2_lib.baseboard_fab2(sch_1):page43_i2@mstr_sconn.sconn288_h44441004(chips)!SCONN288_H44441004_PIP-SCONN,HA!!!F147!DQS1N!!!!
S!M_A_DQS_DP<1>!J4G1!164!@baseboard_fab2_lib.baseboard_fab2(sch_1):page43_i2@mstr_sconn.sconn288_h44441004(chips)!SCONN288_H44441004_PIP-SCONN,HA!!!F147!DQS1P!!!!
S!M_A_DQS_DN<2>!J4G1!174!@baseboard_fab2_lib.baseboard_fab2(sch_1):page43_i2@mstr_sconn.sconn288_h44441004(chips)!SCONN288_H44441004_PIP-SCONN,HA!!!F147!DQS2N!!!!
S!M_A_DQS_DP<2>!J4G1!175!@baseboard_fab2_lib.baseboard_fab2(sch_1):page43_i2@mstr_sconn.sconn288_h44441004(chips)!SCONN288_H44441004_PIP-SCONN,HA!!!F147!DQS2P!!!!
S!M_A_DQS_DN<3>!J4G1!185!@baseboard_fab2_lib.baseboard_fab2(sch_1):page43_i2@mstr_sconn.sconn288_h44441004(chips)!SCONN288_H44441004_PIP-SCONN,HA!!!F147!DQS3N!!!!
S!M_A_DQS_DP<3>!J4G1!186!@baseboard_fab2_lib.baseboard_fab2(sch_1):page43_i2@mstr_sconn.sconn288_h44441004(chips)!SCONN288_H44441004_PIP-SCONN,HA!!!F147!DQS3P!!!!
S!M_A_DQS_DN<4>!J4G1!244!@baseboard_fab2_lib.baseboard_fab2(sch_1):page43_i2@mstr_sconn.sconn288_h44441004(chips)!SCONN288_H44441004_PIP-SCONN,HA!!!F147!DQS4N!!!!
S!M_A_DQS_DP<4>!J4G1!245!@baseboard_fab2_lib.baseboard_fab2(sch_1):page43_i2@mstr_sconn.sconn288_h44441004(chips)!SCONN288_H44441004_PIP-SCONN,HA!!!F147!DQS4P!!!!
S!M_A_DQS_DN<5>!J4G1!255!@baseboard_fab2_lib.baseboard_fab2(sch_1):page43_i2@mstr_sconn.sconn288_h44441004(chips)!SCONN288_H44441004_PIP-SCONN,HA!!!F147!DQS5N!!!!
S!M_A_DQS_DP<5>!J4G1!256!@baseboard_fab2_lib.baseboard_fab2(sch_1):page43_i2@mstr_sconn.sconn288_h44441004(chips)!SCONN288_H44441004_PIP-SCONN,HA!!!F147!DQS5P!!!!
S!M_A_DQS_DN<6>!J4G1!266!@baseboard_fab2_lib.baseboard_fab2(sch_1):page43_i2@mstr_sconn.sconn288_h44441004(chips)!SCONN288_H44441004_PIP-SCONN,HA!!!F147!DQS6N!!!!
S!M_A_DQS_DP<6>!J4G1!267!@baseboard_fab2_lib.baseboard_fab2(sch_1):page43_i2@mstr_sconn.sconn288_h44441004(chips)!SCONN288_H44441004_PIP-SCONN,HA!!!F147!DQS6P!!!!
S!M_A_DQS_DN<7>!J4G1!277!@baseboard_fab2_lib.baseboard_fab2(sch_1):page43_i2@mstr_sconn.sconn288_h44441004(chips)!SCONN288_H44441004_PIP-SCONN,HA!!!F147!DQS7N!!!!
S!M_A_DQS_DP<7>!J4G1!278!@baseboard_fab2_lib.baseboard_fab2(sch_1):page43_i2@mstr_sconn.sconn288_h44441004(chips)!SCONN288_H44441004_PIP-SCONN,HA!!!F147!DQS7P!!!!
S!M_A_DQS_DN<8>!J4G1!196!@baseboard_fab2_lib.baseboard_fab2(sch_1):page43_i2@mstr_sconn.sconn288_h44441004(chips)!SCONN288_H44441004_PIP-SCONN,HA!!!F147!DQS8N!!!!
S!M_A_DQS_DP<8>!J4G1!197!@baseboard_fab2_lib.baseboard_fab2(sch_1):page43_i2@mstr_sconn.sconn288_h44441004(chips)!SCONN288_H44441004_PIP-SCONN,HA!!!F147!DQS8P!!!!
S!M_A_DQS_DN<9>!J4G1!8!@baseboard_fab2_lib.baseboard_fab2(sch_1):page43_i2@mstr_sconn.sconn288_h44441004(chips)!SCONN288_H44441004_PIP-SCONN,HA!!!F147!DQS9N!!!!
S!M_A_DQS_DP<9>!J4G1!7!@baseboard_fab2_lib.baseboard_fab2(sch_1):page43_i2@mstr_sconn.sconn288_h44441004(chips)!SCONN288_H44441004_PIP-SCONN,HA!!!F147!DQS9P!!!!
S!GND!J4G1!283!@baseboard_fab2_lib.baseboard_fab2(sch_1):page43_i259@mstr_sconn.sconn288_h44441004(chips)!SCONN288_H44441004_PIP-SCONN,HA!!!F146!VSS(0)!!!!
S!GND!J4G1!261!@baseboard_fab2_lib.baseboard_fab2(sch_1):page43_i259@mstr_sconn.sconn288_h44441004(chips)!SCONN288_H44441004_PIP-SCONN,HA!!!F146!VSS(10)!!!!
S!GND!J4G1!259!@baseboard_fab2_lib.baseboard_fab2(sch_1):page43_i259@mstr_sconn.sconn288_h44441004(chips)!SCONN288_H44441004_PIP-SCONN,HA!!!F146!VSS(11)!!!!
S!GND!J4G1!257!@baseboard_fab2_lib.baseboard_fab2(sch_1):page43_i259@mstr_sconn.sconn288_h44441004(chips)!SCONN288_H44441004_PIP-SCONN,HA!!!F146!VSS(12)!!!!
S!GND!J4G1!254!@baseboard_fab2_lib.baseboard_fab2(sch_1):page43_i259@mstr_sconn.sconn288_h44441004(chips)!SCONN288_H44441004_PIP-SCONN,HA!!!F146!VSS(13)!!!!
S!GND!J4G1!252!@baseboard_fab2_lib.baseboard_fab2(sch_1):page43_i259@mstr_sconn.sconn288_h44441004(chips)!SCONN288_H44441004_PIP-SCONN,HA!!!F146!VSS(14)!!!!
S!GND!J4G1!250!@baseboard_fab2_lib.baseboard_fab2(sch_1):page43_i259@mstr_sconn.sconn288_h44441004(chips)!SCONN288_H44441004_PIP-SCONN,HA!!!F146!VSS(15)!!!!
S!GND!J4G1!248!@baseboard_fab2_lib.baseboard_fab2(sch_1):page43_i259@mstr_sconn.sconn288_h44441004(chips)!SCONN288_H44441004_PIP-SCONN,HA!!!F146!VSS(16)!!!!
S!GND!J4G1!246!@baseboard_fab2_lib.baseboard_fab2(sch_1):page43_i259@mstr_sconn.sconn288_h44441004(chips)!SCONN288_H44441004_PIP-SCONN,HA!!!F146!VSS(17)!!!!
S!GND!J4G1!243!@baseboard_fab2_lib.baseboard_fab2(sch_1):page43_i259@mstr_sconn.sconn288_h44441004(chips)!SCONN288_H44441004_PIP-SCONN,HA!!!F146!VSS(18)!!!!
S!GND!J4G1!241!@baseboard_fab2_lib.baseboard_fab2(sch_1):page43_i259@mstr_sconn.sconn288_h44441004(chips)!SCONN288_H44441004_PIP-SCONN,HA!!!F146!VSS(19)!!!!
S!GND!J4G1!281!@baseboard_fab2_lib.baseboard_fab2(sch_1):page43_i259@mstr_sconn.sconn288_h44441004(chips)!SCONN288_H44441004_PIP-SCONN,HA!!!F146!VSS(1)!!!!
S!GND!J4G1!239!@baseboard_fab2_lib.baseboard_fab2(sch_1):page43_i259@mstr_sconn.sconn288_h44441004(chips)!SCONN288_H44441004_PIP-SCONN,HA!!!F146!VSS(20)!!!!
S!GND!J4G1!202!@baseboard_fab2_lib.baseboard_fab2(sch_1):page43_i259@mstr_sconn.sconn288_h44441004(chips)!SCONN288_H44441004_PIP-SCONN,HA!!!F146!VSS(21)!!!!
S!GND!J4G1!200!@baseboard_fab2_lib.baseboard_fab2(sch_1):page43_i259@mstr_sconn.sconn288_h44441004(chips)!SCONN288_H44441004_PIP-SCONN,HA!!!F146!VSS(22)!!!!
S!GND!J4G1!198!@baseboard_fab2_lib.baseboard_fab2(sch_1):page43_i259@mstr_sconn.sconn288_h44441004(chips)!SCONN288_H44441004_PIP-SCONN,HA!!!F146!VSS(23)!!!!
S!GND!J4G1!195!@baseboard_fab2_lib.baseboard_fab2(sch_1):page43_i259@mstr_sconn.sconn288_h44441004(chips)!SCONN288_H44441004_PIP-SCONN,HA!!!F146!VSS(24)!!!!
S!GND!J4G1!193!@baseboard_fab2_lib.baseboard_fab2(sch_1):page43_i259@mstr_sconn.sconn288_h44441004(chips)!SCONN288_H44441004_PIP-SCONN,HA!!!F146!VSS(25)!!!!
S!GND!J4G1!191!@baseboard_fab2_lib.baseboard_fab2(sch_1):page43_i259@mstr_sconn.sconn288_h44441004(chips)!SCONN288_H44441004_PIP-SCONN,HA!!!F146!VSS(26)!!!!
S!GND!J4G1!189!@baseboard_fab2_lib.baseboard_fab2(sch_1):page43_i259@mstr_sconn.sconn288_h44441004(chips)!SCONN288_H44441004_PIP-SCONN,HA!!!F146!VSS(27)!!!!
S!GND!J4G1!187!@baseboard_fab2_lib.baseboard_fab2(sch_1):page43_i259@mstr_sconn.sconn288_h44441004(chips)!SCONN288_H44441004_PIP-SCONN,HA!!!F146!VSS(28)!!!!
S!GND!J4G1!184!@baseboard_fab2_lib.baseboard_fab2(sch_1):page43_i259@mstr_sconn.sconn288_h44441004(chips)!SCONN288_H44441004_PIP-SCONN,HA!!!F146!VSS(29)!!!!
S!GND!J4G1!279!@baseboard_fab2_lib.baseboard_fab2(sch_1):page43_i259@mstr_sconn.sconn288_h44441004(chips)!SCONN288_H44441004_PIP-SCONN,HA!!!F146!VSS(2)!!!!
S!GND!J4G1!182!@baseboard_fab2_lib.baseboard_fab2(sch_1):page43_i259@mstr_sconn.sconn288_h44441004(chips)!SCONN288_H44441004_PIP-SCONN,HA!!!F146!VSS(30)!!!!
S!GND!J4G1!180!@baseboard_fab2_lib.baseboard_fab2(sch_1):page43_i259@mstr_sconn.sconn288_h44441004(chips)!SCONN288_H44441004_PIP-SCONN,HA!!!F146!VSS(31)!!!!
S!GND!J4G1!178!@baseboard_fab2_lib.baseboard_fab2(sch_1):page43_i259@mstr_sconn.sconn288_h44441004(chips)!SCONN288_H44441004_PIP-SCONN,HA!!!F146!VSS(32)!!!!
S!GND!J4G1!176!@baseboard_fab2_lib.baseboard_fab2(sch_1):page43_i259@mstr_sconn.sconn288_h44441004(chips)!SCONN288_H44441004_PIP-SCONN,HA!!!F146!VSS(33)!!!!
S!GND!J4G1!173!@baseboard_fab2_lib.baseboard_fab2(sch_1):page43_i259@mstr_sconn.sconn288_h44441004(chips)!SCONN288_H44441004_PIP-SCONN,HA!!!F146!VSS(34)!!!!
S!GND!J4G1!171!@baseboard_fab2_lib.baseboard_fab2(sch_1):page43_i259@mstr_sconn.sconn288_h44441004(chips)!SCONN288_H44441004_PIP-SCONN,HA!!!F146!VSS(35)!!!!
S!GND!J4G1!169!@baseboard_fab2_lib.baseboard_fab2(sch_1):page43_i259@mstr_sconn.sconn288_h44441004(chips)!SCONN288_H44441004_PIP-SCONN,HA!!!F146!VSS(36)!!!!
S!GND!J4G1!167!@baseboard_fab2_lib.baseboard_fab2(sch_1):page43_i259@mstr_sconn.sconn288_h44441004(chips)!SCONN288_H44441004_PIP-SCONN,HA!!!F146!VSS(37)!!!!
S!GND!J4G1!165!@baseboard_fab2_lib.baseboard_fab2(sch_1):page43_i259@mstr_sconn.sconn288_h44441004(chips)!SCONN288_H44441004_PIP-SCONN,HA!!!F146!VSS(38)!!!!
S!GND!J4G1!162!@baseboard_fab2_lib.baseboard_fab2(sch_1):page43_i259@mstr_sconn.sconn288_h44441004(chips)!SCONN288_H44441004_PIP-SCONN,HA!!!F146!VSS(39)!!!!
S!GND!J4G1!276!@baseboard_fab2_lib.baseboard_fab2(sch_1):page43_i259@mstr_sconn.sconn288_h44441004(chips)!SCONN288_H44441004_PIP-SCONN,HA!!!F146!VSS(3)!!!!
S!GND!J4G1!160!@baseboard_fab2_lib.baseboard_fab2(sch_1):page43_i259@mstr_sconn.sconn288_h44441004(chips)!SCONN288_H44441004_PIP-SCONN,HA!!!F146!VSS(40)!!!!
S!GND!J4G1!158!@baseboard_fab2_lib.baseboard_fab2(sch_1):page43_i259@mstr_sconn.sconn288_h44441004(chips)!SCONN288_H44441004_PIP-SCONN,HA!!!F146!VSS(41)!!!!
S!GND!J4G1!156!@baseboard_fab2_lib.baseboard_fab2(sch_1):page43_i259@mstr_sconn.sconn288_h44441004(chips)!SCONN288_H44441004_PIP-SCONN,HA!!!F146!VSS(42)!!!!
S!GND!J4G1!154!@baseboard_fab2_lib.baseboard_fab2(sch_1):page43_i259@mstr_sconn.sconn288_h44441004(chips)!SCONN288_H44441004_PIP-SCONN,HA!!!F146!VSS(43)!!!!
S!GND!J4G1!151!@baseboard_fab2_lib.baseboard_fab2(sch_1):page43_i259@mstr_sconn.sconn288_h44441004(chips)!SCONN288_H44441004_PIP-SCONN,HA!!!F146!VSS(44)!!!!
S!GND!J4G1!149!@baseboard_fab2_lib.baseboard_fab2(sch_1):page43_i259@mstr_sconn.sconn288_h44441004(chips)!SCONN288_H44441004_PIP-SCONN,HA!!!F146!VSS(45)!!!!
S!GND!J4G1!147!@baseboard_fab2_lib.baseboard_fab2(sch_1):page43_i259@mstr_sconn.sconn288_h44441004(chips)!SCONN288_H44441004_PIP-SCONN,HA!!!F146!VSS(46)!!!!
S!GND!J4G1!138!@baseboard_fab2_lib.baseboard_fab2(sch_1):page43_i259@mstr_sconn.sconn288_h44441004(chips)!SCONN288_H44441004_PIP-SCONN,HA!!!F146!VSS(47)!!!!
S!GND!J4G1!136!@baseboard_fab2_lib.baseboard_fab2(sch_1):page43_i259@mstr_sconn.sconn288_h44441004(chips)!SCONN288_H44441004_PIP-SCONN,HA!!!F146!VSS(48)!!!!
S!GND!J4G1!134!@baseboard_fab2_lib.baseboard_fab2(sch_1):page43_i259@mstr_sconn.sconn288_h44441004(chips)!SCONN288_H44441004_PIP-SCONN,HA!!!F146!VSS(49)!!!!
S!GND!J4G1!274!@baseboard_fab2_lib.baseboard_fab2(sch_1):page43_i259@mstr_sconn.sconn288_h44441004(chips)!SCONN288_H44441004_PIP-SCONN,HA!!!F146!VSS(4)!!!!
S!GND!J4G1!131!@baseboard_fab2_lib.baseboard_fab2(sch_1):page43_i259@mstr_sconn.sconn288_h44441004(chips)!SCONN288_H44441004_PIP-SCONN,HA!!!F146!VSS(50)!!!!
S!GND!J4G1!129!@baseboard_fab2_lib.baseboard_fab2(sch_1):page43_i259@mstr_sconn.sconn288_h44441004(chips)!SCONN288_H44441004_PIP-SCONN,HA!!!F146!VSS(51)!!!!
S!GND!J4G1!127!@baseboard_fab2_lib.baseboard_fab2(sch_1):page43_i259@mstr_sconn.sconn288_h44441004(chips)!SCONN288_H44441004_PIP-SCONN,HA!!!F146!VSS(52)!!!!
S!GND!J4G1!125!@baseboard_fab2_lib.baseboard_fab2(sch_1):page43_i259@mstr_sconn.sconn288_h44441004(chips)!SCONN288_H44441004_PIP-SCONN,HA!!!F146!VSS(53)!!!!
S!GND!J4G1!123!@baseboard_fab2_lib.baseboard_fab2(sch_1):page43_i259@mstr_sconn.sconn288_h44441004(chips)!SCONN288_H44441004_PIP-SCONN,HA!!!F146!VSS(54)!!!!
S!GND!J4G1!120!@baseboard_fab2_lib.baseboard_fab2(sch_1):page43_i259@mstr_sconn.sconn288_h44441004(chips)!SCONN288_H44441004_PIP-SCONN,HA!!!F146!VSS(55)!!!!
S!GND!J4G1!118!@baseboard_fab2_lib.baseboard_fab2(sch_1):page43_i259@mstr_sconn.sconn288_h44441004(chips)!SCONN288_H44441004_PIP-SCONN,HA!!!F146!VSS(56)!!!!
S!GND!J4G1!116!@baseboard_fab2_lib.baseboard_fab2(sch_1):page43_i259@mstr_sconn.sconn288_h44441004(chips)!SCONN288_H44441004_PIP-SCONN,HA!!!F146!VSS(57)!!!!
S!GND!J4G1!114!@baseboard_fab2_lib.baseboard_fab2(sch_1):page43_i259@mstr_sconn.sconn288_h44441004(chips)!SCONN288_H44441004_PIP-SCONN,HA!!!F146!VSS(58)!!!!
S!GND!J4G1!112!@baseboard_fab2_lib.baseboard_fab2(sch_1):page43_i259@mstr_sconn.sconn288_h44441004(chips)!SCONN288_H44441004_PIP-SCONN,HA!!!F146!VSS(59)!!!!
S!GND!J4G1!272!@baseboard_fab2_lib.baseboard_fab2(sch_1):page43_i259@mstr_sconn.sconn288_h44441004(chips)!SCONN288_H44441004_PIP-SCONN,HA!!!F146!VSS(5)!!!!
S!GND!J4G1!109!@baseboard_fab2_lib.baseboard_fab2(sch_1):page43_i259@mstr_sconn.sconn288_h44441004(chips)!SCONN288_H44441004_PIP-SCONN,HA!!!F146!VSS(60)!!!!
S!GND!J4G1!107!@baseboard_fab2_lib.baseboard_fab2(sch_1):page43_i259@mstr_sconn.sconn288_h44441004(chips)!SCONN288_H44441004_PIP-SCONN,HA!!!F146!VSS(61)!!!!
S!GND!J4G1!105!@baseboard_fab2_lib.baseboard_fab2(sch_1):page43_i259@mstr_sconn.sconn288_h44441004(chips)!SCONN288_H44441004_PIP-SCONN,HA!!!F146!VSS(62)!!!!
S!GND!J4G1!103!@baseboard_fab2_lib.baseboard_fab2(sch_1):page43_i259@mstr_sconn.sconn288_h44441004(chips)!SCONN288_H44441004_PIP-SCONN,HA!!!F146!VSS(63)!!!!
S!GND!J4G1!101!@baseboard_fab2_lib.baseboard_fab2(sch_1):page43_i259@mstr_sconn.sconn288_h44441004(chips)!SCONN288_H44441004_PIP-SCONN,HA!!!F146!VSS(64)!!!!
S!GND!J4G1!98!@baseboard_fab2_lib.baseboard_fab2(sch_1):page43_i259@mstr_sconn.sconn288_h44441004(chips)!SCONN288_H44441004_PIP-SCONN,HA!!!F146!VSS(65)!!!!
S!GND!J4G1!96!@baseboard_fab2_lib.baseboard_fab2(sch_1):page43_i259@mstr_sconn.sconn288_h44441004(chips)!SCONN288_H44441004_PIP-SCONN,HA!!!F146!VSS(66)!!!!
S!GND!J4G1!94!@baseboard_fab2_lib.baseboard_fab2(sch_1):page43_i259@mstr_sconn.sconn288_h44441004(chips)!SCONN288_H44441004_PIP-SCONN,HA!!!F146!VSS(67)!!!!
S!GND!J4G1!57!@baseboard_fab2_lib.baseboard_fab2(sch_1):page43_i259@mstr_sconn.sconn288_h44441004(chips)!SCONN288_H44441004_PIP-SCONN,HA!!!F146!VSS(68)!!!!
S!GND!J4G1!55!@baseboard_fab2_lib.baseboard_fab2(sch_1):page43_i259@mstr_sconn.sconn288_h44441004(chips)!SCONN288_H44441004_PIP-SCONN,HA!!!F146!VSS(69)!!!!
S!GND!J4G1!270!@baseboard_fab2_lib.baseboard_fab2(sch_1):page43_i259@mstr_sconn.sconn288_h44441004(chips)!SCONN288_H44441004_PIP-SCONN,HA!!!F146!VSS(6)!!!!
S!GND!J4G1!53!@baseboard_fab2_lib.baseboard_fab2(sch_1):page43_i259@mstr_sconn.sconn288_h44441004(chips)!SCONN288_H44441004_PIP-SCONN,HA!!!F146!VSS(70)!!!!
S!GND!J4G1!50!@baseboard_fab2_lib.baseboard_fab2(sch_1):page43_i259@mstr_sconn.sconn288_h44441004(chips)!SCONN288_H44441004_PIP-SCONN,HA!!!F146!VSS(71)!!!!
S!GND!J4G1!48!@baseboard_fab2_lib.baseboard_fab2(sch_1):page43_i259@mstr_sconn.sconn288_h44441004(chips)!SCONN288_H44441004_PIP-SCONN,HA!!!F146!VSS(72)!!!!
S!GND!J4G1!46!@baseboard_fab2_lib.baseboard_fab2(sch_1):page43_i259@mstr_sconn.sconn288_h44441004(chips)!SCONN288_H44441004_PIP-SCONN,HA!!!F146!VSS(73)!!!!
S!GND!J4G1!44!@baseboard_fab2_lib.baseboard_fab2(sch_1):page43_i259@mstr_sconn.sconn288_h44441004(chips)!SCONN288_H44441004_PIP-SCONN,HA!!!F146!VSS(74)!!!!
S!GND!J4G1!42!@baseboard_fab2_lib.baseboard_fab2(sch_1):page43_i259@mstr_sconn.sconn288_h44441004(chips)!SCONN288_H44441004_PIP-SCONN,HA!!!F146!VSS(75)!!!!
S!GND!J4G1!39!@baseboard_fab2_lib.baseboard_fab2(sch_1):page43_i259@mstr_sconn.sconn288_h44441004(chips)!SCONN288_H44441004_PIP-SCONN,HA!!!F146!VSS(76)!!!!
S!GND!J4G1!37!@baseboard_fab2_lib.baseboard_fab2(sch_1):page43_i259@mstr_sconn.sconn288_h44441004(chips)!SCONN288_H44441004_PIP-SCONN,HA!!!F146!VSS(77)!!!!
S!GND!J4G1!35!@baseboard_fab2_lib.baseboard_fab2(sch_1):page43_i259@mstr_sconn.sconn288_h44441004(chips)!SCONN288_H44441004_PIP-SCONN,HA!!!F146!VSS(78)!!!!
S!GND!J4G1!33!@baseboard_fab2_lib.baseboard_fab2(sch_1):page43_i259@mstr_sconn.sconn288_h44441004(chips)!SCONN288_H44441004_PIP-SCONN,HA!!!F146!VSS(79)!!!!
S!GND!J4G1!268!@baseboard_fab2_lib.baseboard_fab2(sch_1):page43_i259@mstr_sconn.sconn288_h44441004(chips)!SCONN288_H44441004_PIP-SCONN,HA!!!F146!VSS(7)!!!!
S!GND!J4G1!31!@baseboard_fab2_lib.baseboard_fab2(sch_1):page43_i259@mstr_sconn.sconn288_h44441004(chips)!SCONN288_H44441004_PIP-SCONN,HA!!!F146!VSS(80)!!!!
S!GND!J4G1!28!@baseboard_fab2_lib.baseboard_fab2(sch_1):page43_i259@mstr_sconn.sconn288_h44441004(chips)!SCONN288_H44441004_PIP-SCONN,HA!!!F146!VSS(81)!!!!
S!GND!J4G1!26!@baseboard_fab2_lib.baseboard_fab2(sch_1):page43_i259@mstr_sconn.sconn288_h44441004(chips)!SCONN288_H44441004_PIP-SCONN,HA!!!F146!VSS(82)!!!!
S!GND!J4G1!24!@baseboard_fab2_lib.baseboard_fab2(sch_1):page43_i259@mstr_sconn.sconn288_h44441004(chips)!SCONN288_H44441004_PIP-SCONN,HA!!!F146!VSS(83)!!!!
S!GND!J4G1!22!@baseboard_fab2_lib.baseboard_fab2(sch_1):page43_i259@mstr_sconn.sconn288_h44441004(chips)!SCONN288_H44441004_PIP-SCONN,HA!!!F146!VSS(84)!!!!
S!GND!J4G1!20!@baseboard_fab2_lib.baseboard_fab2(sch_1):page43_i259@mstr_sconn.sconn288_h44441004(chips)!SCONN288_H44441004_PIP-SCONN,HA!!!F146!VSS(85)!!!!
S!GND!J4G1!17!@baseboard_fab2_lib.baseboard_fab2(sch_1):page43_i259@mstr_sconn.sconn288_h44441004(chips)!SCONN288_H44441004_PIP-SCONN,HA!!!F146!VSS(86)!!!!
S!GND!J4G1!15!@baseboard_fab2_lib.baseboard_fab2(sch_1):page43_i259@mstr_sconn.sconn288_h44441004(chips)!SCONN288_H44441004_PIP-SCONN,HA!!!F146!VSS(87)!!!!
S!GND!J4G1!13!@baseboard_fab2_lib.baseboard_fab2(sch_1):page43_i259@mstr_sconn.sconn288_h44441004(chips)!SCONN288_H44441004_PIP-SCONN,HA!!!F146!VSS(88)!!!!
S!GND!J4G1!11!@baseboard_fab2_lib.baseboard_fab2(sch_1):page43_i259@mstr_sconn.sconn288_h44441004(chips)!SCONN288_H44441004_PIP-SCONN,HA!!!F146!VSS(89)!!!!
S!GND!J4G1!265!@baseboard_fab2_lib.baseboard_fab2(sch_1):page43_i259@mstr_sconn.sconn288_h44441004(chips)!SCONN288_H44441004_PIP-SCONN,HA!!!F146!VSS(8)!!!!
S!GND!J4G1!9!@baseboard_fab2_lib.baseboard_fab2(sch_1):page43_i259@mstr_sconn.sconn288_h44441004(chips)!SCONN288_H44441004_PIP-SCONN,HA!!!F146!VSS(90)!!!!
S!GND!J4G1!6!@baseboard_fab2_lib.baseboard_fab2(sch_1):page43_i259@mstr_sconn.sconn288_h44441004(chips)!SCONN288_H44441004_PIP-SCONN,HA!!!F146!VSS(91)!!!!
S!GND!J4G1!4!@baseboard_fab2_lib.baseboard_fab2(sch_1):page43_i259@mstr_sconn.sconn288_h44441004(chips)!SCONN288_H44441004_PIP-SCONN,HA!!!F146!VSS(92)!!!!
S!GND!J4G1!2!@baseboard_fab2_lib.baseboard_fab2(sch_1):page43_i259@mstr_sconn.sconn288_h44441004(chips)!SCONN288_H44441004_PIP-SCONN,HA!!!F146!VSS(93)!!!!
S!GND!J4G1!263!@baseboard_fab2_lib.baseboard_fab2(sch_1):page43_i259@mstr_sconn.sconn288_h44441004(chips)!SCONN288_H44441004_PIP-SCONN,HA!!!F146!VSS(9)!!!!
S!P12V_NVDIMM_ABC!J4G1!145!@baseboard_fab2_lib.baseboard_fab2(sch_1):page43_i260@mstr_sconn.sconn288_h44441004(chips)!SCONN288_H44441004_PIP-SCONN,HA!!!F145!\12v\(0)!!!!
S!P12V_NVDIMM_ABC!J4G1!1!@baseboard_fab2_lib.baseboard_fab2(sch_1):page43_i260@mstr_sconn.sconn288_h44441004(chips)!SCONN288_H44441004_PIP-SCONN,HA!!!F145!\12v\(1)!!!!
S!PVDDQ_ABC!J4G1!236!@baseboard_fab2_lib.baseboard_fab2(sch_1):page43_i260@mstr_sconn.sconn288_h44441004(chips)!SCONN288_H44441004_PIP-SCONN,HA!!!F145!VDD(0)!!!!
S!PVDDQ_ABC!J4G1!209!@baseboard_fab2_lib.baseboard_fab2(sch_1):page43_i260@mstr_sconn.sconn288_h44441004(chips)!SCONN288_H44441004_PIP-SCONN,HA!!!F145!VDD(10)!!!!
S!PVDDQ_ABC!J4G1!206!@baseboard_fab2_lib.baseboard_fab2(sch_1):page43_i260@mstr_sconn.sconn288_h44441004(chips)!SCONN288_H44441004_PIP-SCONN,HA!!!F145!VDD(11)!!!!
S!PVDDQ_ABC!J4G1!204!@baseboard_fab2_lib.baseboard_fab2(sch_1):page43_i260@mstr_sconn.sconn288_h44441004(chips)!SCONN288_H44441004_PIP-SCONN,HA!!!F145!VDD(12)!!!!
S!PVDDQ_ABC!J4G1!92!@baseboard_fab2_lib.baseboard_fab2(sch_1):page43_i260@mstr_sconn.sconn288_h44441004(chips)!SCONN288_H44441004_PIP-SCONN,HA!!!F145!VDD(13)!!!!
S!PVDDQ_ABC!J4G1!90!@baseboard_fab2_lib.baseboard_fab2(sch_1):page43_i260@mstr_sconn.sconn288_h44441004(chips)!SCONN288_H44441004_PIP-SCONN,HA!!!F145!VDD(14)!!!!
S!PVDDQ_ABC!J4G1!88!@baseboard_fab2_lib.baseboard_fab2(sch_1):page43_i260@mstr_sconn.sconn288_h44441004(chips)!SCONN288_H44441004_PIP-SCONN,HA!!!F145!VDD(15)!!!!
S!PVDDQ_ABC!J4G1!85!@baseboard_fab2_lib.baseboard_fab2(sch_1):page43_i260@mstr_sconn.sconn288_h44441004(chips)!SCONN288_H44441004_PIP-SCONN,HA!!!F145!VDD(16)!!!!
S!PVDDQ_ABC!J4G1!83!@baseboard_fab2_lib.baseboard_fab2(sch_1):page43_i260@mstr_sconn.sconn288_h44441004(chips)!SCONN288_H44441004_PIP-SCONN,HA!!!F145!VDD(17)!!!!
S!PVDDQ_ABC!J4G1!80!@baseboard_fab2_lib.baseboard_fab2(sch_1):page43_i260@mstr_sconn.sconn288_h44441004(chips)!SCONN288_H44441004_PIP-SCONN,HA!!!F145!VDD(18)!!!!
S!PVDDQ_ABC!J4G1!76!@baseboard_fab2_lib.baseboard_fab2(sch_1):page43_i260@mstr_sconn.sconn288_h44441004(chips)!SCONN288_H44441004_PIP-SCONN,HA!!!F145!VDD(19)!!!!
S!PVDDQ_ABC!J4G1!233!@baseboard_fab2_lib.baseboard_fab2(sch_1):page43_i260@mstr_sconn.sconn288_h44441004(chips)!SCONN288_H44441004_PIP-SCONN,HA!!!F145!VDD(1)!!!!
S!PVDDQ_ABC!J4G1!73!@baseboard_fab2_lib.baseboard_fab2(sch_1):page43_i260@mstr_sconn.sconn288_h44441004(chips)!SCONN288_H44441004_PIP-SCONN,HA!!!F145!VDD(20)!!!!
S!PVDDQ_ABC!J4G1!70!@baseboard_fab2_lib.baseboard_fab2(sch_1):page43_i260@mstr_sconn.sconn288_h44441004(chips)!SCONN288_H44441004_PIP-SCONN,HA!!!F145!VDD(21)!!!!
S!PVDDQ_ABC!J4G1!67!@baseboard_fab2_lib.baseboard_fab2(sch_1):page43_i260@mstr_sconn.sconn288_h44441004(chips)!SCONN288_H44441004_PIP-SCONN,HA!!!F145!VDD(22)!!!!
S!PVDDQ_ABC!J4G1!64!@baseboard_fab2_lib.baseboard_fab2(sch_1):page43_i260@mstr_sconn.sconn288_h44441004(chips)!SCONN288_H44441004_PIP-SCONN,HA!!!F145!VDD(23)!!!!
S!PVDDQ_ABC!J4G1!61!@baseboard_fab2_lib.baseboard_fab2(sch_1):page43_i260@mstr_sconn.sconn288_h44441004(chips)!SCONN288_H44441004_PIP-SCONN,HA!!!F145!VDD(24)!!!!
S!PVDDQ_ABC!J4G1!59!@baseboard_fab2_lib.baseboard_fab2(sch_1):page43_i260@mstr_sconn.sconn288_h44441004(chips)!SCONN288_H44441004_PIP-SCONN,HA!!!F145!VDD(25)!!!!
S!PVDDQ_ABC!J4G1!231!@baseboard_fab2_lib.baseboard_fab2(sch_1):page43_i260@mstr_sconn.sconn288_h44441004(chips)!SCONN288_H44441004_PIP-SCONN,HA!!!F145!VDD(2)!!!!
S!PVDDQ_ABC!J4G1!229!@baseboard_fab2_lib.baseboard_fab2(sch_1):page43_i260@mstr_sconn.sconn288_h44441004(chips)!SCONN288_H44441004_PIP-SCONN,HA!!!F145!VDD(3)!!!!
S!PVDDQ_ABC!J4G1!226!@baseboard_fab2_lib.baseboard_fab2(sch_1):page43_i260@mstr_sconn.sconn288_h44441004(chips)!SCONN288_H44441004_PIP-SCONN,HA!!!F145!VDD(4)!!!!
S!PVDDQ_ABC!J4G1!223!@baseboard_fab2_lib.baseboard_fab2(sch_1):page43_i260@mstr_sconn.sconn288_h44441004(chips)!SCONN288_H44441004_PIP-SCONN,HA!!!F145!VDD(5)!!!!
S!PVDDQ_ABC!J4G1!220!@baseboard_fab2_lib.baseboard_fab2(sch_1):page43_i260@mstr_sconn.sconn288_h44441004(chips)!SCONN288_H44441004_PIP-SCONN,HA!!!F145!VDD(6)!!!!
S!PVDDQ_ABC!J4G1!217!@baseboard_fab2_lib.baseboard_fab2(sch_1):page43_i260@mstr_sconn.sconn288_h44441004(chips)!SCONN288_H44441004_PIP-SCONN,HA!!!F145!VDD(7)!!!!
S!PVDDQ_ABC!J4G1!215!@baseboard_fab2_lib.baseboard_fab2(sch_1):page43_i260@mstr_sconn.sconn288_h44441004(chips)!SCONN288_H44441004_PIP-SCONN,HA!!!F145!VDD(8)!!!!
S!PVDDQ_ABC!J4G1!212!@baseboard_fab2_lib.baseboard_fab2(sch_1):page43_i260@mstr_sconn.sconn288_h44441004(chips)!SCONN288_H44441004_PIP-SCONN,HA!!!F145!VDD(9)!!!!
S!PVPP_ABC!J4G1!287!@baseboard_fab2_lib.baseboard_fab2(sch_1):page43_i260@mstr_sconn.sconn288_h44441004(chips)!SCONN288_H44441004_PIP-SCONN,HA!!!F145!VPP(0)!!!!
S!PVPP_ABC!J4G1!286!@baseboard_fab2_lib.baseboard_fab2(sch_1):page43_i260@mstr_sconn.sconn288_h44441004(chips)!SCONN288_H44441004_PIP-SCONN,HA!!!F145!VPP(1)!!!!
S!PVPP_ABC!J4G1!288!@baseboard_fab2_lib.baseboard_fab2(sch_1):page43_i260@mstr_sconn.sconn288_h44441004(chips)!SCONN288_H44441004_PIP-SCONN,HA!!!F145!VPP(2)!!!!
S!PVPP_ABC!J4G1!143!@baseboard_fab2_lib.baseboard_fab2(sch_1):page43_i260@mstr_sconn.sconn288_h44441004(chips)!SCONN288_H44441004_PIP-SCONN,HA!!!F145!VPP(3)!!!!
S!PVPP_ABC!J4G1!142!@baseboard_fab2_lib.baseboard_fab2(sch_1):page43_i260@mstr_sconn.sconn288_h44441004(chips)!SCONN288_H44441004_PIP-SCONN,HA!!!F145!VPP(4)!!!!
S!PVTT_ABC!J4G1!221!@baseboard_fab2_lib.baseboard_fab2(sch_1):page43_i260@mstr_sconn.sconn288_h44441004(chips)!SCONN288_H44441004_PIP-SCONN,HA!!!F145!VTT(0)!!!!
S!PVTT_ABC!J4G1!77!@baseboard_fab2_lib.baseboard_fab2(sch_1):page43_i260@mstr_sconn.sconn288_h44441004(chips)!SCONN288_H44441004_PIP-SCONN,HA!!!F145!VTT(1)!!!!
S!M_B_MA<0>!J4G2!79!@baseboard_fab2_lib.baseboard_fab2(sch_1):page45_i111@mstr_sconn.sconn288_h44441004(chips)!SCONN288_H44441004_PIP-SCONN,HA!!!F144!A0!!!!
S!M_B_MA<1>!J4G2!72!@baseboard_fab2_lib.baseboard_fab2(sch_1):page45_i111@mstr_sconn.sconn288_h44441004(chips)!SCONN288_H44441004_PIP-SCONN,HA!!!F144!A1!!!!
S!M_B_MA<10>!J4G2!225!@baseboard_fab2_lib.baseboard_fab2(sch_1):page45_i111@mstr_sconn.sconn288_h44441004(chips)!SCONN288_H44441004_PIP-SCONN,HA!!!F144!A10!!!!
S!M_B_MA<11>!J4G2!210!@baseboard_fab2_lib.baseboard_fab2(sch_1):page45_i111@mstr_sconn.sconn288_h44441004(chips)!SCONN288_H44441004_PIP-SCONN,HA!!!F144!A11!!!!
S!M_B_MA<12>!J4G2!65!@baseboard_fab2_lib.baseboard_fab2(sch_1):page45_i111@mstr_sconn.sconn288_h44441004(chips)!SCONN288_H44441004_PIP-SCONN,HA!!!F144!A12!!!!
S!M_B_MA<13>!J4G2!232!@baseboard_fab2_lib.baseboard_fab2(sch_1):page45_i111@mstr_sconn.sconn288_h44441004(chips)!SCONN288_H44441004_PIP-SCONN,HA!!!F144!A13!!!!
S!M_B_MA<14>!J4G2!228!@baseboard_fab2_lib.baseboard_fab2(sch_1):page45_i111@mstr_sconn.sconn288_h44441004(chips)!SCONN288_H44441004_PIP-SCONN,HA!!!F144!A14_WE_N!!!!
S!M_B_MA<15>!J4G2!86!@baseboard_fab2_lib.baseboard_fab2(sch_1):page45_i111@mstr_sconn.sconn288_h44441004(chips)!SCONN288_H44441004_PIP-SCONN,HA!!!F144!A15_CAS_N!!!!
S!M_B_MA<16>!J4G2!82!@baseboard_fab2_lib.baseboard_fab2(sch_1):page45_i111@mstr_sconn.sconn288_h44441004(chips)!SCONN288_H44441004_PIP-SCONN,HA!!!F144!A16_RAS_N!!!!
S!M_B_MA<17>!J4G2!234!@baseboard_fab2_lib.baseboard_fab2(sch_1):page45_i111@mstr_sconn.sconn288_h44441004(chips)!SCONN288_H44441004_PIP-SCONN,HA!!!F144!A17!!!!
S!M_B_MA<2>!J4G2!216!@baseboard_fab2_lib.baseboard_fab2(sch_1):page45_i111@mstr_sconn.sconn288_h44441004(chips)!SCONN288_H44441004_PIP-SCONN,HA!!!F144!A2!!!!
S!M_B_MA<3>!J4G2!71!@baseboard_fab2_lib.baseboard_fab2(sch_1):page45_i111@mstr_sconn.sconn288_h44441004(chips)!SCONN288_H44441004_PIP-SCONN,HA!!!F144!A3!!!!
S!M_B_MA<4>!J4G2!214!@baseboard_fab2_lib.baseboard_fab2(sch_1):page45_i111@mstr_sconn.sconn288_h44441004(chips)!SCONN288_H44441004_PIP-SCONN,HA!!!F144!A4!!!!
S!M_B_MA<5>!J4G2!213!@baseboard_fab2_lib.baseboard_fab2(sch_1):page45_i111@mstr_sconn.sconn288_h44441004(chips)!SCONN288_H44441004_PIP-SCONN,HA!!!F144!A5!!!!
S!M_B_MA<6>!J4G2!69!@baseboard_fab2_lib.baseboard_fab2(sch_1):page45_i111@mstr_sconn.sconn288_h44441004(chips)!SCONN288_H44441004_PIP-SCONN,HA!!!F144!A6!!!!
S!M_B_MA<7>!J4G2!211!@baseboard_fab2_lib.baseboard_fab2(sch_1):page45_i111@mstr_sconn.sconn288_h44441004(chips)!SCONN288_H44441004_PIP-SCONN,HA!!!F144!A7!!!!
S!M_B_MA<8>!J4G2!68!@baseboard_fab2_lib.baseboard_fab2(sch_1):page45_i111@mstr_sconn.sconn288_h44441004(chips)!SCONN288_H44441004_PIP-SCONN,HA!!!F144!A8!!!!
S!M_B_MA<9>!J4G2!66!@baseboard_fab2_lib.baseboard_fab2(sch_1):page45_i111@mstr_sconn.sconn288_h44441004(chips)!SCONN288_H44441004_PIP-SCONN,HA!!!F144!A9!!!!
S!M_B_ACT_N!J4G2!62!@baseboard_fab2_lib.baseboard_fab2(sch_1):page45_i111@mstr_sconn.sconn288_h44441004(chips)!SCONN288_H44441004_PIP-SCONN,HA!!!F144!ACT_N!!!!
S!M_B_ALERT_N!J4G2!208!@baseboard_fab2_lib.baseboard_fab2(sch_1):page45_i111@mstr_sconn.sconn288_h44441004(chips)!SCONN288_H44441004_PIP-SCONN,HA!!!F144!ALERT_N!!!!
S!M_B_BA<0>!J4G2!81!@baseboard_fab2_lib.baseboard_fab2(sch_1):page45_i111@mstr_sconn.sconn288_h44441004(chips)!SCONN288_H44441004_PIP-SCONN,HA!!!F144!BA(0)!!!!
S!M_B_BA<1>!J4G2!224!@baseboard_fab2_lib.baseboard_fab2(sch_1):page45_i111@mstr_sconn.sconn288_h44441004(chips)!SCONN288_H44441004_PIP-SCONN,HA!!!F144!BA(1)!!!!
S!M_B_BG<0>!J4G2!63!@baseboard_fab2_lib.baseboard_fab2(sch_1):page45_i111@mstr_sconn.sconn288_h44441004(chips)!SCONN288_H44441004_PIP-SCONN,HA!!!F144!BG(0)!!!!
S!M_B_BG<1>!J4G2!207!@baseboard_fab2_lib.baseboard_fab2(sch_1):page45_i111@mstr_sconn.sconn288_h44441004(chips)!SCONN288_H44441004_PIP-SCONN,HA!!!F144!BG(1)!!!!
S!M_B_C<2>!J4G2!235!@baseboard_fab2_lib.baseboard_fab2(sch_1):page45_i111@mstr_sconn.sconn288_h44441004(chips)!SCONN288_H44441004_PIP-SCONN,HA!!!F144!C(2)!!!!
S!M_B_ECC<1>!J4G2!49!@baseboard_fab2_lib.baseboard_fab2(sch_1):page45_i111@mstr_sconn.sconn288_h44441004(chips)!SCONN288_H44441004_PIP-SCONN,HA!!!F144!CB(0)!!!!
S!M_B_ECC<0>!J4G2!194!@baseboard_fab2_lib.baseboard_fab2(sch_1):page45_i111@mstr_sconn.sconn288_h44441004(chips)!SCONN288_H44441004_PIP-SCONN,HA!!!F144!CB(1)!!!!
S!M_B_ECC<3>!J4G2!56!@baseboard_fab2_lib.baseboard_fab2(sch_1):page45_i111@mstr_sconn.sconn288_h44441004(chips)!SCONN288_H44441004_PIP-SCONN,HA!!!F144!CB(2)!!!!
S!M_B_ECC<2>!J4G2!201!@baseboard_fab2_lib.baseboard_fab2(sch_1):page45_i111@mstr_sconn.sconn288_h44441004(chips)!SCONN288_H44441004_PIP-SCONN,HA!!!F144!CB(3)!!!!
S!M_B_ECC<5>!J4G2!47!@baseboard_fab2_lib.baseboard_fab2(sch_1):page45_i111@mstr_sconn.sconn288_h44441004(chips)!SCONN288_H44441004_PIP-SCONN,HA!!!F144!CB(4)!!!!
S!M_B_ECC<4>!J4G2!192!@baseboard_fab2_lib.baseboard_fab2(sch_1):page45_i111@mstr_sconn.sconn288_h44441004(chips)!SCONN288_H44441004_PIP-SCONN,HA!!!F144!CB(5)!!!!
S!M_B_ECC<7>!J4G2!54!@baseboard_fab2_lib.baseboard_fab2(sch_1):page45_i111@mstr_sconn.sconn288_h44441004(chips)!SCONN288_H44441004_PIP-SCONN,HA!!!F144!CB(6)!!!!
S!M_B_ECC<6>!J4G2!199!@baseboard_fab2_lib.baseboard_fab2(sch_1):page45_i111@mstr_sconn.sconn288_h44441004(chips)!SCONN288_H44441004_PIP-SCONN,HA!!!F144!CB(7)!!!!
S!M_B_CLK_DN<0>!J4G2!75!@baseboard_fab2_lib.baseboard_fab2(sch_1):page45_i111@mstr_sconn.sconn288_h44441004(chips)!SCONN288_H44441004_PIP-SCONN,HA!!!F144!CK0N!!!!
S!M_B_CLK_DP<0>!J4G2!74!@baseboard_fab2_lib.baseboard_fab2(sch_1):page45_i111@mstr_sconn.sconn288_h44441004(chips)!SCONN288_H44441004_PIP-SCONN,HA!!!F144!CK0P!!!!
S!M_B_CLK_DN<1>!J4G2!219!@baseboard_fab2_lib.baseboard_fab2(sch_1):page45_i111@mstr_sconn.sconn288_h44441004(chips)!SCONN288_H44441004_PIP-SCONN,HA!!!F144!CK1N!!!!
S!M_B_CLK_DP<1>!J4G2!218!@baseboard_fab2_lib.baseboard_fab2(sch_1):page45_i111@mstr_sconn.sconn288_h44441004(chips)!SCONN288_H44441004_PIP-SCONN,HA!!!F144!CK1P!!!!
S!M_B_CKE<0>!J4G2!60!@baseboard_fab2_lib.baseboard_fab2(sch_1):page45_i111@mstr_sconn.sconn288_h44441004(chips)!SCONN288_H44441004_PIP-SCONN,HA!!!F144!CKE(0)!!!!
S!M_B_CKE<1>!J4G2!203!@baseboard_fab2_lib.baseboard_fab2(sch_1):page45_i111@mstr_sconn.sconn288_h44441004(chips)!SCONN288_H44441004_PIP-SCONN,HA!!!F144!CKE(1)!!!!
S!M_B_DQ<1>!J4G2!5!@baseboard_fab2_lib.baseboard_fab2(sch_1):page45_i111@mstr_sconn.sconn288_h44441004(chips)!SCONN288_H44441004_PIP-SCONN,HA!!!F144!DQ(0)!!!!
S!M_B_DQ<11>!J4G2!23!@baseboard_fab2_lib.baseboard_fab2(sch_1):page45_i111@mstr_sconn.sconn288_h44441004(chips)!SCONN288_H44441004_PIP-SCONN,HA!!!F144!DQ(10)!!!!
S!M_B_DQ<10>!J4G2!168!@baseboard_fab2_lib.baseboard_fab2(sch_1):page45_i111@mstr_sconn.sconn288_h44441004(chips)!SCONN288_H44441004_PIP-SCONN,HA!!!F144!DQ(11)!!!!
S!M_B_DQ<13>!J4G2!14!@baseboard_fab2_lib.baseboard_fab2(sch_1):page45_i111@mstr_sconn.sconn288_h44441004(chips)!SCONN288_H44441004_PIP-SCONN,HA!!!F144!DQ(12)!!!!
S!M_B_DQ<12>!J4G2!159!@baseboard_fab2_lib.baseboard_fab2(sch_1):page45_i111@mstr_sconn.sconn288_h44441004(chips)!SCONN288_H44441004_PIP-SCONN,HA!!!F144!DQ(13)!!!!
S!M_B_DQ<15>!J4G2!21!@baseboard_fab2_lib.baseboard_fab2(sch_1):page45_i111@mstr_sconn.sconn288_h44441004(chips)!SCONN288_H44441004_PIP-SCONN,HA!!!F144!DQ(14)!!!!
S!M_B_DQ<14>!J4G2!166!@baseboard_fab2_lib.baseboard_fab2(sch_1):page45_i111@mstr_sconn.sconn288_h44441004(chips)!SCONN288_H44441004_PIP-SCONN,HA!!!F144!DQ(15)!!!!
S!M_B_DQ<17>!J4G2!27!@baseboard_fab2_lib.baseboard_fab2(sch_1):page45_i111@mstr_sconn.sconn288_h44441004(chips)!SCONN288_H44441004_PIP-SCONN,HA!!!F144!DQ(16)!!!!
S!M_B_DQ<16>!J4G2!172!@baseboard_fab2_lib.baseboard_fab2(sch_1):page45_i111@mstr_sconn.sconn288_h44441004(chips)!SCONN288_H44441004_PIP-SCONN,HA!!!F144!DQ(17)!!!!
S!M_B_DQ<19>!J4G2!34!@baseboard_fab2_lib.baseboard_fab2(sch_1):page45_i111@mstr_sconn.sconn288_h44441004(chips)!SCONN288_H44441004_PIP-SCONN,HA!!!F144!DQ(18)!!!!
S!M_B_DQ<18>!J4G2!179!@baseboard_fab2_lib.baseboard_fab2(sch_1):page45_i111@mstr_sconn.sconn288_h44441004(chips)!SCONN288_H44441004_PIP-SCONN,HA!!!F144!DQ(19)!!!!
S!M_B_DQ<0>!J4G2!150!@baseboard_fab2_lib.baseboard_fab2(sch_1):page45_i111@mstr_sconn.sconn288_h44441004(chips)!SCONN288_H44441004_PIP-SCONN,HA!!!F144!DQ(1)!!!!
S!M_B_DQ<21>!J4G2!25!@baseboard_fab2_lib.baseboard_fab2(sch_1):page45_i111@mstr_sconn.sconn288_h44441004(chips)!SCONN288_H44441004_PIP-SCONN,HA!!!F144!DQ(20)!!!!
S!M_B_DQ<20>!J4G2!170!@baseboard_fab2_lib.baseboard_fab2(sch_1):page45_i111@mstr_sconn.sconn288_h44441004(chips)!SCONN288_H44441004_PIP-SCONN,HA!!!F144!DQ(21)!!!!
S!M_B_DQ<23>!J4G2!32!@baseboard_fab2_lib.baseboard_fab2(sch_1):page45_i111@mstr_sconn.sconn288_h44441004(chips)!SCONN288_H44441004_PIP-SCONN,HA!!!F144!DQ(22)!!!!
S!M_B_DQ<22>!J4G2!177!@baseboard_fab2_lib.baseboard_fab2(sch_1):page45_i111@mstr_sconn.sconn288_h44441004(chips)!SCONN288_H44441004_PIP-SCONN,HA!!!F144!DQ(23)!!!!
S!M_B_DQ<25>!J4G2!38!@baseboard_fab2_lib.baseboard_fab2(sch_1):page45_i111@mstr_sconn.sconn288_h44441004(chips)!SCONN288_H44441004_PIP-SCONN,HA!!!F144!DQ(24)!!!!
S!M_B_DQ<24>!J4G2!183!@baseboard_fab2_lib.baseboard_fab2(sch_1):page45_i111@mstr_sconn.sconn288_h44441004(chips)!SCONN288_H44441004_PIP-SCONN,HA!!!F144!DQ(25)!!!!
S!M_B_DQ<27>!J4G2!45!@baseboard_fab2_lib.baseboard_fab2(sch_1):page45_i111@mstr_sconn.sconn288_h44441004(chips)!SCONN288_H44441004_PIP-SCONN,HA!!!F144!DQ(26)!!!!
S!M_B_DQ<26>!J4G2!190!@baseboard_fab2_lib.baseboard_fab2(sch_1):page45_i111@mstr_sconn.sconn288_h44441004(chips)!SCONN288_H44441004_PIP-SCONN,HA!!!F144!DQ(27)!!!!
S!M_B_DQ<29>!J4G2!36!@baseboard_fab2_lib.baseboard_fab2(sch_1):page45_i111@mstr_sconn.sconn288_h44441004(chips)!SCONN288_H44441004_PIP-SCONN,HA!!!F144!DQ(28)!!!!
S!M_B_DQ<28>!J4G2!181!@baseboard_fab2_lib.baseboard_fab2(sch_1):page45_i111@mstr_sconn.sconn288_h44441004(chips)!SCONN288_H44441004_PIP-SCONN,HA!!!F144!DQ(29)!!!!
S!M_B_DQ<3>!J4G2!12!@baseboard_fab2_lib.baseboard_fab2(sch_1):page45_i111@mstr_sconn.sconn288_h44441004(chips)!SCONN288_H44441004_PIP-SCONN,HA!!!F144!DQ(2)!!!!
S!M_B_DQ<31>!J4G2!43!@baseboard_fab2_lib.baseboard_fab2(sch_1):page45_i111@mstr_sconn.sconn288_h44441004(chips)!SCONN288_H44441004_PIP-SCONN,HA!!!F144!DQ(30)!!!!
S!M_B_DQ<30>!J4G2!188!@baseboard_fab2_lib.baseboard_fab2(sch_1):page45_i111@mstr_sconn.sconn288_h44441004(chips)!SCONN288_H44441004_PIP-SCONN,HA!!!F144!DQ(31)!!!!
S!M_B_DQ<33>!J4G2!97!@baseboard_fab2_lib.baseboard_fab2(sch_1):page45_i111@mstr_sconn.sconn288_h44441004(chips)!SCONN288_H44441004_PIP-SCONN,HA!!!F144!DQ(32)!!!!
S!M_B_DQ<32>!J4G2!242!@baseboard_fab2_lib.baseboard_fab2(sch_1):page45_i111@mstr_sconn.sconn288_h44441004(chips)!SCONN288_H44441004_PIP-SCONN,HA!!!F144!DQ(33)!!!!
S!M_B_DQ<35>!J4G2!104!@baseboard_fab2_lib.baseboard_fab2(sch_1):page45_i111@mstr_sconn.sconn288_h44441004(chips)!SCONN288_H44441004_PIP-SCONN,HA!!!F144!DQ(34)!!!!
S!M_B_DQ<34>!J4G2!249!@baseboard_fab2_lib.baseboard_fab2(sch_1):page45_i111@mstr_sconn.sconn288_h44441004(chips)!SCONN288_H44441004_PIP-SCONN,HA!!!F144!DQ(35)!!!!
S!M_B_DQ<37>!J4G2!95!@baseboard_fab2_lib.baseboard_fab2(sch_1):page45_i111@mstr_sconn.sconn288_h44441004(chips)!SCONN288_H44441004_PIP-SCONN,HA!!!F144!DQ(36)!!!!
S!M_B_DQ<36>!J4G2!240!@baseboard_fab2_lib.baseboard_fab2(sch_1):page45_i111@mstr_sconn.sconn288_h44441004(chips)!SCONN288_H44441004_PIP-SCONN,HA!!!F144!DQ(37)!!!!
S!M_B_DQ<39>!J4G2!102!@baseboard_fab2_lib.baseboard_fab2(sch_1):page45_i111@mstr_sconn.sconn288_h44441004(chips)!SCONN288_H44441004_PIP-SCONN,HA!!!F144!DQ(38)!!!!
S!M_B_DQ<38>!J4G2!247!@baseboard_fab2_lib.baseboard_fab2(sch_1):page45_i111@mstr_sconn.sconn288_h44441004(chips)!SCONN288_H44441004_PIP-SCONN,HA!!!F144!DQ(39)!!!!
S!M_B_DQ<2>!J4G2!157!@baseboard_fab2_lib.baseboard_fab2(sch_1):page45_i111@mstr_sconn.sconn288_h44441004(chips)!SCONN288_H44441004_PIP-SCONN,HA!!!F144!DQ(3)!!!!
S!M_B_DQ<41>!J4G2!108!@baseboard_fab2_lib.baseboard_fab2(sch_1):page45_i111@mstr_sconn.sconn288_h44441004(chips)!SCONN288_H44441004_PIP-SCONN,HA!!!F144!DQ(40)!!!!
S!M_B_DQ<40>!J4G2!253!@baseboard_fab2_lib.baseboard_fab2(sch_1):page45_i111@mstr_sconn.sconn288_h44441004(chips)!SCONN288_H44441004_PIP-SCONN,HA!!!F144!DQ(41)!!!!
S!M_B_DQ<43>!J4G2!115!@baseboard_fab2_lib.baseboard_fab2(sch_1):page45_i111@mstr_sconn.sconn288_h44441004(chips)!SCONN288_H44441004_PIP-SCONN,HA!!!F144!DQ(42)!!!!
S!M_B_DQ<42>!J4G2!260!@baseboard_fab2_lib.baseboard_fab2(sch_1):page45_i111@mstr_sconn.sconn288_h44441004(chips)!SCONN288_H44441004_PIP-SCONN,HA!!!F144!DQ(43)!!!!
S!M_B_DQ<45>!J4G2!106!@baseboard_fab2_lib.baseboard_fab2(sch_1):page45_i111@mstr_sconn.sconn288_h44441004(chips)!SCONN288_H44441004_PIP-SCONN,HA!!!F144!DQ(44)!!!!
S!M_B_DQ<44>!J4G2!251!@baseboard_fab2_lib.baseboard_fab2(sch_1):page45_i111@mstr_sconn.sconn288_h44441004(chips)!SCONN288_H44441004_PIP-SCONN,HA!!!F144!DQ(45)!!!!
S!M_B_DQ<47>!J4G2!113!@baseboard_fab2_lib.baseboard_fab2(sch_1):page45_i111@mstr_sconn.sconn288_h44441004(chips)!SCONN288_H44441004_PIP-SCONN,HA!!!F144!DQ(46)!!!!
S!M_B_DQ<46>!J4G2!258!@baseboard_fab2_lib.baseboard_fab2(sch_1):page45_i111@mstr_sconn.sconn288_h44441004(chips)!SCONN288_H44441004_PIP-SCONN,HA!!!F144!DQ(47)!!!!
S!M_B_DQ<49>!J4G2!119!@baseboard_fab2_lib.baseboard_fab2(sch_1):page45_i111@mstr_sconn.sconn288_h44441004(chips)!SCONN288_H44441004_PIP-SCONN,HA!!!F144!DQ(48)!!!!
S!M_B_DQ<48>!J4G2!264!@baseboard_fab2_lib.baseboard_fab2(sch_1):page45_i111@mstr_sconn.sconn288_h44441004(chips)!SCONN288_H44441004_PIP-SCONN,HA!!!F144!DQ(49)!!!!
S!M_B_DQ<5>!J4G2!3!@baseboard_fab2_lib.baseboard_fab2(sch_1):page45_i111@mstr_sconn.sconn288_h44441004(chips)!SCONN288_H44441004_PIP-SCONN,HA!!!F144!DQ(4)!!!!
S!M_B_DQ<51>!J4G2!126!@baseboard_fab2_lib.baseboard_fab2(sch_1):page45_i111@mstr_sconn.sconn288_h44441004(chips)!SCONN288_H44441004_PIP-SCONN,HA!!!F144!DQ(50)!!!!
S!M_B_DQ<50>!J4G2!271!@baseboard_fab2_lib.baseboard_fab2(sch_1):page45_i111@mstr_sconn.sconn288_h44441004(chips)!SCONN288_H44441004_PIP-SCONN,HA!!!F144!DQ(51)!!!!
S!M_B_DQ<53>!J4G2!117!@baseboard_fab2_lib.baseboard_fab2(sch_1):page45_i111@mstr_sconn.sconn288_h44441004(chips)!SCONN288_H44441004_PIP-SCONN,HA!!!F144!DQ(52)!!!!
S!M_B_DQ<52>!J4G2!262!@baseboard_fab2_lib.baseboard_fab2(sch_1):page45_i111@mstr_sconn.sconn288_h44441004(chips)!SCONN288_H44441004_PIP-SCONN,HA!!!F144!DQ(53)!!!!
S!M_B_DQ<55>!J4G2!124!@baseboard_fab2_lib.baseboard_fab2(sch_1):page45_i111@mstr_sconn.sconn288_h44441004(chips)!SCONN288_H44441004_PIP-SCONN,HA!!!F144!DQ(54)!!!!
S!M_B_DQ<54>!J4G2!269!@baseboard_fab2_lib.baseboard_fab2(sch_1):page45_i111@mstr_sconn.sconn288_h44441004(chips)!SCONN288_H44441004_PIP-SCONN,HA!!!F144!DQ(55)!!!!
S!M_B_DQ<57>!J4G2!130!@baseboard_fab2_lib.baseboard_fab2(sch_1):page45_i111@mstr_sconn.sconn288_h44441004(chips)!SCONN288_H44441004_PIP-SCONN,HA!!!F144!DQ(56)!!!!
S!M_B_DQ<56>!J4G2!275!@baseboard_fab2_lib.baseboard_fab2(sch_1):page45_i111@mstr_sconn.sconn288_h44441004(chips)!SCONN288_H44441004_PIP-SCONN,HA!!!F144!DQ(57)!!!!
S!M_B_DQ<59>!J4G2!137!@baseboard_fab2_lib.baseboard_fab2(sch_1):page45_i111@mstr_sconn.sconn288_h44441004(chips)!SCONN288_H44441004_PIP-SCONN,HA!!!F144!DQ(58)!!!!
S!M_B_DQ<58>!J4G2!282!@baseboard_fab2_lib.baseboard_fab2(sch_1):page45_i111@mstr_sconn.sconn288_h44441004(chips)!SCONN288_H44441004_PIP-SCONN,HA!!!F144!DQ(59)!!!!
S!M_B_DQ<4>!J4G2!148!@baseboard_fab2_lib.baseboard_fab2(sch_1):page45_i111@mstr_sconn.sconn288_h44441004(chips)!SCONN288_H44441004_PIP-SCONN,HA!!!F144!DQ(5)!!!!
S!M_B_DQ<61>!J4G2!128!@baseboard_fab2_lib.baseboard_fab2(sch_1):page45_i111@mstr_sconn.sconn288_h44441004(chips)!SCONN288_H44441004_PIP-SCONN,HA!!!F144!DQ(60)!!!!
S!M_B_DQ<60>!J4G2!273!@baseboard_fab2_lib.baseboard_fab2(sch_1):page45_i111@mstr_sconn.sconn288_h44441004(chips)!SCONN288_H44441004_PIP-SCONN,HA!!!F144!DQ(61)!!!!
S!M_B_DQ<63>!J4G2!135!@baseboard_fab2_lib.baseboard_fab2(sch_1):page45_i111@mstr_sconn.sconn288_h44441004(chips)!SCONN288_H44441004_PIP-SCONN,HA!!!F144!DQ(62)!!!!
S!M_B_DQ<62>!J4G2!280!@baseboard_fab2_lib.baseboard_fab2(sch_1):page45_i111@mstr_sconn.sconn288_h44441004(chips)!SCONN288_H44441004_PIP-SCONN,HA!!!F144!DQ(63)!!!!
S!M_B_DQ<7>!J4G2!10!@baseboard_fab2_lib.baseboard_fab2(sch_1):page45_i111@mstr_sconn.sconn288_h44441004(chips)!SCONN288_H44441004_PIP-SCONN,HA!!!F144!DQ(6)!!!!
S!M_B_DQ<6>!J4G2!155!@baseboard_fab2_lib.baseboard_fab2(sch_1):page45_i111@mstr_sconn.sconn288_h44441004(chips)!SCONN288_H44441004_PIP-SCONN,HA!!!F144!DQ(7)!!!!
S!M_B_DQ<9>!J4G2!16!@baseboard_fab2_lib.baseboard_fab2(sch_1):page45_i111@mstr_sconn.sconn288_h44441004(chips)!SCONN288_H44441004_PIP-SCONN,HA!!!F144!DQ(8)!!!!
S!M_B_DQ<8>!J4G2!161!@baseboard_fab2_lib.baseboard_fab2(sch_1):page45_i111@mstr_sconn.sconn288_h44441004(chips)!SCONN288_H44441004_PIP-SCONN,HA!!!F144!DQ(9)!!!!
S!FM_DIMM_EVENT_COD_N!J4G2!78!@baseboard_fab2_lib.baseboard_fab2(sch_1):page45_i111@mstr_sconn.sconn288_h44441004(chips)!SCONN288_H44441004_PIP-SCONN,HA!!!F144!EVENT_N!!!!
S!M_B_ODT<0>!J4G2!87!@baseboard_fab2_lib.baseboard_fab2(sch_1):page45_i111@mstr_sconn.sconn288_h44441004(chips)!SCONN288_H44441004_PIP-SCONN,HA!!!F144!ODT(0)!!!!
S!M_B_ODT<1>!J4G2!91!@baseboard_fab2_lib.baseboard_fab2(sch_1):page45_i111@mstr_sconn.sconn288_h44441004(chips)!SCONN288_H44441004_PIP-SCONN,HA!!!F144!ODT(1)!!!!
S!M_B_PAR!J4G2!222!@baseboard_fab2_lib.baseboard_fab2(sch_1):page45_i111@mstr_sconn.sconn288_h44441004(chips)!SCONN288_H44441004_PIP-SCONN,HA!!!F144!PAR!!!!
S!M_ABC_RST_N!J4G2!58!@baseboard_fab2_lib.baseboard_fab2(sch_1):page45_i111@mstr_sconn.sconn288_h44441004(chips)!SCONN288_H44441004_PIP-SCONN,HA!!!F144!RESET_N!!!!
S!TP_CH_B_DIMM_B0_RFU_0!J4G2!205!@baseboard_fab2_lib.baseboard_fab2(sch_1):page45_i111@mstr_sconn.sconn288_h44441004(chips)!SCONN288_H44441004_PIP-SCONN,HA!!!F144!RFU(0)!!!!
S!TP_CH_B_DIMM_B0_RFU_1!J4G2!227!@baseboard_fab2_lib.baseboard_fab2(sch_1):page45_i111@mstr_sconn.sconn288_h44441004(chips)!SCONN288_H44441004_PIP-SCONN,HA!!!F144!RFU(1)!!!!
S!TP_CH_B_DIMM_B0_RFU_2!J4G2!144!@baseboard_fab2_lib.baseboard_fab2(sch_1):page45_i111@mstr_sconn.sconn288_h44441004(chips)!SCONN288_H44441004_PIP-SCONN,HA!!!F144!RFU(2)!!!!
S!M_B_CS_N<0>!J4G2!84!@baseboard_fab2_lib.baseboard_fab2(sch_1):page45_i111@mstr_sconn.sconn288_h44441004(chips)!SCONN288_H44441004_PIP-SCONN,HA!!!F144!S0_N!!!!
S!M_B_CS_N<1>!J4G2!89!@baseboard_fab2_lib.baseboard_fab2(sch_1):page45_i111@mstr_sconn.sconn288_h44441004(chips)!SCONN288_H44441004_PIP-SCONN,HA!!!F144!S1_N!!!!
S!M_B_CS_N<2>!J4G2!93!@baseboard_fab2_lib.baseboard_fab2(sch_1):page45_i111@mstr_sconn.sconn288_h44441004(chips)!SCONN288_H44441004_PIP-SCONN,HA!!!F144!S2_N_C(0)!!!!
S!M_B_CS_N<3>!J4G2!237!@baseboard_fab2_lib.baseboard_fab2(sch_1):page45_i111@mstr_sconn.sconn288_h44441004(chips)!SCONN288_H44441004_PIP-SCONN,HA!!!F144!S3_N_C(1)!!!!
S!GND!J4G2!139!@baseboard_fab2_lib.baseboard_fab2(sch_1):page45_i111@mstr_sconn.sconn288_h44441004(chips)!SCONN288_H44441004_PIP-SCONN,HA!!!F144!SA(0)!!!!
S!PVPP_ABC!J4G2!140!@baseboard_fab2_lib.baseboard_fab2(sch_1):page45_i111@mstr_sconn.sconn288_h44441004(chips)!SCONN288_H44441004_PIP-SCONN,HA!!!F144!SA(1)!!!!
S!GND!J4G2!238!@baseboard_fab2_lib.baseboard_fab2(sch_1):page45_i111@mstr_sconn.sconn288_h44441004(chips)!SCONN288_H44441004_PIP-SCONN,HA!!!F144!SA(2)!!!!
S!FM_ADR_COMPLETE_ABC_N!J4G2!230!@baseboard_fab2_lib.baseboard_fab2(sch_1):page45_i111@mstr_sconn.sconn288_h44441004(chips)!SCONN288_H44441004_PIP-SCONN,HA!!!F144!SAVE_N_NC!!!!
S!SMB_DDR_ABC_VPP_SCL!J4G2!141!@baseboard_fab2_lib.baseboard_fab2(sch_1):page45_i111@mstr_sconn.sconn288_h44441004(chips)!SCONN288_H44441004_PIP-SCONN,HA!!!F144!SCL!!!!
S!SMB_DDR_ABC_VPP_SDA!J4G2!285!@baseboard_fab2_lib.baseboard_fab2(sch_1):page45_i111@mstr_sconn.sconn288_h44441004(chips)!SCONN288_H44441004_PIP-SCONN,HA!!!F144!SDA!!!!
S!PVPP_ABC!J4G2!284!@baseboard_fab2_lib.baseboard_fab2(sch_1):page45_i111@mstr_sconn.sconn288_h44441004(chips)!SCONN288_H44441004_PIP-SCONN,HA!!!F144!VDDSPD!!!!
S!M_B_VREF!J4G2!146!@baseboard_fab2_lib.baseboard_fab2(sch_1):page45_i111@mstr_sconn.sconn288_h44441004(chips)!SCONN288_H44441004_PIP-SCONN,HA!!!F144!VREFCA!!!!
S!M_B_DQS_DN<0>!J4G2!152!@baseboard_fab2_lib.baseboard_fab2(sch_1):page45_i61@mstr_sconn.sconn288_h44441004(chips)!SCONN288_H44441004_PIP-SCONN,HA!!!F143!DQS0N!!!!
S!M_B_DQS_DP<0>!J4G2!153!@baseboard_fab2_lib.baseboard_fab2(sch_1):page45_i61@mstr_sconn.sconn288_h44441004(chips)!SCONN288_H44441004_PIP-SCONN,HA!!!F143!DQS0P!!!!
S!M_B_DQS_DN<10>!J4G2!19!@baseboard_fab2_lib.baseboard_fab2(sch_1):page45_i61@mstr_sconn.sconn288_h44441004(chips)!SCONN288_H44441004_PIP-SCONN,HA!!!F143!DQS10N!!!!
S!M_B_DQS_DP<10>!J4G2!18!@baseboard_fab2_lib.baseboard_fab2(sch_1):page45_i61@mstr_sconn.sconn288_h44441004(chips)!SCONN288_H44441004_PIP-SCONN,HA!!!F143!DQS10P!!!!
S!M_B_DQS_DN<11>!J4G2!30!@baseboard_fab2_lib.baseboard_fab2(sch_1):page45_i61@mstr_sconn.sconn288_h44441004(chips)!SCONN288_H44441004_PIP-SCONN,HA!!!F143!DQS11N!!!!
S!M_B_DQS_DP<11>!J4G2!29!@baseboard_fab2_lib.baseboard_fab2(sch_1):page45_i61@mstr_sconn.sconn288_h44441004(chips)!SCONN288_H44441004_PIP-SCONN,HA!!!F143!DQS11P!!!!
S!M_B_DQS_DN<12>!J4G2!41!@baseboard_fab2_lib.baseboard_fab2(sch_1):page45_i61@mstr_sconn.sconn288_h44441004(chips)!SCONN288_H44441004_PIP-SCONN,HA!!!F143!DQS12N!!!!
S!M_B_DQS_DP<12>!J4G2!40!@baseboard_fab2_lib.baseboard_fab2(sch_1):page45_i61@mstr_sconn.sconn288_h44441004(chips)!SCONN288_H44441004_PIP-SCONN,HA!!!F143!DQS12P!!!!
S!M_B_DQS_DN<13>!J4G2!100!@baseboard_fab2_lib.baseboard_fab2(sch_1):page45_i61@mstr_sconn.sconn288_h44441004(chips)!SCONN288_H44441004_PIP-SCONN,HA!!!F143!DQS13N!!!!
S!M_B_DQS_DP<13>!J4G2!99!@baseboard_fab2_lib.baseboard_fab2(sch_1):page45_i61@mstr_sconn.sconn288_h44441004(chips)!SCONN288_H44441004_PIP-SCONN,HA!!!F143!DQS13P!!!!
S!M_B_DQS_DN<14>!J4G2!111!@baseboard_fab2_lib.baseboard_fab2(sch_1):page45_i61@mstr_sconn.sconn288_h44441004(chips)!SCONN288_H44441004_PIP-SCONN,HA!!!F143!DQS14N!!!!
S!M_B_DQS_DP<14>!J4G2!110!@baseboard_fab2_lib.baseboard_fab2(sch_1):page45_i61@mstr_sconn.sconn288_h44441004(chips)!SCONN288_H44441004_PIP-SCONN,HA!!!F143!DQS14P!!!!
S!M_B_DQS_DN<15>!J4G2!122!@baseboard_fab2_lib.baseboard_fab2(sch_1):page45_i61@mstr_sconn.sconn288_h44441004(chips)!SCONN288_H44441004_PIP-SCONN,HA!!!F143!DQS15N!!!!
S!M_B_DQS_DP<15>!J4G2!121!@baseboard_fab2_lib.baseboard_fab2(sch_1):page45_i61@mstr_sconn.sconn288_h44441004(chips)!SCONN288_H44441004_PIP-SCONN,HA!!!F143!DQS15P!!!!
S!M_B_DQS_DN<16>!J4G2!133!@baseboard_fab2_lib.baseboard_fab2(sch_1):page45_i61@mstr_sconn.sconn288_h44441004(chips)!SCONN288_H44441004_PIP-SCONN,HA!!!F143!DQS16N!!!!
S!M_B_DQS_DP<16>!J4G2!132!@baseboard_fab2_lib.baseboard_fab2(sch_1):page45_i61@mstr_sconn.sconn288_h44441004(chips)!SCONN288_H44441004_PIP-SCONN,HA!!!F143!DQS16P!!!!
S!M_B_DQS_DN<17>!J4G2!52!@baseboard_fab2_lib.baseboard_fab2(sch_1):page45_i61@mstr_sconn.sconn288_h44441004(chips)!SCONN288_H44441004_PIP-SCONN,HA!!!F143!DQS17N!!!!
S!M_B_DQS_DP<17>!J4G2!51!@baseboard_fab2_lib.baseboard_fab2(sch_1):page45_i61@mstr_sconn.sconn288_h44441004(chips)!SCONN288_H44441004_PIP-SCONN,HA!!!F143!DQS17P!!!!
S!M_B_DQS_DN<1>!J4G2!163!@baseboard_fab2_lib.baseboard_fab2(sch_1):page45_i61@mstr_sconn.sconn288_h44441004(chips)!SCONN288_H44441004_PIP-SCONN,HA!!!F143!DQS1N!!!!
S!M_B_DQS_DP<1>!J4G2!164!@baseboard_fab2_lib.baseboard_fab2(sch_1):page45_i61@mstr_sconn.sconn288_h44441004(chips)!SCONN288_H44441004_PIP-SCONN,HA!!!F143!DQS1P!!!!
S!M_B_DQS_DN<2>!J4G2!174!@baseboard_fab2_lib.baseboard_fab2(sch_1):page45_i61@mstr_sconn.sconn288_h44441004(chips)!SCONN288_H44441004_PIP-SCONN,HA!!!F143!DQS2N!!!!
S!M_B_DQS_DP<2>!J4G2!175!@baseboard_fab2_lib.baseboard_fab2(sch_1):page45_i61@mstr_sconn.sconn288_h44441004(chips)!SCONN288_H44441004_PIP-SCONN,HA!!!F143!DQS2P!!!!
S!M_B_DQS_DN<3>!J4G2!185!@baseboard_fab2_lib.baseboard_fab2(sch_1):page45_i61@mstr_sconn.sconn288_h44441004(chips)!SCONN288_H44441004_PIP-SCONN,HA!!!F143!DQS3N!!!!
S!M_B_DQS_DP<3>!J4G2!186!@baseboard_fab2_lib.baseboard_fab2(sch_1):page45_i61@mstr_sconn.sconn288_h44441004(chips)!SCONN288_H44441004_PIP-SCONN,HA!!!F143!DQS3P!!!!
S!M_B_DQS_DN<4>!J4G2!244!@baseboard_fab2_lib.baseboard_fab2(sch_1):page45_i61@mstr_sconn.sconn288_h44441004(chips)!SCONN288_H44441004_PIP-SCONN,HA!!!F143!DQS4N!!!!
S!M_B_DQS_DP<4>!J4G2!245!@baseboard_fab2_lib.baseboard_fab2(sch_1):page45_i61@mstr_sconn.sconn288_h44441004(chips)!SCONN288_H44441004_PIP-SCONN,HA!!!F143!DQS4P!!!!
S!M_B_DQS_DN<5>!J4G2!255!@baseboard_fab2_lib.baseboard_fab2(sch_1):page45_i61@mstr_sconn.sconn288_h44441004(chips)!SCONN288_H44441004_PIP-SCONN,HA!!!F143!DQS5N!!!!
S!M_B_DQS_DP<5>!J4G2!256!@baseboard_fab2_lib.baseboard_fab2(sch_1):page45_i61@mstr_sconn.sconn288_h44441004(chips)!SCONN288_H44441004_PIP-SCONN,HA!!!F143!DQS5P!!!!
S!M_B_DQS_DN<6>!J4G2!266!@baseboard_fab2_lib.baseboard_fab2(sch_1):page45_i61@mstr_sconn.sconn288_h44441004(chips)!SCONN288_H44441004_PIP-SCONN,HA!!!F143!DQS6N!!!!
S!M_B_DQS_DP<6>!J4G2!267!@baseboard_fab2_lib.baseboard_fab2(sch_1):page45_i61@mstr_sconn.sconn288_h44441004(chips)!SCONN288_H44441004_PIP-SCONN,HA!!!F143!DQS6P!!!!
S!M_B_DQS_DN<7>!J4G2!277!@baseboard_fab2_lib.baseboard_fab2(sch_1):page45_i61@mstr_sconn.sconn288_h44441004(chips)!SCONN288_H44441004_PIP-SCONN,HA!!!F143!DQS7N!!!!
S!M_B_DQS_DP<7>!J4G2!278!@baseboard_fab2_lib.baseboard_fab2(sch_1):page45_i61@mstr_sconn.sconn288_h44441004(chips)!SCONN288_H44441004_PIP-SCONN,HA!!!F143!DQS7P!!!!
S!M_B_DQS_DN<8>!J4G2!196!@baseboard_fab2_lib.baseboard_fab2(sch_1):page45_i61@mstr_sconn.sconn288_h44441004(chips)!SCONN288_H44441004_PIP-SCONN,HA!!!F143!DQS8N!!!!
S!M_B_DQS_DP<8>!J4G2!197!@baseboard_fab2_lib.baseboard_fab2(sch_1):page45_i61@mstr_sconn.sconn288_h44441004(chips)!SCONN288_H44441004_PIP-SCONN,HA!!!F143!DQS8P!!!!
S!M_B_DQS_DN<9>!J4G2!8!@baseboard_fab2_lib.baseboard_fab2(sch_1):page45_i61@mstr_sconn.sconn288_h44441004(chips)!SCONN288_H44441004_PIP-SCONN,HA!!!F143!DQS9N!!!!
S!M_B_DQS_DP<9>!J4G2!7!@baseboard_fab2_lib.baseboard_fab2(sch_1):page45_i61@mstr_sconn.sconn288_h44441004(chips)!SCONN288_H44441004_PIP-SCONN,HA!!!F143!DQS9P!!!!
S!GND!J4G2!283!@baseboard_fab2_lib.baseboard_fab2(sch_1):page45_i43@mstr_sconn.sconn288_h44441004(chips)!SCONN288_H44441004_PIP-SCONN,HA!!!F142!VSS(0)!!!!
S!GND!J4G2!261!@baseboard_fab2_lib.baseboard_fab2(sch_1):page45_i43@mstr_sconn.sconn288_h44441004(chips)!SCONN288_H44441004_PIP-SCONN,HA!!!F142!VSS(10)!!!!
S!GND!J4G2!259!@baseboard_fab2_lib.baseboard_fab2(sch_1):page45_i43@mstr_sconn.sconn288_h44441004(chips)!SCONN288_H44441004_PIP-SCONN,HA!!!F142!VSS(11)!!!!
S!GND!J4G2!257!@baseboard_fab2_lib.baseboard_fab2(sch_1):page45_i43@mstr_sconn.sconn288_h44441004(chips)!SCONN288_H44441004_PIP-SCONN,HA!!!F142!VSS(12)!!!!
S!GND!J4G2!254!@baseboard_fab2_lib.baseboard_fab2(sch_1):page45_i43@mstr_sconn.sconn288_h44441004(chips)!SCONN288_H44441004_PIP-SCONN,HA!!!F142!VSS(13)!!!!
S!GND!J4G2!252!@baseboard_fab2_lib.baseboard_fab2(sch_1):page45_i43@mstr_sconn.sconn288_h44441004(chips)!SCONN288_H44441004_PIP-SCONN,HA!!!F142!VSS(14)!!!!
S!GND!J4G2!250!@baseboard_fab2_lib.baseboard_fab2(sch_1):page45_i43@mstr_sconn.sconn288_h44441004(chips)!SCONN288_H44441004_PIP-SCONN,HA!!!F142!VSS(15)!!!!
S!GND!J4G2!248!@baseboard_fab2_lib.baseboard_fab2(sch_1):page45_i43@mstr_sconn.sconn288_h44441004(chips)!SCONN288_H44441004_PIP-SCONN,HA!!!F142!VSS(16)!!!!
S!GND!J4G2!246!@baseboard_fab2_lib.baseboard_fab2(sch_1):page45_i43@mstr_sconn.sconn288_h44441004(chips)!SCONN288_H44441004_PIP-SCONN,HA!!!F142!VSS(17)!!!!
S!GND!J4G2!243!@baseboard_fab2_lib.baseboard_fab2(sch_1):page45_i43@mstr_sconn.sconn288_h44441004(chips)!SCONN288_H44441004_PIP-SCONN,HA!!!F142!VSS(18)!!!!
S!GND!J4G2!241!@baseboard_fab2_lib.baseboard_fab2(sch_1):page45_i43@mstr_sconn.sconn288_h44441004(chips)!SCONN288_H44441004_PIP-SCONN,HA!!!F142!VSS(19)!!!!
S!GND!J4G2!281!@baseboard_fab2_lib.baseboard_fab2(sch_1):page45_i43@mstr_sconn.sconn288_h44441004(chips)!SCONN288_H44441004_PIP-SCONN,HA!!!F142!VSS(1)!!!!
S!GND!J4G2!239!@baseboard_fab2_lib.baseboard_fab2(sch_1):page45_i43@mstr_sconn.sconn288_h44441004(chips)!SCONN288_H44441004_PIP-SCONN,HA!!!F142!VSS(20)!!!!
S!GND!J4G2!202!@baseboard_fab2_lib.baseboard_fab2(sch_1):page45_i43@mstr_sconn.sconn288_h44441004(chips)!SCONN288_H44441004_PIP-SCONN,HA!!!F142!VSS(21)!!!!
S!GND!J4G2!200!@baseboard_fab2_lib.baseboard_fab2(sch_1):page45_i43@mstr_sconn.sconn288_h44441004(chips)!SCONN288_H44441004_PIP-SCONN,HA!!!F142!VSS(22)!!!!
S!GND!J4G2!198!@baseboard_fab2_lib.baseboard_fab2(sch_1):page45_i43@mstr_sconn.sconn288_h44441004(chips)!SCONN288_H44441004_PIP-SCONN,HA!!!F142!VSS(23)!!!!
S!GND!J4G2!195!@baseboard_fab2_lib.baseboard_fab2(sch_1):page45_i43@mstr_sconn.sconn288_h44441004(chips)!SCONN288_H44441004_PIP-SCONN,HA!!!F142!VSS(24)!!!!
S!GND!J4G2!193!@baseboard_fab2_lib.baseboard_fab2(sch_1):page45_i43@mstr_sconn.sconn288_h44441004(chips)!SCONN288_H44441004_PIP-SCONN,HA!!!F142!VSS(25)!!!!
S!GND!J4G2!191!@baseboard_fab2_lib.baseboard_fab2(sch_1):page45_i43@mstr_sconn.sconn288_h44441004(chips)!SCONN288_H44441004_PIP-SCONN,HA!!!F142!VSS(26)!!!!
S!GND!J4G2!189!@baseboard_fab2_lib.baseboard_fab2(sch_1):page45_i43@mstr_sconn.sconn288_h44441004(chips)!SCONN288_H44441004_PIP-SCONN,HA!!!F142!VSS(27)!!!!
S!GND!J4G2!187!@baseboard_fab2_lib.baseboard_fab2(sch_1):page45_i43@mstr_sconn.sconn288_h44441004(chips)!SCONN288_H44441004_PIP-SCONN,HA!!!F142!VSS(28)!!!!
S!GND!J4G2!184!@baseboard_fab2_lib.baseboard_fab2(sch_1):page45_i43@mstr_sconn.sconn288_h44441004(chips)!SCONN288_H44441004_PIP-SCONN,HA!!!F142!VSS(29)!!!!
S!GND!J4G2!279!@baseboard_fab2_lib.baseboard_fab2(sch_1):page45_i43@mstr_sconn.sconn288_h44441004(chips)!SCONN288_H44441004_PIP-SCONN,HA!!!F142!VSS(2)!!!!
S!GND!J4G2!182!@baseboard_fab2_lib.baseboard_fab2(sch_1):page45_i43@mstr_sconn.sconn288_h44441004(chips)!SCONN288_H44441004_PIP-SCONN,HA!!!F142!VSS(30)!!!!
S!GND!J4G2!180!@baseboard_fab2_lib.baseboard_fab2(sch_1):page45_i43@mstr_sconn.sconn288_h44441004(chips)!SCONN288_H44441004_PIP-SCONN,HA!!!F142!VSS(31)!!!!
S!GND!J4G2!178!@baseboard_fab2_lib.baseboard_fab2(sch_1):page45_i43@mstr_sconn.sconn288_h44441004(chips)!SCONN288_H44441004_PIP-SCONN,HA!!!F142!VSS(32)!!!!
S!GND!J4G2!176!@baseboard_fab2_lib.baseboard_fab2(sch_1):page45_i43@mstr_sconn.sconn288_h44441004(chips)!SCONN288_H44441004_PIP-SCONN,HA!!!F142!VSS(33)!!!!
S!GND!J4G2!173!@baseboard_fab2_lib.baseboard_fab2(sch_1):page45_i43@mstr_sconn.sconn288_h44441004(chips)!SCONN288_H44441004_PIP-SCONN,HA!!!F142!VSS(34)!!!!
S!GND!J4G2!171!@baseboard_fab2_lib.baseboard_fab2(sch_1):page45_i43@mstr_sconn.sconn288_h44441004(chips)!SCONN288_H44441004_PIP-SCONN,HA!!!F142!VSS(35)!!!!
S!GND!J4G2!169!@baseboard_fab2_lib.baseboard_fab2(sch_1):page45_i43@mstr_sconn.sconn288_h44441004(chips)!SCONN288_H44441004_PIP-SCONN,HA!!!F142!VSS(36)!!!!
S!GND!J4G2!167!@baseboard_fab2_lib.baseboard_fab2(sch_1):page45_i43@mstr_sconn.sconn288_h44441004(chips)!SCONN288_H44441004_PIP-SCONN,HA!!!F142!VSS(37)!!!!
S!GND!J4G2!165!@baseboard_fab2_lib.baseboard_fab2(sch_1):page45_i43@mstr_sconn.sconn288_h44441004(chips)!SCONN288_H44441004_PIP-SCONN,HA!!!F142!VSS(38)!!!!
S!GND!J4G2!162!@baseboard_fab2_lib.baseboard_fab2(sch_1):page45_i43@mstr_sconn.sconn288_h44441004(chips)!SCONN288_H44441004_PIP-SCONN,HA!!!F142!VSS(39)!!!!
S!GND!J4G2!276!@baseboard_fab2_lib.baseboard_fab2(sch_1):page45_i43@mstr_sconn.sconn288_h44441004(chips)!SCONN288_H44441004_PIP-SCONN,HA!!!F142!VSS(3)!!!!
S!GND!J4G2!160!@baseboard_fab2_lib.baseboard_fab2(sch_1):page45_i43@mstr_sconn.sconn288_h44441004(chips)!SCONN288_H44441004_PIP-SCONN,HA!!!F142!VSS(40)!!!!
S!GND!J4G2!158!@baseboard_fab2_lib.baseboard_fab2(sch_1):page45_i43@mstr_sconn.sconn288_h44441004(chips)!SCONN288_H44441004_PIP-SCONN,HA!!!F142!VSS(41)!!!!
S!GND!J4G2!156!@baseboard_fab2_lib.baseboard_fab2(sch_1):page45_i43@mstr_sconn.sconn288_h44441004(chips)!SCONN288_H44441004_PIP-SCONN,HA!!!F142!VSS(42)!!!!
S!GND!J4G2!154!@baseboard_fab2_lib.baseboard_fab2(sch_1):page45_i43@mstr_sconn.sconn288_h44441004(chips)!SCONN288_H44441004_PIP-SCONN,HA!!!F142!VSS(43)!!!!
S!GND!J4G2!151!@baseboard_fab2_lib.baseboard_fab2(sch_1):page45_i43@mstr_sconn.sconn288_h44441004(chips)!SCONN288_H44441004_PIP-SCONN,HA!!!F142!VSS(44)!!!!
S!GND!J4G2!149!@baseboard_fab2_lib.baseboard_fab2(sch_1):page45_i43@mstr_sconn.sconn288_h44441004(chips)!SCONN288_H44441004_PIP-SCONN,HA!!!F142!VSS(45)!!!!
S!GND!J4G2!147!@baseboard_fab2_lib.baseboard_fab2(sch_1):page45_i43@mstr_sconn.sconn288_h44441004(chips)!SCONN288_H44441004_PIP-SCONN,HA!!!F142!VSS(46)!!!!
S!GND!J4G2!138!@baseboard_fab2_lib.baseboard_fab2(sch_1):page45_i43@mstr_sconn.sconn288_h44441004(chips)!SCONN288_H44441004_PIP-SCONN,HA!!!F142!VSS(47)!!!!
S!GND!J4G2!136!@baseboard_fab2_lib.baseboard_fab2(sch_1):page45_i43@mstr_sconn.sconn288_h44441004(chips)!SCONN288_H44441004_PIP-SCONN,HA!!!F142!VSS(48)!!!!
S!GND!J4G2!134!@baseboard_fab2_lib.baseboard_fab2(sch_1):page45_i43@mstr_sconn.sconn288_h44441004(chips)!SCONN288_H44441004_PIP-SCONN,HA!!!F142!VSS(49)!!!!
S!GND!J4G2!274!@baseboard_fab2_lib.baseboard_fab2(sch_1):page45_i43@mstr_sconn.sconn288_h44441004(chips)!SCONN288_H44441004_PIP-SCONN,HA!!!F142!VSS(4)!!!!
S!GND!J4G2!131!@baseboard_fab2_lib.baseboard_fab2(sch_1):page45_i43@mstr_sconn.sconn288_h44441004(chips)!SCONN288_H44441004_PIP-SCONN,HA!!!F142!VSS(50)!!!!
S!GND!J4G2!129!@baseboard_fab2_lib.baseboard_fab2(sch_1):page45_i43@mstr_sconn.sconn288_h44441004(chips)!SCONN288_H44441004_PIP-SCONN,HA!!!F142!VSS(51)!!!!
S!GND!J4G2!127!@baseboard_fab2_lib.baseboard_fab2(sch_1):page45_i43@mstr_sconn.sconn288_h44441004(chips)!SCONN288_H44441004_PIP-SCONN,HA!!!F142!VSS(52)!!!!
S!GND!J4G2!125!@baseboard_fab2_lib.baseboard_fab2(sch_1):page45_i43@mstr_sconn.sconn288_h44441004(chips)!SCONN288_H44441004_PIP-SCONN,HA!!!F142!VSS(53)!!!!
S!GND!J4G2!123!@baseboard_fab2_lib.baseboard_fab2(sch_1):page45_i43@mstr_sconn.sconn288_h44441004(chips)!SCONN288_H44441004_PIP-SCONN,HA!!!F142!VSS(54)!!!!
S!GND!J4G2!120!@baseboard_fab2_lib.baseboard_fab2(sch_1):page45_i43@mstr_sconn.sconn288_h44441004(chips)!SCONN288_H44441004_PIP-SCONN,HA!!!F142!VSS(55)!!!!
S!GND!J4G2!118!@baseboard_fab2_lib.baseboard_fab2(sch_1):page45_i43@mstr_sconn.sconn288_h44441004(chips)!SCONN288_H44441004_PIP-SCONN,HA!!!F142!VSS(56)!!!!
S!GND!J4G2!116!@baseboard_fab2_lib.baseboard_fab2(sch_1):page45_i43@mstr_sconn.sconn288_h44441004(chips)!SCONN288_H44441004_PIP-SCONN,HA!!!F142!VSS(57)!!!!
S!GND!J4G2!114!@baseboard_fab2_lib.baseboard_fab2(sch_1):page45_i43@mstr_sconn.sconn288_h44441004(chips)!SCONN288_H44441004_PIP-SCONN,HA!!!F142!VSS(58)!!!!
S!GND!J4G2!112!@baseboard_fab2_lib.baseboard_fab2(sch_1):page45_i43@mstr_sconn.sconn288_h44441004(chips)!SCONN288_H44441004_PIP-SCONN,HA!!!F142!VSS(59)!!!!
S!GND!J4G2!272!@baseboard_fab2_lib.baseboard_fab2(sch_1):page45_i43@mstr_sconn.sconn288_h44441004(chips)!SCONN288_H44441004_PIP-SCONN,HA!!!F142!VSS(5)!!!!
S!GND!J4G2!109!@baseboard_fab2_lib.baseboard_fab2(sch_1):page45_i43@mstr_sconn.sconn288_h44441004(chips)!SCONN288_H44441004_PIP-SCONN,HA!!!F142!VSS(60)!!!!
S!GND!J4G2!107!@baseboard_fab2_lib.baseboard_fab2(sch_1):page45_i43@mstr_sconn.sconn288_h44441004(chips)!SCONN288_H44441004_PIP-SCONN,HA!!!F142!VSS(61)!!!!
S!GND!J4G2!105!@baseboard_fab2_lib.baseboard_fab2(sch_1):page45_i43@mstr_sconn.sconn288_h44441004(chips)!SCONN288_H44441004_PIP-SCONN,HA!!!F142!VSS(62)!!!!
S!GND!J4G2!103!@baseboard_fab2_lib.baseboard_fab2(sch_1):page45_i43@mstr_sconn.sconn288_h44441004(chips)!SCONN288_H44441004_PIP-SCONN,HA!!!F142!VSS(63)!!!!
S!GND!J4G2!101!@baseboard_fab2_lib.baseboard_fab2(sch_1):page45_i43@mstr_sconn.sconn288_h44441004(chips)!SCONN288_H44441004_PIP-SCONN,HA!!!F142!VSS(64)!!!!
S!GND!J4G2!98!@baseboard_fab2_lib.baseboard_fab2(sch_1):page45_i43@mstr_sconn.sconn288_h44441004(chips)!SCONN288_H44441004_PIP-SCONN,HA!!!F142!VSS(65)!!!!
S!GND!J4G2!96!@baseboard_fab2_lib.baseboard_fab2(sch_1):page45_i43@mstr_sconn.sconn288_h44441004(chips)!SCONN288_H44441004_PIP-SCONN,HA!!!F142!VSS(66)!!!!
S!GND!J4G2!94!@baseboard_fab2_lib.baseboard_fab2(sch_1):page45_i43@mstr_sconn.sconn288_h44441004(chips)!SCONN288_H44441004_PIP-SCONN,HA!!!F142!VSS(67)!!!!
S!GND!J4G2!57!@baseboard_fab2_lib.baseboard_fab2(sch_1):page45_i43@mstr_sconn.sconn288_h44441004(chips)!SCONN288_H44441004_PIP-SCONN,HA!!!F142!VSS(68)!!!!
S!GND!J4G2!55!@baseboard_fab2_lib.baseboard_fab2(sch_1):page45_i43@mstr_sconn.sconn288_h44441004(chips)!SCONN288_H44441004_PIP-SCONN,HA!!!F142!VSS(69)!!!!
S!GND!J4G2!270!@baseboard_fab2_lib.baseboard_fab2(sch_1):page45_i43@mstr_sconn.sconn288_h44441004(chips)!SCONN288_H44441004_PIP-SCONN,HA!!!F142!VSS(6)!!!!
S!GND!J4G2!53!@baseboard_fab2_lib.baseboard_fab2(sch_1):page45_i43@mstr_sconn.sconn288_h44441004(chips)!SCONN288_H44441004_PIP-SCONN,HA!!!F142!VSS(70)!!!!
S!GND!J4G2!50!@baseboard_fab2_lib.baseboard_fab2(sch_1):page45_i43@mstr_sconn.sconn288_h44441004(chips)!SCONN288_H44441004_PIP-SCONN,HA!!!F142!VSS(71)!!!!
S!GND!J4G2!48!@baseboard_fab2_lib.baseboard_fab2(sch_1):page45_i43@mstr_sconn.sconn288_h44441004(chips)!SCONN288_H44441004_PIP-SCONN,HA!!!F142!VSS(72)!!!!
S!GND!J4G2!46!@baseboard_fab2_lib.baseboard_fab2(sch_1):page45_i43@mstr_sconn.sconn288_h44441004(chips)!SCONN288_H44441004_PIP-SCONN,HA!!!F142!VSS(73)!!!!
S!GND!J4G2!44!@baseboard_fab2_lib.baseboard_fab2(sch_1):page45_i43@mstr_sconn.sconn288_h44441004(chips)!SCONN288_H44441004_PIP-SCONN,HA!!!F142!VSS(74)!!!!
S!GND!J4G2!42!@baseboard_fab2_lib.baseboard_fab2(sch_1):page45_i43@mstr_sconn.sconn288_h44441004(chips)!SCONN288_H44441004_PIP-SCONN,HA!!!F142!VSS(75)!!!!
S!GND!J4G2!39!@baseboard_fab2_lib.baseboard_fab2(sch_1):page45_i43@mstr_sconn.sconn288_h44441004(chips)!SCONN288_H44441004_PIP-SCONN,HA!!!F142!VSS(76)!!!!
S!GND!J4G2!37!@baseboard_fab2_lib.baseboard_fab2(sch_1):page45_i43@mstr_sconn.sconn288_h44441004(chips)!SCONN288_H44441004_PIP-SCONN,HA!!!F142!VSS(77)!!!!
S!GND!J4G2!35!@baseboard_fab2_lib.baseboard_fab2(sch_1):page45_i43@mstr_sconn.sconn288_h44441004(chips)!SCONN288_H44441004_PIP-SCONN,HA!!!F142!VSS(78)!!!!
S!GND!J4G2!33!@baseboard_fab2_lib.baseboard_fab2(sch_1):page45_i43@mstr_sconn.sconn288_h44441004(chips)!SCONN288_H44441004_PIP-SCONN,HA!!!F142!VSS(79)!!!!
S!GND!J4G2!268!@baseboard_fab2_lib.baseboard_fab2(sch_1):page45_i43@mstr_sconn.sconn288_h44441004(chips)!SCONN288_H44441004_PIP-SCONN,HA!!!F142!VSS(7)!!!!
S!GND!J4G2!31!@baseboard_fab2_lib.baseboard_fab2(sch_1):page45_i43@mstr_sconn.sconn288_h44441004(chips)!SCONN288_H44441004_PIP-SCONN,HA!!!F142!VSS(80)!!!!
S!GND!J4G2!28!@baseboard_fab2_lib.baseboard_fab2(sch_1):page45_i43@mstr_sconn.sconn288_h44441004(chips)!SCONN288_H44441004_PIP-SCONN,HA!!!F142!VSS(81)!!!!
S!GND!J4G2!26!@baseboard_fab2_lib.baseboard_fab2(sch_1):page45_i43@mstr_sconn.sconn288_h44441004(chips)!SCONN288_H44441004_PIP-SCONN,HA!!!F142!VSS(82)!!!!
S!GND!J4G2!24!@baseboard_fab2_lib.baseboard_fab2(sch_1):page45_i43@mstr_sconn.sconn288_h44441004(chips)!SCONN288_H44441004_PIP-SCONN,HA!!!F142!VSS(83)!!!!
S!GND!J4G2!22!@baseboard_fab2_lib.baseboard_fab2(sch_1):page45_i43@mstr_sconn.sconn288_h44441004(chips)!SCONN288_H44441004_PIP-SCONN,HA!!!F142!VSS(84)!!!!
S!GND!J4G2!20!@baseboard_fab2_lib.baseboard_fab2(sch_1):page45_i43@mstr_sconn.sconn288_h44441004(chips)!SCONN288_H44441004_PIP-SCONN,HA!!!F142!VSS(85)!!!!
S!GND!J4G2!17!@baseboard_fab2_lib.baseboard_fab2(sch_1):page45_i43@mstr_sconn.sconn288_h44441004(chips)!SCONN288_H44441004_PIP-SCONN,HA!!!F142!VSS(86)!!!!
S!GND!J4G2!15!@baseboard_fab2_lib.baseboard_fab2(sch_1):page45_i43@mstr_sconn.sconn288_h44441004(chips)!SCONN288_H44441004_PIP-SCONN,HA!!!F142!VSS(87)!!!!
S!GND!J4G2!13!@baseboard_fab2_lib.baseboard_fab2(sch_1):page45_i43@mstr_sconn.sconn288_h44441004(chips)!SCONN288_H44441004_PIP-SCONN,HA!!!F142!VSS(88)!!!!
S!GND!J4G2!11!@baseboard_fab2_lib.baseboard_fab2(sch_1):page45_i43@mstr_sconn.sconn288_h44441004(chips)!SCONN288_H44441004_PIP-SCONN,HA!!!F142!VSS(89)!!!!
S!GND!J4G2!265!@baseboard_fab2_lib.baseboard_fab2(sch_1):page45_i43@mstr_sconn.sconn288_h44441004(chips)!SCONN288_H44441004_PIP-SCONN,HA!!!F142!VSS(8)!!!!
S!GND!J4G2!9!@baseboard_fab2_lib.baseboard_fab2(sch_1):page45_i43@mstr_sconn.sconn288_h44441004(chips)!SCONN288_H44441004_PIP-SCONN,HA!!!F142!VSS(90)!!!!
S!GND!J4G2!6!@baseboard_fab2_lib.baseboard_fab2(sch_1):page45_i43@mstr_sconn.sconn288_h44441004(chips)!SCONN288_H44441004_PIP-SCONN,HA!!!F142!VSS(91)!!!!
S!GND!J4G2!4!@baseboard_fab2_lib.baseboard_fab2(sch_1):page45_i43@mstr_sconn.sconn288_h44441004(chips)!SCONN288_H44441004_PIP-SCONN,HA!!!F142!VSS(92)!!!!
S!GND!J4G2!2!@baseboard_fab2_lib.baseboard_fab2(sch_1):page45_i43@mstr_sconn.sconn288_h44441004(chips)!SCONN288_H44441004_PIP-SCONN,HA!!!F142!VSS(93)!!!!
S!GND!J4G2!263!@baseboard_fab2_lib.baseboard_fab2(sch_1):page45_i43@mstr_sconn.sconn288_h44441004(chips)!SCONN288_H44441004_PIP-SCONN,HA!!!F142!VSS(9)!!!!
S!P12V_NVDIMM_ABC!J4G2!145!@baseboard_fab2_lib.baseboard_fab2(sch_1):page45_i169@mstr_sconn.sconn288_h44441004(chips)!SCONN288_H44441004_PIP-SCONN,HA!!!F141!\12v\(0)!!!!
S!P12V_NVDIMM_ABC!J4G2!1!@baseboard_fab2_lib.baseboard_fab2(sch_1):page45_i169@mstr_sconn.sconn288_h44441004(chips)!SCONN288_H44441004_PIP-SCONN,HA!!!F141!\12v\(1)!!!!
S!PVDDQ_ABC!J4G2!236!@baseboard_fab2_lib.baseboard_fab2(sch_1):page45_i169@mstr_sconn.sconn288_h44441004(chips)!SCONN288_H44441004_PIP-SCONN,HA!!!F141!VDD(0)!!!!
S!PVDDQ_ABC!J4G2!209!@baseboard_fab2_lib.baseboard_fab2(sch_1):page45_i169@mstr_sconn.sconn288_h44441004(chips)!SCONN288_H44441004_PIP-SCONN,HA!!!F141!VDD(10)!!!!
S!PVDDQ_ABC!J4G2!206!@baseboard_fab2_lib.baseboard_fab2(sch_1):page45_i169@mstr_sconn.sconn288_h44441004(chips)!SCONN288_H44441004_PIP-SCONN,HA!!!F141!VDD(11)!!!!
S!PVDDQ_ABC!J4G2!204!@baseboard_fab2_lib.baseboard_fab2(sch_1):page45_i169@mstr_sconn.sconn288_h44441004(chips)!SCONN288_H44441004_PIP-SCONN,HA!!!F141!VDD(12)!!!!
S!PVDDQ_ABC!J4G2!92!@baseboard_fab2_lib.baseboard_fab2(sch_1):page45_i169@mstr_sconn.sconn288_h44441004(chips)!SCONN288_H44441004_PIP-SCONN,HA!!!F141!VDD(13)!!!!
S!PVDDQ_ABC!J4G2!90!@baseboard_fab2_lib.baseboard_fab2(sch_1):page45_i169@mstr_sconn.sconn288_h44441004(chips)!SCONN288_H44441004_PIP-SCONN,HA!!!F141!VDD(14)!!!!
S!PVDDQ_ABC!J4G2!88!@baseboard_fab2_lib.baseboard_fab2(sch_1):page45_i169@mstr_sconn.sconn288_h44441004(chips)!SCONN288_H44441004_PIP-SCONN,HA!!!F141!VDD(15)!!!!
S!PVDDQ_ABC!J4G2!85!@baseboard_fab2_lib.baseboard_fab2(sch_1):page45_i169@mstr_sconn.sconn288_h44441004(chips)!SCONN288_H44441004_PIP-SCONN,HA!!!F141!VDD(16)!!!!
S!PVDDQ_ABC!J4G2!83!@baseboard_fab2_lib.baseboard_fab2(sch_1):page45_i169@mstr_sconn.sconn288_h44441004(chips)!SCONN288_H44441004_PIP-SCONN,HA!!!F141!VDD(17)!!!!
S!PVDDQ_ABC!J4G2!80!@baseboard_fab2_lib.baseboard_fab2(sch_1):page45_i169@mstr_sconn.sconn288_h44441004(chips)!SCONN288_H44441004_PIP-SCONN,HA!!!F141!VDD(18)!!!!
S!PVDDQ_ABC!J4G2!76!@baseboard_fab2_lib.baseboard_fab2(sch_1):page45_i169@mstr_sconn.sconn288_h44441004(chips)!SCONN288_H44441004_PIP-SCONN,HA!!!F141!VDD(19)!!!!
S!PVDDQ_ABC!J4G2!233!@baseboard_fab2_lib.baseboard_fab2(sch_1):page45_i169@mstr_sconn.sconn288_h44441004(chips)!SCONN288_H44441004_PIP-SCONN,HA!!!F141!VDD(1)!!!!
S!PVDDQ_ABC!J4G2!73!@baseboard_fab2_lib.baseboard_fab2(sch_1):page45_i169@mstr_sconn.sconn288_h44441004(chips)!SCONN288_H44441004_PIP-SCONN,HA!!!F141!VDD(20)!!!!
S!PVDDQ_ABC!J4G2!70!@baseboard_fab2_lib.baseboard_fab2(sch_1):page45_i169@mstr_sconn.sconn288_h44441004(chips)!SCONN288_H44441004_PIP-SCONN,HA!!!F141!VDD(21)!!!!
S!PVDDQ_ABC!J4G2!67!@baseboard_fab2_lib.baseboard_fab2(sch_1):page45_i169@mstr_sconn.sconn288_h44441004(chips)!SCONN288_H44441004_PIP-SCONN,HA!!!F141!VDD(22)!!!!
S!PVDDQ_ABC!J4G2!64!@baseboard_fab2_lib.baseboard_fab2(sch_1):page45_i169@mstr_sconn.sconn288_h44441004(chips)!SCONN288_H44441004_PIP-SCONN,HA!!!F141!VDD(23)!!!!
S!PVDDQ_ABC!J4G2!61!@baseboard_fab2_lib.baseboard_fab2(sch_1):page45_i169@mstr_sconn.sconn288_h44441004(chips)!SCONN288_H44441004_PIP-SCONN,HA!!!F141!VDD(24)!!!!
S!PVDDQ_ABC!J4G2!59!@baseboard_fab2_lib.baseboard_fab2(sch_1):page45_i169@mstr_sconn.sconn288_h44441004(chips)!SCONN288_H44441004_PIP-SCONN,HA!!!F141!VDD(25)!!!!
S!PVDDQ_ABC!J4G2!231!@baseboard_fab2_lib.baseboard_fab2(sch_1):page45_i169@mstr_sconn.sconn288_h44441004(chips)!SCONN288_H44441004_PIP-SCONN,HA!!!F141!VDD(2)!!!!
S!PVDDQ_ABC!J4G2!229!@baseboard_fab2_lib.baseboard_fab2(sch_1):page45_i169@mstr_sconn.sconn288_h44441004(chips)!SCONN288_H44441004_PIP-SCONN,HA!!!F141!VDD(3)!!!!
S!PVDDQ_ABC!J4G2!226!@baseboard_fab2_lib.baseboard_fab2(sch_1):page45_i169@mstr_sconn.sconn288_h44441004(chips)!SCONN288_H44441004_PIP-SCONN,HA!!!F141!VDD(4)!!!!
S!PVDDQ_ABC!J4G2!223!@baseboard_fab2_lib.baseboard_fab2(sch_1):page45_i169@mstr_sconn.sconn288_h44441004(chips)!SCONN288_H44441004_PIP-SCONN,HA!!!F141!VDD(5)!!!!
S!PVDDQ_ABC!J4G2!220!@baseboard_fab2_lib.baseboard_fab2(sch_1):page45_i169@mstr_sconn.sconn288_h44441004(chips)!SCONN288_H44441004_PIP-SCONN,HA!!!F141!VDD(6)!!!!
S!PVDDQ_ABC!J4G2!217!@baseboard_fab2_lib.baseboard_fab2(sch_1):page45_i169@mstr_sconn.sconn288_h44441004(chips)!SCONN288_H44441004_PIP-SCONN,HA!!!F141!VDD(7)!!!!
S!PVDDQ_ABC!J4G2!215!@baseboard_fab2_lib.baseboard_fab2(sch_1):page45_i169@mstr_sconn.sconn288_h44441004(chips)!SCONN288_H44441004_PIP-SCONN,HA!!!F141!VDD(8)!!!!
S!PVDDQ_ABC!J4G2!212!@baseboard_fab2_lib.baseboard_fab2(sch_1):page45_i169@mstr_sconn.sconn288_h44441004(chips)!SCONN288_H44441004_PIP-SCONN,HA!!!F141!VDD(9)!!!!
S!PVPP_ABC!J4G2!287!@baseboard_fab2_lib.baseboard_fab2(sch_1):page45_i169@mstr_sconn.sconn288_h44441004(chips)!SCONN288_H44441004_PIP-SCONN,HA!!!F141!VPP(0)!!!!
S!PVPP_ABC!J4G2!286!@baseboard_fab2_lib.baseboard_fab2(sch_1):page45_i169@mstr_sconn.sconn288_h44441004(chips)!SCONN288_H44441004_PIP-SCONN,HA!!!F141!VPP(1)!!!!
S!PVPP_ABC!J4G2!288!@baseboard_fab2_lib.baseboard_fab2(sch_1):page45_i169@mstr_sconn.sconn288_h44441004(chips)!SCONN288_H44441004_PIP-SCONN,HA!!!F141!VPP(2)!!!!
S!PVPP_ABC!J4G2!143!@baseboard_fab2_lib.baseboard_fab2(sch_1):page45_i169@mstr_sconn.sconn288_h44441004(chips)!SCONN288_H44441004_PIP-SCONN,HA!!!F141!VPP(3)!!!!
S!PVPP_ABC!J4G2!142!@baseboard_fab2_lib.baseboard_fab2(sch_1):page45_i169@mstr_sconn.sconn288_h44441004(chips)!SCONN288_H44441004_PIP-SCONN,HA!!!F141!VPP(4)!!!!
S!PVTT_ABC!J4G2!221!@baseboard_fab2_lib.baseboard_fab2(sch_1):page45_i169@mstr_sconn.sconn288_h44441004(chips)!SCONN288_H44441004_PIP-SCONN,HA!!!F141!VTT(0)!!!!
S!PVTT_ABC!J4G2!77!@baseboard_fab2_lib.baseboard_fab2(sch_1):page45_i169@mstr_sconn.sconn288_h44441004(chips)!SCONN288_H44441004_PIP-SCONN,HA!!!F141!VTT(1)!!!!
S!M_C_MA<0>!J4G3!79!@baseboard_fab2_lib.baseboard_fab2(sch_1):page47_i111@mstr_sconn.sconn288_h44441004(chips)!SCONN288_H44441004_PIP-SCONN,HA!!!F140!A0!!!!
S!M_C_MA<1>!J4G3!72!@baseboard_fab2_lib.baseboard_fab2(sch_1):page47_i111@mstr_sconn.sconn288_h44441004(chips)!SCONN288_H44441004_PIP-SCONN,HA!!!F140!A1!!!!
S!M_C_MA<10>!J4G3!225!@baseboard_fab2_lib.baseboard_fab2(sch_1):page47_i111@mstr_sconn.sconn288_h44441004(chips)!SCONN288_H44441004_PIP-SCONN,HA!!!F140!A10!!!!
S!M_C_MA<11>!J4G3!210!@baseboard_fab2_lib.baseboard_fab2(sch_1):page47_i111@mstr_sconn.sconn288_h44441004(chips)!SCONN288_H44441004_PIP-SCONN,HA!!!F140!A11!!!!
S!M_C_MA<12>!J4G3!65!@baseboard_fab2_lib.baseboard_fab2(sch_1):page47_i111@mstr_sconn.sconn288_h44441004(chips)!SCONN288_H44441004_PIP-SCONN,HA!!!F140!A12!!!!
S!M_C_MA<13>!J4G3!232!@baseboard_fab2_lib.baseboard_fab2(sch_1):page47_i111@mstr_sconn.sconn288_h44441004(chips)!SCONN288_H44441004_PIP-SCONN,HA!!!F140!A13!!!!
S!M_C_MA<14>!J4G3!228!@baseboard_fab2_lib.baseboard_fab2(sch_1):page47_i111@mstr_sconn.sconn288_h44441004(chips)!SCONN288_H44441004_PIP-SCONN,HA!!!F140!A14_WE_N!!!!
S!M_C_MA<15>!J4G3!86!@baseboard_fab2_lib.baseboard_fab2(sch_1):page47_i111@mstr_sconn.sconn288_h44441004(chips)!SCONN288_H44441004_PIP-SCONN,HA!!!F140!A15_CAS_N!!!!
S!M_C_MA<16>!J4G3!82!@baseboard_fab2_lib.baseboard_fab2(sch_1):page47_i111@mstr_sconn.sconn288_h44441004(chips)!SCONN288_H44441004_PIP-SCONN,HA!!!F140!A16_RAS_N!!!!
S!M_C_MA<17>!J4G3!234!@baseboard_fab2_lib.baseboard_fab2(sch_1):page47_i111@mstr_sconn.sconn288_h44441004(chips)!SCONN288_H44441004_PIP-SCONN,HA!!!F140!A17!!!!
S!M_C_MA<2>!J4G3!216!@baseboard_fab2_lib.baseboard_fab2(sch_1):page47_i111@mstr_sconn.sconn288_h44441004(chips)!SCONN288_H44441004_PIP-SCONN,HA!!!F140!A2!!!!
S!M_C_MA<3>!J4G3!71!@baseboard_fab2_lib.baseboard_fab2(sch_1):page47_i111@mstr_sconn.sconn288_h44441004(chips)!SCONN288_H44441004_PIP-SCONN,HA!!!F140!A3!!!!
S!M_C_MA<4>!J4G3!214!@baseboard_fab2_lib.baseboard_fab2(sch_1):page47_i111@mstr_sconn.sconn288_h44441004(chips)!SCONN288_H44441004_PIP-SCONN,HA!!!F140!A4!!!!
S!M_C_MA<5>!J4G3!213!@baseboard_fab2_lib.baseboard_fab2(sch_1):page47_i111@mstr_sconn.sconn288_h44441004(chips)!SCONN288_H44441004_PIP-SCONN,HA!!!F140!A5!!!!
S!M_C_MA<6>!J4G3!69!@baseboard_fab2_lib.baseboard_fab2(sch_1):page47_i111@mstr_sconn.sconn288_h44441004(chips)!SCONN288_H44441004_PIP-SCONN,HA!!!F140!A6!!!!
S!M_C_MA<7>!J4G3!211!@baseboard_fab2_lib.baseboard_fab2(sch_1):page47_i111@mstr_sconn.sconn288_h44441004(chips)!SCONN288_H44441004_PIP-SCONN,HA!!!F140!A7!!!!
S!M_C_MA<8>!J4G3!68!@baseboard_fab2_lib.baseboard_fab2(sch_1):page47_i111@mstr_sconn.sconn288_h44441004(chips)!SCONN288_H44441004_PIP-SCONN,HA!!!F140!A8!!!!
S!M_C_MA<9>!J4G3!66!@baseboard_fab2_lib.baseboard_fab2(sch_1):page47_i111@mstr_sconn.sconn288_h44441004(chips)!SCONN288_H44441004_PIP-SCONN,HA!!!F140!A9!!!!
S!M_C_ACT_N!J4G3!62!@baseboard_fab2_lib.baseboard_fab2(sch_1):page47_i111@mstr_sconn.sconn288_h44441004(chips)!SCONN288_H44441004_PIP-SCONN,HA!!!F140!ACT_N!!!!
S!M_C_ALERT_N!J4G3!208!@baseboard_fab2_lib.baseboard_fab2(sch_1):page47_i111@mstr_sconn.sconn288_h44441004(chips)!SCONN288_H44441004_PIP-SCONN,HA!!!F140!ALERT_N!!!!
S!M_C_BA<0>!J4G3!81!@baseboard_fab2_lib.baseboard_fab2(sch_1):page47_i111@mstr_sconn.sconn288_h44441004(chips)!SCONN288_H44441004_PIP-SCONN,HA!!!F140!BA(0)!!!!
S!M_C_BA<1>!J4G3!224!@baseboard_fab2_lib.baseboard_fab2(sch_1):page47_i111@mstr_sconn.sconn288_h44441004(chips)!SCONN288_H44441004_PIP-SCONN,HA!!!F140!BA(1)!!!!
S!M_C_BG<0>!J4G3!63!@baseboard_fab2_lib.baseboard_fab2(sch_1):page47_i111@mstr_sconn.sconn288_h44441004(chips)!SCONN288_H44441004_PIP-SCONN,HA!!!F140!BG(0)!!!!
S!M_C_BG<1>!J4G3!207!@baseboard_fab2_lib.baseboard_fab2(sch_1):page47_i111@mstr_sconn.sconn288_h44441004(chips)!SCONN288_H44441004_PIP-SCONN,HA!!!F140!BG(1)!!!!
S!M_C_C<2>!J4G3!235!@baseboard_fab2_lib.baseboard_fab2(sch_1):page47_i111@mstr_sconn.sconn288_h44441004(chips)!SCONN288_H44441004_PIP-SCONN,HA!!!F140!C(2)!!!!
S!M_C_ECC<1>!J4G3!49!@baseboard_fab2_lib.baseboard_fab2(sch_1):page47_i111@mstr_sconn.sconn288_h44441004(chips)!SCONN288_H44441004_PIP-SCONN,HA!!!F140!CB(0)!!!!
S!M_C_ECC<0>!J4G3!194!@baseboard_fab2_lib.baseboard_fab2(sch_1):page47_i111@mstr_sconn.sconn288_h44441004(chips)!SCONN288_H44441004_PIP-SCONN,HA!!!F140!CB(1)!!!!
S!M_C_ECC<3>!J4G3!56!@baseboard_fab2_lib.baseboard_fab2(sch_1):page47_i111@mstr_sconn.sconn288_h44441004(chips)!SCONN288_H44441004_PIP-SCONN,HA!!!F140!CB(2)!!!!
S!M_C_ECC<2>!J4G3!201!@baseboard_fab2_lib.baseboard_fab2(sch_1):page47_i111@mstr_sconn.sconn288_h44441004(chips)!SCONN288_H44441004_PIP-SCONN,HA!!!F140!CB(3)!!!!
S!M_C_ECC<5>!J4G3!47!@baseboard_fab2_lib.baseboard_fab2(sch_1):page47_i111@mstr_sconn.sconn288_h44441004(chips)!SCONN288_H44441004_PIP-SCONN,HA!!!F140!CB(4)!!!!
S!M_C_ECC<4>!J4G3!192!@baseboard_fab2_lib.baseboard_fab2(sch_1):page47_i111@mstr_sconn.sconn288_h44441004(chips)!SCONN288_H44441004_PIP-SCONN,HA!!!F140!CB(5)!!!!
S!M_C_ECC<7>!J4G3!54!@baseboard_fab2_lib.baseboard_fab2(sch_1):page47_i111@mstr_sconn.sconn288_h44441004(chips)!SCONN288_H44441004_PIP-SCONN,HA!!!F140!CB(6)!!!!
S!M_C_ECC<6>!J4G3!199!@baseboard_fab2_lib.baseboard_fab2(sch_1):page47_i111@mstr_sconn.sconn288_h44441004(chips)!SCONN288_H44441004_PIP-SCONN,HA!!!F140!CB(7)!!!!
S!M_C_CLK_DN<0>!J4G3!75!@baseboard_fab2_lib.baseboard_fab2(sch_1):page47_i111@mstr_sconn.sconn288_h44441004(chips)!SCONN288_H44441004_PIP-SCONN,HA!!!F140!CK0N!!!!
S!M_C_CLK_DP<0>!J4G3!74!@baseboard_fab2_lib.baseboard_fab2(sch_1):page47_i111@mstr_sconn.sconn288_h44441004(chips)!SCONN288_H44441004_PIP-SCONN,HA!!!F140!CK0P!!!!
S!M_C_CLK_DN<1>!J4G3!219!@baseboard_fab2_lib.baseboard_fab2(sch_1):page47_i111@mstr_sconn.sconn288_h44441004(chips)!SCONN288_H44441004_PIP-SCONN,HA!!!F140!CK1N!!!!
S!M_C_CLK_DP<1>!J4G3!218!@baseboard_fab2_lib.baseboard_fab2(sch_1):page47_i111@mstr_sconn.sconn288_h44441004(chips)!SCONN288_H44441004_PIP-SCONN,HA!!!F140!CK1P!!!!
S!M_C_CKE<0>!J4G3!60!@baseboard_fab2_lib.baseboard_fab2(sch_1):page47_i111@mstr_sconn.sconn288_h44441004(chips)!SCONN288_H44441004_PIP-SCONN,HA!!!F140!CKE(0)!!!!
S!M_C_CKE<1>!J4G3!203!@baseboard_fab2_lib.baseboard_fab2(sch_1):page47_i111@mstr_sconn.sconn288_h44441004(chips)!SCONN288_H44441004_PIP-SCONN,HA!!!F140!CKE(1)!!!!
S!M_C_DQ<1>!J4G3!5!@baseboard_fab2_lib.baseboard_fab2(sch_1):page47_i111@mstr_sconn.sconn288_h44441004(chips)!SCONN288_H44441004_PIP-SCONN,HA!!!F140!DQ(0)!!!!
S!M_C_DQ<11>!J4G3!23!@baseboard_fab2_lib.baseboard_fab2(sch_1):page47_i111@mstr_sconn.sconn288_h44441004(chips)!SCONN288_H44441004_PIP-SCONN,HA!!!F140!DQ(10)!!!!
S!M_C_DQ<10>!J4G3!168!@baseboard_fab2_lib.baseboard_fab2(sch_1):page47_i111@mstr_sconn.sconn288_h44441004(chips)!SCONN288_H44441004_PIP-SCONN,HA!!!F140!DQ(11)!!!!
S!M_C_DQ<13>!J4G3!14!@baseboard_fab2_lib.baseboard_fab2(sch_1):page47_i111@mstr_sconn.sconn288_h44441004(chips)!SCONN288_H44441004_PIP-SCONN,HA!!!F140!DQ(12)!!!!
S!M_C_DQ<12>!J4G3!159!@baseboard_fab2_lib.baseboard_fab2(sch_1):page47_i111@mstr_sconn.sconn288_h44441004(chips)!SCONN288_H44441004_PIP-SCONN,HA!!!F140!DQ(13)!!!!
S!M_C_DQ<15>!J4G3!21!@baseboard_fab2_lib.baseboard_fab2(sch_1):page47_i111@mstr_sconn.sconn288_h44441004(chips)!SCONN288_H44441004_PIP-SCONN,HA!!!F140!DQ(14)!!!!
S!M_C_DQ<14>!J4G3!166!@baseboard_fab2_lib.baseboard_fab2(sch_1):page47_i111@mstr_sconn.sconn288_h44441004(chips)!SCONN288_H44441004_PIP-SCONN,HA!!!F140!DQ(15)!!!!
S!M_C_DQ<17>!J4G3!27!@baseboard_fab2_lib.baseboard_fab2(sch_1):page47_i111@mstr_sconn.sconn288_h44441004(chips)!SCONN288_H44441004_PIP-SCONN,HA!!!F140!DQ(16)!!!!
S!M_C_DQ<16>!J4G3!172!@baseboard_fab2_lib.baseboard_fab2(sch_1):page47_i111@mstr_sconn.sconn288_h44441004(chips)!SCONN288_H44441004_PIP-SCONN,HA!!!F140!DQ(17)!!!!
S!M_C_DQ<19>!J4G3!34!@baseboard_fab2_lib.baseboard_fab2(sch_1):page47_i111@mstr_sconn.sconn288_h44441004(chips)!SCONN288_H44441004_PIP-SCONN,HA!!!F140!DQ(18)!!!!
S!M_C_DQ<18>!J4G3!179!@baseboard_fab2_lib.baseboard_fab2(sch_1):page47_i111@mstr_sconn.sconn288_h44441004(chips)!SCONN288_H44441004_PIP-SCONN,HA!!!F140!DQ(19)!!!!
S!M_C_DQ<0>!J4G3!150!@baseboard_fab2_lib.baseboard_fab2(sch_1):page47_i111@mstr_sconn.sconn288_h44441004(chips)!SCONN288_H44441004_PIP-SCONN,HA!!!F140!DQ(1)!!!!
S!M_C_DQ<21>!J4G3!25!@baseboard_fab2_lib.baseboard_fab2(sch_1):page47_i111@mstr_sconn.sconn288_h44441004(chips)!SCONN288_H44441004_PIP-SCONN,HA!!!F140!DQ(20)!!!!
S!M_C_DQ<20>!J4G3!170!@baseboard_fab2_lib.baseboard_fab2(sch_1):page47_i111@mstr_sconn.sconn288_h44441004(chips)!SCONN288_H44441004_PIP-SCONN,HA!!!F140!DQ(21)!!!!
S!M_C_DQ<23>!J4G3!32!@baseboard_fab2_lib.baseboard_fab2(sch_1):page47_i111@mstr_sconn.sconn288_h44441004(chips)!SCONN288_H44441004_PIP-SCONN,HA!!!F140!DQ(22)!!!!
S!M_C_DQ<22>!J4G3!177!@baseboard_fab2_lib.baseboard_fab2(sch_1):page47_i111@mstr_sconn.sconn288_h44441004(chips)!SCONN288_H44441004_PIP-SCONN,HA!!!F140!DQ(23)!!!!
S!M_C_DQ<25>!J4G3!38!@baseboard_fab2_lib.baseboard_fab2(sch_1):page47_i111@mstr_sconn.sconn288_h44441004(chips)!SCONN288_H44441004_PIP-SCONN,HA!!!F140!DQ(24)!!!!
S!M_C_DQ<24>!J4G3!183!@baseboard_fab2_lib.baseboard_fab2(sch_1):page47_i111@mstr_sconn.sconn288_h44441004(chips)!SCONN288_H44441004_PIP-SCONN,HA!!!F140!DQ(25)!!!!
S!M_C_DQ<27>!J4G3!45!@baseboard_fab2_lib.baseboard_fab2(sch_1):page47_i111@mstr_sconn.sconn288_h44441004(chips)!SCONN288_H44441004_PIP-SCONN,HA!!!F140!DQ(26)!!!!
S!M_C_DQ<26>!J4G3!190!@baseboard_fab2_lib.baseboard_fab2(sch_1):page47_i111@mstr_sconn.sconn288_h44441004(chips)!SCONN288_H44441004_PIP-SCONN,HA!!!F140!DQ(27)!!!!
S!M_C_DQ<29>!J4G3!36!@baseboard_fab2_lib.baseboard_fab2(sch_1):page47_i111@mstr_sconn.sconn288_h44441004(chips)!SCONN288_H44441004_PIP-SCONN,HA!!!F140!DQ(28)!!!!
S!M_C_DQ<28>!J4G3!181!@baseboard_fab2_lib.baseboard_fab2(sch_1):page47_i111@mstr_sconn.sconn288_h44441004(chips)!SCONN288_H44441004_PIP-SCONN,HA!!!F140!DQ(29)!!!!
S!M_C_DQ<3>!J4G3!12!@baseboard_fab2_lib.baseboard_fab2(sch_1):page47_i111@mstr_sconn.sconn288_h44441004(chips)!SCONN288_H44441004_PIP-SCONN,HA!!!F140!DQ(2)!!!!
S!M_C_DQ<31>!J4G3!43!@baseboard_fab2_lib.baseboard_fab2(sch_1):page47_i111@mstr_sconn.sconn288_h44441004(chips)!SCONN288_H44441004_PIP-SCONN,HA!!!F140!DQ(30)!!!!
S!M_C_DQ<30>!J4G3!188!@baseboard_fab2_lib.baseboard_fab2(sch_1):page47_i111@mstr_sconn.sconn288_h44441004(chips)!SCONN288_H44441004_PIP-SCONN,HA!!!F140!DQ(31)!!!!
S!M_C_DQ<33>!J4G3!97!@baseboard_fab2_lib.baseboard_fab2(sch_1):page47_i111@mstr_sconn.sconn288_h44441004(chips)!SCONN288_H44441004_PIP-SCONN,HA!!!F140!DQ(32)!!!!
S!M_C_DQ<32>!J4G3!242!@baseboard_fab2_lib.baseboard_fab2(sch_1):page47_i111@mstr_sconn.sconn288_h44441004(chips)!SCONN288_H44441004_PIP-SCONN,HA!!!F140!DQ(33)!!!!
S!M_C_DQ<35>!J4G3!104!@baseboard_fab2_lib.baseboard_fab2(sch_1):page47_i111@mstr_sconn.sconn288_h44441004(chips)!SCONN288_H44441004_PIP-SCONN,HA!!!F140!DQ(34)!!!!
S!M_C_DQ<34>!J4G3!249!@baseboard_fab2_lib.baseboard_fab2(sch_1):page47_i111@mstr_sconn.sconn288_h44441004(chips)!SCONN288_H44441004_PIP-SCONN,HA!!!F140!DQ(35)!!!!
S!M_C_DQ<37>!J4G3!95!@baseboard_fab2_lib.baseboard_fab2(sch_1):page47_i111@mstr_sconn.sconn288_h44441004(chips)!SCONN288_H44441004_PIP-SCONN,HA!!!F140!DQ(36)!!!!
S!M_C_DQ<36>!J4G3!240!@baseboard_fab2_lib.baseboard_fab2(sch_1):page47_i111@mstr_sconn.sconn288_h44441004(chips)!SCONN288_H44441004_PIP-SCONN,HA!!!F140!DQ(37)!!!!
S!M_C_DQ<39>!J4G3!102!@baseboard_fab2_lib.baseboard_fab2(sch_1):page47_i111@mstr_sconn.sconn288_h44441004(chips)!SCONN288_H44441004_PIP-SCONN,HA!!!F140!DQ(38)!!!!
S!M_C_DQ<38>!J4G3!247!@baseboard_fab2_lib.baseboard_fab2(sch_1):page47_i111@mstr_sconn.sconn288_h44441004(chips)!SCONN288_H44441004_PIP-SCONN,HA!!!F140!DQ(39)!!!!
S!M_C_DQ<2>!J4G3!157!@baseboard_fab2_lib.baseboard_fab2(sch_1):page47_i111@mstr_sconn.sconn288_h44441004(chips)!SCONN288_H44441004_PIP-SCONN,HA!!!F140!DQ(3)!!!!
S!M_C_DQ<41>!J4G3!108!@baseboard_fab2_lib.baseboard_fab2(sch_1):page47_i111@mstr_sconn.sconn288_h44441004(chips)!SCONN288_H44441004_PIP-SCONN,HA!!!F140!DQ(40)!!!!
S!M_C_DQ<40>!J4G3!253!@baseboard_fab2_lib.baseboard_fab2(sch_1):page47_i111@mstr_sconn.sconn288_h44441004(chips)!SCONN288_H44441004_PIP-SCONN,HA!!!F140!DQ(41)!!!!
S!M_C_DQ<43>!J4G3!115!@baseboard_fab2_lib.baseboard_fab2(sch_1):page47_i111@mstr_sconn.sconn288_h44441004(chips)!SCONN288_H44441004_PIP-SCONN,HA!!!F140!DQ(42)!!!!
S!M_C_DQ<42>!J4G3!260!@baseboard_fab2_lib.baseboard_fab2(sch_1):page47_i111@mstr_sconn.sconn288_h44441004(chips)!SCONN288_H44441004_PIP-SCONN,HA!!!F140!DQ(43)!!!!
S!M_C_DQ<45>!J4G3!106!@baseboard_fab2_lib.baseboard_fab2(sch_1):page47_i111@mstr_sconn.sconn288_h44441004(chips)!SCONN288_H44441004_PIP-SCONN,HA!!!F140!DQ(44)!!!!
S!M_C_DQ<44>!J4G3!251!@baseboard_fab2_lib.baseboard_fab2(sch_1):page47_i111@mstr_sconn.sconn288_h44441004(chips)!SCONN288_H44441004_PIP-SCONN,HA!!!F140!DQ(45)!!!!
S!M_C_DQ<47>!J4G3!113!@baseboard_fab2_lib.baseboard_fab2(sch_1):page47_i111@mstr_sconn.sconn288_h44441004(chips)!SCONN288_H44441004_PIP-SCONN,HA!!!F140!DQ(46)!!!!
S!M_C_DQ<46>!J4G3!258!@baseboard_fab2_lib.baseboard_fab2(sch_1):page47_i111@mstr_sconn.sconn288_h44441004(chips)!SCONN288_H44441004_PIP-SCONN,HA!!!F140!DQ(47)!!!!
S!M_C_DQ<49>!J4G3!119!@baseboard_fab2_lib.baseboard_fab2(sch_1):page47_i111@mstr_sconn.sconn288_h44441004(chips)!SCONN288_H44441004_PIP-SCONN,HA!!!F140!DQ(48)!!!!
S!M_C_DQ<48>!J4G3!264!@baseboard_fab2_lib.baseboard_fab2(sch_1):page47_i111@mstr_sconn.sconn288_h44441004(chips)!SCONN288_H44441004_PIP-SCONN,HA!!!F140!DQ(49)!!!!
S!M_C_DQ<5>!J4G3!3!@baseboard_fab2_lib.baseboard_fab2(sch_1):page47_i111@mstr_sconn.sconn288_h44441004(chips)!SCONN288_H44441004_PIP-SCONN,HA!!!F140!DQ(4)!!!!
S!M_C_DQ<51>!J4G3!126!@baseboard_fab2_lib.baseboard_fab2(sch_1):page47_i111@mstr_sconn.sconn288_h44441004(chips)!SCONN288_H44441004_PIP-SCONN,HA!!!F140!DQ(50)!!!!
S!M_C_DQ<50>!J4G3!271!@baseboard_fab2_lib.baseboard_fab2(sch_1):page47_i111@mstr_sconn.sconn288_h44441004(chips)!SCONN288_H44441004_PIP-SCONN,HA!!!F140!DQ(51)!!!!
S!M_C_DQ<53>!J4G3!117!@baseboard_fab2_lib.baseboard_fab2(sch_1):page47_i111@mstr_sconn.sconn288_h44441004(chips)!SCONN288_H44441004_PIP-SCONN,HA!!!F140!DQ(52)!!!!
S!M_C_DQ<52>!J4G3!262!@baseboard_fab2_lib.baseboard_fab2(sch_1):page47_i111@mstr_sconn.sconn288_h44441004(chips)!SCONN288_H44441004_PIP-SCONN,HA!!!F140!DQ(53)!!!!
S!M_C_DQ<55>!J4G3!124!@baseboard_fab2_lib.baseboard_fab2(sch_1):page47_i111@mstr_sconn.sconn288_h44441004(chips)!SCONN288_H44441004_PIP-SCONN,HA!!!F140!DQ(54)!!!!
S!M_C_DQ<54>!J4G3!269!@baseboard_fab2_lib.baseboard_fab2(sch_1):page47_i111@mstr_sconn.sconn288_h44441004(chips)!SCONN288_H44441004_PIP-SCONN,HA!!!F140!DQ(55)!!!!
S!M_C_DQ<57>!J4G3!130!@baseboard_fab2_lib.baseboard_fab2(sch_1):page47_i111@mstr_sconn.sconn288_h44441004(chips)!SCONN288_H44441004_PIP-SCONN,HA!!!F140!DQ(56)!!!!
S!M_C_DQ<56>!J4G3!275!@baseboard_fab2_lib.baseboard_fab2(sch_1):page47_i111@mstr_sconn.sconn288_h44441004(chips)!SCONN288_H44441004_PIP-SCONN,HA!!!F140!DQ(57)!!!!
S!M_C_DQ<59>!J4G3!137!@baseboard_fab2_lib.baseboard_fab2(sch_1):page47_i111@mstr_sconn.sconn288_h44441004(chips)!SCONN288_H44441004_PIP-SCONN,HA!!!F140!DQ(58)!!!!
S!M_C_DQ<58>!J4G3!282!@baseboard_fab2_lib.baseboard_fab2(sch_1):page47_i111@mstr_sconn.sconn288_h44441004(chips)!SCONN288_H44441004_PIP-SCONN,HA!!!F140!DQ(59)!!!!
S!M_C_DQ<4>!J4G3!148!@baseboard_fab2_lib.baseboard_fab2(sch_1):page47_i111@mstr_sconn.sconn288_h44441004(chips)!SCONN288_H44441004_PIP-SCONN,HA!!!F140!DQ(5)!!!!
S!M_C_DQ<61>!J4G3!128!@baseboard_fab2_lib.baseboard_fab2(sch_1):page47_i111@mstr_sconn.sconn288_h44441004(chips)!SCONN288_H44441004_PIP-SCONN,HA!!!F140!DQ(60)!!!!
S!M_C_DQ<60>!J4G3!273!@baseboard_fab2_lib.baseboard_fab2(sch_1):page47_i111@mstr_sconn.sconn288_h44441004(chips)!SCONN288_H44441004_PIP-SCONN,HA!!!F140!DQ(61)!!!!
S!M_C_DQ<63>!J4G3!135!@baseboard_fab2_lib.baseboard_fab2(sch_1):page47_i111@mstr_sconn.sconn288_h44441004(chips)!SCONN288_H44441004_PIP-SCONN,HA!!!F140!DQ(62)!!!!
S!M_C_DQ<62>!J4G3!280!@baseboard_fab2_lib.baseboard_fab2(sch_1):page47_i111@mstr_sconn.sconn288_h44441004(chips)!SCONN288_H44441004_PIP-SCONN,HA!!!F140!DQ(63)!!!!
S!M_C_DQ<7>!J4G3!10!@baseboard_fab2_lib.baseboard_fab2(sch_1):page47_i111@mstr_sconn.sconn288_h44441004(chips)!SCONN288_H44441004_PIP-SCONN,HA!!!F140!DQ(6)!!!!
S!M_C_DQ<6>!J4G3!155!@baseboard_fab2_lib.baseboard_fab2(sch_1):page47_i111@mstr_sconn.sconn288_h44441004(chips)!SCONN288_H44441004_PIP-SCONN,HA!!!F140!DQ(7)!!!!
S!M_C_DQ<9>!J4G3!16!@baseboard_fab2_lib.baseboard_fab2(sch_1):page47_i111@mstr_sconn.sconn288_h44441004(chips)!SCONN288_H44441004_PIP-SCONN,HA!!!F140!DQ(8)!!!!
S!M_C_DQ<8>!J4G3!161!@baseboard_fab2_lib.baseboard_fab2(sch_1):page47_i111@mstr_sconn.sconn288_h44441004(chips)!SCONN288_H44441004_PIP-SCONN,HA!!!F140!DQ(9)!!!!
S!FM_DIMM_EVENT_COD_N!J4G3!78!@baseboard_fab2_lib.baseboard_fab2(sch_1):page47_i111@mstr_sconn.sconn288_h44441004(chips)!SCONN288_H44441004_PIP-SCONN,HA!!!F140!EVENT_N!!!!
S!M_C_ODT<0>!J4G3!87!@baseboard_fab2_lib.baseboard_fab2(sch_1):page47_i111@mstr_sconn.sconn288_h44441004(chips)!SCONN288_H44441004_PIP-SCONN,HA!!!F140!ODT(0)!!!!
S!M_C_ODT<1>!J4G3!91!@baseboard_fab2_lib.baseboard_fab2(sch_1):page47_i111@mstr_sconn.sconn288_h44441004(chips)!SCONN288_H44441004_PIP-SCONN,HA!!!F140!ODT(1)!!!!
S!M_C_PAR!J4G3!222!@baseboard_fab2_lib.baseboard_fab2(sch_1):page47_i111@mstr_sconn.sconn288_h44441004(chips)!SCONN288_H44441004_PIP-SCONN,HA!!!F140!PAR!!!!
S!M_ABC_RST_N!J4G3!58!@baseboard_fab2_lib.baseboard_fab2(sch_1):page47_i111@mstr_sconn.sconn288_h44441004(chips)!SCONN288_H44441004_PIP-SCONN,HA!!!F140!RESET_N!!!!
S!TP_CH_C_DIMM_C0_RFU_0!J4G3!205!@baseboard_fab2_lib.baseboard_fab2(sch_1):page47_i111@mstr_sconn.sconn288_h44441004(chips)!SCONN288_H44441004_PIP-SCONN,HA!!!F140!RFU(0)!!!!
S!TP_CH_C_DIMM_C0_RFU_1!J4G3!227!@baseboard_fab2_lib.baseboard_fab2(sch_1):page47_i111@mstr_sconn.sconn288_h44441004(chips)!SCONN288_H44441004_PIP-SCONN,HA!!!F140!RFU(1)!!!!
S!TP_CH_C_DIMM_C0_RFU_2!J4G3!144!@baseboard_fab2_lib.baseboard_fab2(sch_1):page47_i111@mstr_sconn.sconn288_h44441004(chips)!SCONN288_H44441004_PIP-SCONN,HA!!!F140!RFU(2)!!!!
S!M_C_CS_N<0>!J4G3!84!@baseboard_fab2_lib.baseboard_fab2(sch_1):page47_i111@mstr_sconn.sconn288_h44441004(chips)!SCONN288_H44441004_PIP-SCONN,HA!!!F140!S0_N!!!!
S!M_C_CS_N<1>!J4G3!89!@baseboard_fab2_lib.baseboard_fab2(sch_1):page47_i111@mstr_sconn.sconn288_h44441004(chips)!SCONN288_H44441004_PIP-SCONN,HA!!!F140!S1_N!!!!
S!M_C_CS_N<2>!J4G3!93!@baseboard_fab2_lib.baseboard_fab2(sch_1):page47_i111@mstr_sconn.sconn288_h44441004(chips)!SCONN288_H44441004_PIP-SCONN,HA!!!F140!S2_N_C(0)!!!!
S!M_C_CS_N<3>!J4G3!237!@baseboard_fab2_lib.baseboard_fab2(sch_1):page47_i111@mstr_sconn.sconn288_h44441004(chips)!SCONN288_H44441004_PIP-SCONN,HA!!!F140!S3_N_C(1)!!!!
S!GND!J4G3!139!@baseboard_fab2_lib.baseboard_fab2(sch_1):page47_i111@mstr_sconn.sconn288_h44441004(chips)!SCONN288_H44441004_PIP-SCONN,HA!!!F140!SA(0)!!!!
S!GND!J4G3!140!@baseboard_fab2_lib.baseboard_fab2(sch_1):page47_i111@mstr_sconn.sconn288_h44441004(chips)!SCONN288_H44441004_PIP-SCONN,HA!!!F140!SA(1)!!!!
S!PVPP_ABC!J4G3!238!@baseboard_fab2_lib.baseboard_fab2(sch_1):page47_i111@mstr_sconn.sconn288_h44441004(chips)!SCONN288_H44441004_PIP-SCONN,HA!!!F140!SA(2)!!!!
S!FM_ADR_COMPLETE_ABC_N!J4G3!230!@baseboard_fab2_lib.baseboard_fab2(sch_1):page47_i111@mstr_sconn.sconn288_h44441004(chips)!SCONN288_H44441004_PIP-SCONN,HA!!!F140!SAVE_N_NC!!!!
S!SMB_DDR_ABC_VPP_SCL!J4G3!141!@baseboard_fab2_lib.baseboard_fab2(sch_1):page47_i111@mstr_sconn.sconn288_h44441004(chips)!SCONN288_H44441004_PIP-SCONN,HA!!!F140!SCL!!!!
S!SMB_DDR_ABC_VPP_SDA!J4G3!285!@baseboard_fab2_lib.baseboard_fab2(sch_1):page47_i111@mstr_sconn.sconn288_h44441004(chips)!SCONN288_H44441004_PIP-SCONN,HA!!!F140!SDA!!!!
S!PVPP_ABC!J4G3!284!@baseboard_fab2_lib.baseboard_fab2(sch_1):page47_i111@mstr_sconn.sconn288_h44441004(chips)!SCONN288_H44441004_PIP-SCONN,HA!!!F140!VDDSPD!!!!
S!M_C_VREF!J4G3!146!@baseboard_fab2_lib.baseboard_fab2(sch_1):page47_i111@mstr_sconn.sconn288_h44441004(chips)!SCONN288_H44441004_PIP-SCONN,HA!!!F140!VREFCA!!!!
S!M_C_DQS_DN<0>!J4G3!152!@baseboard_fab2_lib.baseboard_fab2(sch_1):page47_i61@mstr_sconn.sconn288_h44441004(chips)!SCONN288_H44441004_PIP-SCONN,HA!!!F139!DQS0N!!!!
S!M_C_DQS_DP<0>!J4G3!153!@baseboard_fab2_lib.baseboard_fab2(sch_1):page47_i61@mstr_sconn.sconn288_h44441004(chips)!SCONN288_H44441004_PIP-SCONN,HA!!!F139!DQS0P!!!!
S!M_C_DQS_DN<10>!J4G3!19!@baseboard_fab2_lib.baseboard_fab2(sch_1):page47_i61@mstr_sconn.sconn288_h44441004(chips)!SCONN288_H44441004_PIP-SCONN,HA!!!F139!DQS10N!!!!
S!M_C_DQS_DP<10>!J4G3!18!@baseboard_fab2_lib.baseboard_fab2(sch_1):page47_i61@mstr_sconn.sconn288_h44441004(chips)!SCONN288_H44441004_PIP-SCONN,HA!!!F139!DQS10P!!!!
S!M_C_DQS_DN<11>!J4G3!30!@baseboard_fab2_lib.baseboard_fab2(sch_1):page47_i61@mstr_sconn.sconn288_h44441004(chips)!SCONN288_H44441004_PIP-SCONN,HA!!!F139!DQS11N!!!!
S!M_C_DQS_DP<11>!J4G3!29!@baseboard_fab2_lib.baseboard_fab2(sch_1):page47_i61@mstr_sconn.sconn288_h44441004(chips)!SCONN288_H44441004_PIP-SCONN,HA!!!F139!DQS11P!!!!
S!M_C_DQS_DN<12>!J4G3!41!@baseboard_fab2_lib.baseboard_fab2(sch_1):page47_i61@mstr_sconn.sconn288_h44441004(chips)!SCONN288_H44441004_PIP-SCONN,HA!!!F139!DQS12N!!!!
S!M_C_DQS_DP<12>!J4G3!40!@baseboard_fab2_lib.baseboard_fab2(sch_1):page47_i61@mstr_sconn.sconn288_h44441004(chips)!SCONN288_H44441004_PIP-SCONN,HA!!!F139!DQS12P!!!!
S!M_C_DQS_DN<13>!J4G3!100!@baseboard_fab2_lib.baseboard_fab2(sch_1):page47_i61@mstr_sconn.sconn288_h44441004(chips)!SCONN288_H44441004_PIP-SCONN,HA!!!F139!DQS13N!!!!
S!M_C_DQS_DP<13>!J4G3!99!@baseboard_fab2_lib.baseboard_fab2(sch_1):page47_i61@mstr_sconn.sconn288_h44441004(chips)!SCONN288_H44441004_PIP-SCONN,HA!!!F139!DQS13P!!!!
S!M_C_DQS_DN<14>!J4G3!111!@baseboard_fab2_lib.baseboard_fab2(sch_1):page47_i61@mstr_sconn.sconn288_h44441004(chips)!SCONN288_H44441004_PIP-SCONN,HA!!!F139!DQS14N!!!!
S!M_C_DQS_DP<14>!J4G3!110!@baseboard_fab2_lib.baseboard_fab2(sch_1):page47_i61@mstr_sconn.sconn288_h44441004(chips)!SCONN288_H44441004_PIP-SCONN,HA!!!F139!DQS14P!!!!
S!M_C_DQS_DN<15>!J4G3!122!@baseboard_fab2_lib.baseboard_fab2(sch_1):page47_i61@mstr_sconn.sconn288_h44441004(chips)!SCONN288_H44441004_PIP-SCONN,HA!!!F139!DQS15N!!!!
S!M_C_DQS_DP<15>!J4G3!121!@baseboard_fab2_lib.baseboard_fab2(sch_1):page47_i61@mstr_sconn.sconn288_h44441004(chips)!SCONN288_H44441004_PIP-SCONN,HA!!!F139!DQS15P!!!!
S!M_C_DQS_DN<16>!J4G3!133!@baseboard_fab2_lib.baseboard_fab2(sch_1):page47_i61@mstr_sconn.sconn288_h44441004(chips)!SCONN288_H44441004_PIP-SCONN,HA!!!F139!DQS16N!!!!
S!M_C_DQS_DP<16>!J4G3!132!@baseboard_fab2_lib.baseboard_fab2(sch_1):page47_i61@mstr_sconn.sconn288_h44441004(chips)!SCONN288_H44441004_PIP-SCONN,HA!!!F139!DQS16P!!!!
S!M_C_DQS_DN<17>!J4G3!52!@baseboard_fab2_lib.baseboard_fab2(sch_1):page47_i61@mstr_sconn.sconn288_h44441004(chips)!SCONN288_H44441004_PIP-SCONN,HA!!!F139!DQS17N!!!!
S!M_C_DQS_DP<17>!J4G3!51!@baseboard_fab2_lib.baseboard_fab2(sch_1):page47_i61@mstr_sconn.sconn288_h44441004(chips)!SCONN288_H44441004_PIP-SCONN,HA!!!F139!DQS17P!!!!
S!M_C_DQS_DN<1>!J4G3!163!@baseboard_fab2_lib.baseboard_fab2(sch_1):page47_i61@mstr_sconn.sconn288_h44441004(chips)!SCONN288_H44441004_PIP-SCONN,HA!!!F139!DQS1N!!!!
S!M_C_DQS_DP<1>!J4G3!164!@baseboard_fab2_lib.baseboard_fab2(sch_1):page47_i61@mstr_sconn.sconn288_h44441004(chips)!SCONN288_H44441004_PIP-SCONN,HA!!!F139!DQS1P!!!!
S!M_C_DQS_DN<2>!J4G3!174!@baseboard_fab2_lib.baseboard_fab2(sch_1):page47_i61@mstr_sconn.sconn288_h44441004(chips)!SCONN288_H44441004_PIP-SCONN,HA!!!F139!DQS2N!!!!
S!M_C_DQS_DP<2>!J4G3!175!@baseboard_fab2_lib.baseboard_fab2(sch_1):page47_i61@mstr_sconn.sconn288_h44441004(chips)!SCONN288_H44441004_PIP-SCONN,HA!!!F139!DQS2P!!!!
S!M_C_DQS_DN<3>!J4G3!185!@baseboard_fab2_lib.baseboard_fab2(sch_1):page47_i61@mstr_sconn.sconn288_h44441004(chips)!SCONN288_H44441004_PIP-SCONN,HA!!!F139!DQS3N!!!!
S!M_C_DQS_DP<3>!J4G3!186!@baseboard_fab2_lib.baseboard_fab2(sch_1):page47_i61@mstr_sconn.sconn288_h44441004(chips)!SCONN288_H44441004_PIP-SCONN,HA!!!F139!DQS3P!!!!
S!M_C_DQS_DN<4>!J4G3!244!@baseboard_fab2_lib.baseboard_fab2(sch_1):page47_i61@mstr_sconn.sconn288_h44441004(chips)!SCONN288_H44441004_PIP-SCONN,HA!!!F139!DQS4N!!!!
S!M_C_DQS_DP<4>!J4G3!245!@baseboard_fab2_lib.baseboard_fab2(sch_1):page47_i61@mstr_sconn.sconn288_h44441004(chips)!SCONN288_H44441004_PIP-SCONN,HA!!!F139!DQS4P!!!!
S!M_C_DQS_DN<5>!J4G3!255!@baseboard_fab2_lib.baseboard_fab2(sch_1):page47_i61@mstr_sconn.sconn288_h44441004(chips)!SCONN288_H44441004_PIP-SCONN,HA!!!F139!DQS5N!!!!
S!M_C_DQS_DP<5>!J4G3!256!@baseboard_fab2_lib.baseboard_fab2(sch_1):page47_i61@mstr_sconn.sconn288_h44441004(chips)!SCONN288_H44441004_PIP-SCONN,HA!!!F139!DQS5P!!!!
S!M_C_DQS_DN<6>!J4G3!266!@baseboard_fab2_lib.baseboard_fab2(sch_1):page47_i61@mstr_sconn.sconn288_h44441004(chips)!SCONN288_H44441004_PIP-SCONN,HA!!!F139!DQS6N!!!!
S!M_C_DQS_DP<6>!J4G3!267!@baseboard_fab2_lib.baseboard_fab2(sch_1):page47_i61@mstr_sconn.sconn288_h44441004(chips)!SCONN288_H44441004_PIP-SCONN,HA!!!F139!DQS6P!!!!
S!M_C_DQS_DN<7>!J4G3!277!@baseboard_fab2_lib.baseboard_fab2(sch_1):page47_i61@mstr_sconn.sconn288_h44441004(chips)!SCONN288_H44441004_PIP-SCONN,HA!!!F139!DQS7N!!!!
S!M_C_DQS_DP<7>!J4G3!278!@baseboard_fab2_lib.baseboard_fab2(sch_1):page47_i61@mstr_sconn.sconn288_h44441004(chips)!SCONN288_H44441004_PIP-SCONN,HA!!!F139!DQS7P!!!!
S!M_C_DQS_DN<8>!J4G3!196!@baseboard_fab2_lib.baseboard_fab2(sch_1):page47_i61@mstr_sconn.sconn288_h44441004(chips)!SCONN288_H44441004_PIP-SCONN,HA!!!F139!DQS8N!!!!
S!M_C_DQS_DP<8>!J4G3!197!@baseboard_fab2_lib.baseboard_fab2(sch_1):page47_i61@mstr_sconn.sconn288_h44441004(chips)!SCONN288_H44441004_PIP-SCONN,HA!!!F139!DQS8P!!!!
S!M_C_DQS_DN<9>!J4G3!8!@baseboard_fab2_lib.baseboard_fab2(sch_1):page47_i61@mstr_sconn.sconn288_h44441004(chips)!SCONN288_H44441004_PIP-SCONN,HA!!!F139!DQS9N!!!!
S!M_C_DQS_DP<9>!J4G3!7!@baseboard_fab2_lib.baseboard_fab2(sch_1):page47_i61@mstr_sconn.sconn288_h44441004(chips)!SCONN288_H44441004_PIP-SCONN,HA!!!F139!DQS9P!!!!
S!GND!J4G3!283!@baseboard_fab2_lib.baseboard_fab2(sch_1):page47_i43@mstr_sconn.sconn288_h44441004(chips)!SCONN288_H44441004_PIP-SCONN,HA!!!F138!VSS(0)!!!!
S!GND!J4G3!261!@baseboard_fab2_lib.baseboard_fab2(sch_1):page47_i43@mstr_sconn.sconn288_h44441004(chips)!SCONN288_H44441004_PIP-SCONN,HA!!!F138!VSS(10)!!!!
S!GND!J4G3!259!@baseboard_fab2_lib.baseboard_fab2(sch_1):page47_i43@mstr_sconn.sconn288_h44441004(chips)!SCONN288_H44441004_PIP-SCONN,HA!!!F138!VSS(11)!!!!
S!GND!J4G3!257!@baseboard_fab2_lib.baseboard_fab2(sch_1):page47_i43@mstr_sconn.sconn288_h44441004(chips)!SCONN288_H44441004_PIP-SCONN,HA!!!F138!VSS(12)!!!!
S!GND!J4G3!254!@baseboard_fab2_lib.baseboard_fab2(sch_1):page47_i43@mstr_sconn.sconn288_h44441004(chips)!SCONN288_H44441004_PIP-SCONN,HA!!!F138!VSS(13)!!!!
S!GND!J4G3!252!@baseboard_fab2_lib.baseboard_fab2(sch_1):page47_i43@mstr_sconn.sconn288_h44441004(chips)!SCONN288_H44441004_PIP-SCONN,HA!!!F138!VSS(14)!!!!
S!GND!J4G3!250!@baseboard_fab2_lib.baseboard_fab2(sch_1):page47_i43@mstr_sconn.sconn288_h44441004(chips)!SCONN288_H44441004_PIP-SCONN,HA!!!F138!VSS(15)!!!!
S!GND!J4G3!248!@baseboard_fab2_lib.baseboard_fab2(sch_1):page47_i43@mstr_sconn.sconn288_h44441004(chips)!SCONN288_H44441004_PIP-SCONN,HA!!!F138!VSS(16)!!!!
S!GND!J4G3!246!@baseboard_fab2_lib.baseboard_fab2(sch_1):page47_i43@mstr_sconn.sconn288_h44441004(chips)!SCONN288_H44441004_PIP-SCONN,HA!!!F138!VSS(17)!!!!
S!GND!J4G3!243!@baseboard_fab2_lib.baseboard_fab2(sch_1):page47_i43@mstr_sconn.sconn288_h44441004(chips)!SCONN288_H44441004_PIP-SCONN,HA!!!F138!VSS(18)!!!!
S!GND!J4G3!241!@baseboard_fab2_lib.baseboard_fab2(sch_1):page47_i43@mstr_sconn.sconn288_h44441004(chips)!SCONN288_H44441004_PIP-SCONN,HA!!!F138!VSS(19)!!!!
S!GND!J4G3!281!@baseboard_fab2_lib.baseboard_fab2(sch_1):page47_i43@mstr_sconn.sconn288_h44441004(chips)!SCONN288_H44441004_PIP-SCONN,HA!!!F138!VSS(1)!!!!
S!GND!J4G3!239!@baseboard_fab2_lib.baseboard_fab2(sch_1):page47_i43@mstr_sconn.sconn288_h44441004(chips)!SCONN288_H44441004_PIP-SCONN,HA!!!F138!VSS(20)!!!!
S!GND!J4G3!202!@baseboard_fab2_lib.baseboard_fab2(sch_1):page47_i43@mstr_sconn.sconn288_h44441004(chips)!SCONN288_H44441004_PIP-SCONN,HA!!!F138!VSS(21)!!!!
S!GND!J4G3!200!@baseboard_fab2_lib.baseboard_fab2(sch_1):page47_i43@mstr_sconn.sconn288_h44441004(chips)!SCONN288_H44441004_PIP-SCONN,HA!!!F138!VSS(22)!!!!
S!GND!J4G3!198!@baseboard_fab2_lib.baseboard_fab2(sch_1):page47_i43@mstr_sconn.sconn288_h44441004(chips)!SCONN288_H44441004_PIP-SCONN,HA!!!F138!VSS(23)!!!!
S!GND!J4G3!195!@baseboard_fab2_lib.baseboard_fab2(sch_1):page47_i43@mstr_sconn.sconn288_h44441004(chips)!SCONN288_H44441004_PIP-SCONN,HA!!!F138!VSS(24)!!!!
S!GND!J4G3!193!@baseboard_fab2_lib.baseboard_fab2(sch_1):page47_i43@mstr_sconn.sconn288_h44441004(chips)!SCONN288_H44441004_PIP-SCONN,HA!!!F138!VSS(25)!!!!
S!GND!J4G3!191!@baseboard_fab2_lib.baseboard_fab2(sch_1):page47_i43@mstr_sconn.sconn288_h44441004(chips)!SCONN288_H44441004_PIP-SCONN,HA!!!F138!VSS(26)!!!!
S!GND!J4G3!189!@baseboard_fab2_lib.baseboard_fab2(sch_1):page47_i43@mstr_sconn.sconn288_h44441004(chips)!SCONN288_H44441004_PIP-SCONN,HA!!!F138!VSS(27)!!!!
S!GND!J4G3!187!@baseboard_fab2_lib.baseboard_fab2(sch_1):page47_i43@mstr_sconn.sconn288_h44441004(chips)!SCONN288_H44441004_PIP-SCONN,HA!!!F138!VSS(28)!!!!
S!GND!J4G3!184!@baseboard_fab2_lib.baseboard_fab2(sch_1):page47_i43@mstr_sconn.sconn288_h44441004(chips)!SCONN288_H44441004_PIP-SCONN,HA!!!F138!VSS(29)!!!!
S!GND!J4G3!279!@baseboard_fab2_lib.baseboard_fab2(sch_1):page47_i43@mstr_sconn.sconn288_h44441004(chips)!SCONN288_H44441004_PIP-SCONN,HA!!!F138!VSS(2)!!!!
S!GND!J4G3!182!@baseboard_fab2_lib.baseboard_fab2(sch_1):page47_i43@mstr_sconn.sconn288_h44441004(chips)!SCONN288_H44441004_PIP-SCONN,HA!!!F138!VSS(30)!!!!
S!GND!J4G3!180!@baseboard_fab2_lib.baseboard_fab2(sch_1):page47_i43@mstr_sconn.sconn288_h44441004(chips)!SCONN288_H44441004_PIP-SCONN,HA!!!F138!VSS(31)!!!!
S!GND!J4G3!178!@baseboard_fab2_lib.baseboard_fab2(sch_1):page47_i43@mstr_sconn.sconn288_h44441004(chips)!SCONN288_H44441004_PIP-SCONN,HA!!!F138!VSS(32)!!!!
S!GND!J4G3!176!@baseboard_fab2_lib.baseboard_fab2(sch_1):page47_i43@mstr_sconn.sconn288_h44441004(chips)!SCONN288_H44441004_PIP-SCONN,HA!!!F138!VSS(33)!!!!
S!GND!J4G3!173!@baseboard_fab2_lib.baseboard_fab2(sch_1):page47_i43@mstr_sconn.sconn288_h44441004(chips)!SCONN288_H44441004_PIP-SCONN,HA!!!F138!VSS(34)!!!!
S!GND!J4G3!171!@baseboard_fab2_lib.baseboard_fab2(sch_1):page47_i43@mstr_sconn.sconn288_h44441004(chips)!SCONN288_H44441004_PIP-SCONN,HA!!!F138!VSS(35)!!!!
S!GND!J4G3!169!@baseboard_fab2_lib.baseboard_fab2(sch_1):page47_i43@mstr_sconn.sconn288_h44441004(chips)!SCONN288_H44441004_PIP-SCONN,HA!!!F138!VSS(36)!!!!
S!GND!J4G3!167!@baseboard_fab2_lib.baseboard_fab2(sch_1):page47_i43@mstr_sconn.sconn288_h44441004(chips)!SCONN288_H44441004_PIP-SCONN,HA!!!F138!VSS(37)!!!!
S!GND!J4G3!165!@baseboard_fab2_lib.baseboard_fab2(sch_1):page47_i43@mstr_sconn.sconn288_h44441004(chips)!SCONN288_H44441004_PIP-SCONN,HA!!!F138!VSS(38)!!!!
S!GND!J4G3!162!@baseboard_fab2_lib.baseboard_fab2(sch_1):page47_i43@mstr_sconn.sconn288_h44441004(chips)!SCONN288_H44441004_PIP-SCONN,HA!!!F138!VSS(39)!!!!
S!GND!J4G3!276!@baseboard_fab2_lib.baseboard_fab2(sch_1):page47_i43@mstr_sconn.sconn288_h44441004(chips)!SCONN288_H44441004_PIP-SCONN,HA!!!F138!VSS(3)!!!!
S!GND!J4G3!160!@baseboard_fab2_lib.baseboard_fab2(sch_1):page47_i43@mstr_sconn.sconn288_h44441004(chips)!SCONN288_H44441004_PIP-SCONN,HA!!!F138!VSS(40)!!!!
S!GND!J4G3!158!@baseboard_fab2_lib.baseboard_fab2(sch_1):page47_i43@mstr_sconn.sconn288_h44441004(chips)!SCONN288_H44441004_PIP-SCONN,HA!!!F138!VSS(41)!!!!
S!GND!J4G3!156!@baseboard_fab2_lib.baseboard_fab2(sch_1):page47_i43@mstr_sconn.sconn288_h44441004(chips)!SCONN288_H44441004_PIP-SCONN,HA!!!F138!VSS(42)!!!!
S!GND!J4G3!154!@baseboard_fab2_lib.baseboard_fab2(sch_1):page47_i43@mstr_sconn.sconn288_h44441004(chips)!SCONN288_H44441004_PIP-SCONN,HA!!!F138!VSS(43)!!!!
S!GND!J4G3!151!@baseboard_fab2_lib.baseboard_fab2(sch_1):page47_i43@mstr_sconn.sconn288_h44441004(chips)!SCONN288_H44441004_PIP-SCONN,HA!!!F138!VSS(44)!!!!
S!GND!J4G3!149!@baseboard_fab2_lib.baseboard_fab2(sch_1):page47_i43@mstr_sconn.sconn288_h44441004(chips)!SCONN288_H44441004_PIP-SCONN,HA!!!F138!VSS(45)!!!!
S!GND!J4G3!147!@baseboard_fab2_lib.baseboard_fab2(sch_1):page47_i43@mstr_sconn.sconn288_h44441004(chips)!SCONN288_H44441004_PIP-SCONN,HA!!!F138!VSS(46)!!!!
S!GND!J4G3!138!@baseboard_fab2_lib.baseboard_fab2(sch_1):page47_i43@mstr_sconn.sconn288_h44441004(chips)!SCONN288_H44441004_PIP-SCONN,HA!!!F138!VSS(47)!!!!
S!GND!J4G3!136!@baseboard_fab2_lib.baseboard_fab2(sch_1):page47_i43@mstr_sconn.sconn288_h44441004(chips)!SCONN288_H44441004_PIP-SCONN,HA!!!F138!VSS(48)!!!!
S!GND!J4G3!134!@baseboard_fab2_lib.baseboard_fab2(sch_1):page47_i43@mstr_sconn.sconn288_h44441004(chips)!SCONN288_H44441004_PIP-SCONN,HA!!!F138!VSS(49)!!!!
S!GND!J4G3!274!@baseboard_fab2_lib.baseboard_fab2(sch_1):page47_i43@mstr_sconn.sconn288_h44441004(chips)!SCONN288_H44441004_PIP-SCONN,HA!!!F138!VSS(4)!!!!
S!GND!J4G3!131!@baseboard_fab2_lib.baseboard_fab2(sch_1):page47_i43@mstr_sconn.sconn288_h44441004(chips)!SCONN288_H44441004_PIP-SCONN,HA!!!F138!VSS(50)!!!!
S!GND!J4G3!129!@baseboard_fab2_lib.baseboard_fab2(sch_1):page47_i43@mstr_sconn.sconn288_h44441004(chips)!SCONN288_H44441004_PIP-SCONN,HA!!!F138!VSS(51)!!!!
S!GND!J4G3!127!@baseboard_fab2_lib.baseboard_fab2(sch_1):page47_i43@mstr_sconn.sconn288_h44441004(chips)!SCONN288_H44441004_PIP-SCONN,HA!!!F138!VSS(52)!!!!
S!GND!J4G3!125!@baseboard_fab2_lib.baseboard_fab2(sch_1):page47_i43@mstr_sconn.sconn288_h44441004(chips)!SCONN288_H44441004_PIP-SCONN,HA!!!F138!VSS(53)!!!!
S!GND!J4G3!123!@baseboard_fab2_lib.baseboard_fab2(sch_1):page47_i43@mstr_sconn.sconn288_h44441004(chips)!SCONN288_H44441004_PIP-SCONN,HA!!!F138!VSS(54)!!!!
S!GND!J4G3!120!@baseboard_fab2_lib.baseboard_fab2(sch_1):page47_i43@mstr_sconn.sconn288_h44441004(chips)!SCONN288_H44441004_PIP-SCONN,HA!!!F138!VSS(55)!!!!
S!GND!J4G3!118!@baseboard_fab2_lib.baseboard_fab2(sch_1):page47_i43@mstr_sconn.sconn288_h44441004(chips)!SCONN288_H44441004_PIP-SCONN,HA!!!F138!VSS(56)!!!!
S!GND!J4G3!116!@baseboard_fab2_lib.baseboard_fab2(sch_1):page47_i43@mstr_sconn.sconn288_h44441004(chips)!SCONN288_H44441004_PIP-SCONN,HA!!!F138!VSS(57)!!!!
S!GND!J4G3!114!@baseboard_fab2_lib.baseboard_fab2(sch_1):page47_i43@mstr_sconn.sconn288_h44441004(chips)!SCONN288_H44441004_PIP-SCONN,HA!!!F138!VSS(58)!!!!
S!GND!J4G3!112!@baseboard_fab2_lib.baseboard_fab2(sch_1):page47_i43@mstr_sconn.sconn288_h44441004(chips)!SCONN288_H44441004_PIP-SCONN,HA!!!F138!VSS(59)!!!!
S!GND!J4G3!272!@baseboard_fab2_lib.baseboard_fab2(sch_1):page47_i43@mstr_sconn.sconn288_h44441004(chips)!SCONN288_H44441004_PIP-SCONN,HA!!!F138!VSS(5)!!!!
S!GND!J4G3!109!@baseboard_fab2_lib.baseboard_fab2(sch_1):page47_i43@mstr_sconn.sconn288_h44441004(chips)!SCONN288_H44441004_PIP-SCONN,HA!!!F138!VSS(60)!!!!
S!GND!J4G3!107!@baseboard_fab2_lib.baseboard_fab2(sch_1):page47_i43@mstr_sconn.sconn288_h44441004(chips)!SCONN288_H44441004_PIP-SCONN,HA!!!F138!VSS(61)!!!!
S!GND!J4G3!105!@baseboard_fab2_lib.baseboard_fab2(sch_1):page47_i43@mstr_sconn.sconn288_h44441004(chips)!SCONN288_H44441004_PIP-SCONN,HA!!!F138!VSS(62)!!!!
S!GND!J4G3!103!@baseboard_fab2_lib.baseboard_fab2(sch_1):page47_i43@mstr_sconn.sconn288_h44441004(chips)!SCONN288_H44441004_PIP-SCONN,HA!!!F138!VSS(63)!!!!
S!GND!J4G3!101!@baseboard_fab2_lib.baseboard_fab2(sch_1):page47_i43@mstr_sconn.sconn288_h44441004(chips)!SCONN288_H44441004_PIP-SCONN,HA!!!F138!VSS(64)!!!!
S!GND!J4G3!98!@baseboard_fab2_lib.baseboard_fab2(sch_1):page47_i43@mstr_sconn.sconn288_h44441004(chips)!SCONN288_H44441004_PIP-SCONN,HA!!!F138!VSS(65)!!!!
S!GND!J4G3!96!@baseboard_fab2_lib.baseboard_fab2(sch_1):page47_i43@mstr_sconn.sconn288_h44441004(chips)!SCONN288_H44441004_PIP-SCONN,HA!!!F138!VSS(66)!!!!
S!GND!J4G3!94!@baseboard_fab2_lib.baseboard_fab2(sch_1):page47_i43@mstr_sconn.sconn288_h44441004(chips)!SCONN288_H44441004_PIP-SCONN,HA!!!F138!VSS(67)!!!!
S!GND!J4G3!57!@baseboard_fab2_lib.baseboard_fab2(sch_1):page47_i43@mstr_sconn.sconn288_h44441004(chips)!SCONN288_H44441004_PIP-SCONN,HA!!!F138!VSS(68)!!!!
S!GND!J4G3!55!@baseboard_fab2_lib.baseboard_fab2(sch_1):page47_i43@mstr_sconn.sconn288_h44441004(chips)!SCONN288_H44441004_PIP-SCONN,HA!!!F138!VSS(69)!!!!
S!GND!J4G3!270!@baseboard_fab2_lib.baseboard_fab2(sch_1):page47_i43@mstr_sconn.sconn288_h44441004(chips)!SCONN288_H44441004_PIP-SCONN,HA!!!F138!VSS(6)!!!!
S!GND!J4G3!53!@baseboard_fab2_lib.baseboard_fab2(sch_1):page47_i43@mstr_sconn.sconn288_h44441004(chips)!SCONN288_H44441004_PIP-SCONN,HA!!!F138!VSS(70)!!!!
S!GND!J4G3!50!@baseboard_fab2_lib.baseboard_fab2(sch_1):page47_i43@mstr_sconn.sconn288_h44441004(chips)!SCONN288_H44441004_PIP-SCONN,HA!!!F138!VSS(71)!!!!
S!GND!J4G3!48!@baseboard_fab2_lib.baseboard_fab2(sch_1):page47_i43@mstr_sconn.sconn288_h44441004(chips)!SCONN288_H44441004_PIP-SCONN,HA!!!F138!VSS(72)!!!!
S!GND!J4G3!46!@baseboard_fab2_lib.baseboard_fab2(sch_1):page47_i43@mstr_sconn.sconn288_h44441004(chips)!SCONN288_H44441004_PIP-SCONN,HA!!!F138!VSS(73)!!!!
S!GND!J4G3!44!@baseboard_fab2_lib.baseboard_fab2(sch_1):page47_i43@mstr_sconn.sconn288_h44441004(chips)!SCONN288_H44441004_PIP-SCONN,HA!!!F138!VSS(74)!!!!
S!GND!J4G3!42!@baseboard_fab2_lib.baseboard_fab2(sch_1):page47_i43@mstr_sconn.sconn288_h44441004(chips)!SCONN288_H44441004_PIP-SCONN,HA!!!F138!VSS(75)!!!!
S!GND!J4G3!39!@baseboard_fab2_lib.baseboard_fab2(sch_1):page47_i43@mstr_sconn.sconn288_h44441004(chips)!SCONN288_H44441004_PIP-SCONN,HA!!!F138!VSS(76)!!!!
S!GND!J4G3!37!@baseboard_fab2_lib.baseboard_fab2(sch_1):page47_i43@mstr_sconn.sconn288_h44441004(chips)!SCONN288_H44441004_PIP-SCONN,HA!!!F138!VSS(77)!!!!
S!GND!J4G3!35!@baseboard_fab2_lib.baseboard_fab2(sch_1):page47_i43@mstr_sconn.sconn288_h44441004(chips)!SCONN288_H44441004_PIP-SCONN,HA!!!F138!VSS(78)!!!!
S!GND!J4G3!33!@baseboard_fab2_lib.baseboard_fab2(sch_1):page47_i43@mstr_sconn.sconn288_h44441004(chips)!SCONN288_H44441004_PIP-SCONN,HA!!!F138!VSS(79)!!!!
S!GND!J4G3!268!@baseboard_fab2_lib.baseboard_fab2(sch_1):page47_i43@mstr_sconn.sconn288_h44441004(chips)!SCONN288_H44441004_PIP-SCONN,HA!!!F138!VSS(7)!!!!
S!GND!J4G3!31!@baseboard_fab2_lib.baseboard_fab2(sch_1):page47_i43@mstr_sconn.sconn288_h44441004(chips)!SCONN288_H44441004_PIP-SCONN,HA!!!F138!VSS(80)!!!!
S!GND!J4G3!28!@baseboard_fab2_lib.baseboard_fab2(sch_1):page47_i43@mstr_sconn.sconn288_h44441004(chips)!SCONN288_H44441004_PIP-SCONN,HA!!!F138!VSS(81)!!!!
S!GND!J4G3!26!@baseboard_fab2_lib.baseboard_fab2(sch_1):page47_i43@mstr_sconn.sconn288_h44441004(chips)!SCONN288_H44441004_PIP-SCONN,HA!!!F138!VSS(82)!!!!
S!GND!J4G3!24!@baseboard_fab2_lib.baseboard_fab2(sch_1):page47_i43@mstr_sconn.sconn288_h44441004(chips)!SCONN288_H44441004_PIP-SCONN,HA!!!F138!VSS(83)!!!!
S!GND!J4G3!22!@baseboard_fab2_lib.baseboard_fab2(sch_1):page47_i43@mstr_sconn.sconn288_h44441004(chips)!SCONN288_H44441004_PIP-SCONN,HA!!!F138!VSS(84)!!!!
S!GND!J4G3!20!@baseboard_fab2_lib.baseboard_fab2(sch_1):page47_i43@mstr_sconn.sconn288_h44441004(chips)!SCONN288_H44441004_PIP-SCONN,HA!!!F138!VSS(85)!!!!
S!GND!J4G3!17!@baseboard_fab2_lib.baseboard_fab2(sch_1):page47_i43@mstr_sconn.sconn288_h44441004(chips)!SCONN288_H44441004_PIP-SCONN,HA!!!F138!VSS(86)!!!!
S!GND!J4G3!15!@baseboard_fab2_lib.baseboard_fab2(sch_1):page47_i43@mstr_sconn.sconn288_h44441004(chips)!SCONN288_H44441004_PIP-SCONN,HA!!!F138!VSS(87)!!!!
S!GND!J4G3!13!@baseboard_fab2_lib.baseboard_fab2(sch_1):page47_i43@mstr_sconn.sconn288_h44441004(chips)!SCONN288_H44441004_PIP-SCONN,HA!!!F138!VSS(88)!!!!
S!GND!J4G3!11!@baseboard_fab2_lib.baseboard_fab2(sch_1):page47_i43@mstr_sconn.sconn288_h44441004(chips)!SCONN288_H44441004_PIP-SCONN,HA!!!F138!VSS(89)!!!!
S!GND!J4G3!265!@baseboard_fab2_lib.baseboard_fab2(sch_1):page47_i43@mstr_sconn.sconn288_h44441004(chips)!SCONN288_H44441004_PIP-SCONN,HA!!!F138!VSS(8)!!!!
S!GND!J4G3!9!@baseboard_fab2_lib.baseboard_fab2(sch_1):page47_i43@mstr_sconn.sconn288_h44441004(chips)!SCONN288_H44441004_PIP-SCONN,HA!!!F138!VSS(90)!!!!
S!GND!J4G3!6!@baseboard_fab2_lib.baseboard_fab2(sch_1):page47_i43@mstr_sconn.sconn288_h44441004(chips)!SCONN288_H44441004_PIP-SCONN,HA!!!F138!VSS(91)!!!!
S!GND!J4G3!4!@baseboard_fab2_lib.baseboard_fab2(sch_1):page47_i43@mstr_sconn.sconn288_h44441004(chips)!SCONN288_H44441004_PIP-SCONN,HA!!!F138!VSS(92)!!!!
S!GND!J4G3!2!@baseboard_fab2_lib.baseboard_fab2(sch_1):page47_i43@mstr_sconn.sconn288_h44441004(chips)!SCONN288_H44441004_PIP-SCONN,HA!!!F138!VSS(93)!!!!
S!GND!J4G3!263!@baseboard_fab2_lib.baseboard_fab2(sch_1):page47_i43@mstr_sconn.sconn288_h44441004(chips)!SCONN288_H44441004_PIP-SCONN,HA!!!F138!VSS(9)!!!!
S!P12V_NVDIMM_ABC!J4G3!145!@baseboard_fab2_lib.baseboard_fab2(sch_1):page47_i179@mstr_sconn.sconn288_h44441004(chips)!SCONN288_H44441004_PIP-SCONN,HA!!!F137!\12v\(0)!!!!
S!P12V_NVDIMM_ABC!J4G3!1!@baseboard_fab2_lib.baseboard_fab2(sch_1):page47_i179@mstr_sconn.sconn288_h44441004(chips)!SCONN288_H44441004_PIP-SCONN,HA!!!F137!\12v\(1)!!!!
S!PVDDQ_ABC!J4G3!236!@baseboard_fab2_lib.baseboard_fab2(sch_1):page47_i179@mstr_sconn.sconn288_h44441004(chips)!SCONN288_H44441004_PIP-SCONN,HA!!!F137!VDD(0)!!!!
S!PVDDQ_ABC!J4G3!209!@baseboard_fab2_lib.baseboard_fab2(sch_1):page47_i179@mstr_sconn.sconn288_h44441004(chips)!SCONN288_H44441004_PIP-SCONN,HA!!!F137!VDD(10)!!!!
S!PVDDQ_ABC!J4G3!206!@baseboard_fab2_lib.baseboard_fab2(sch_1):page47_i179@mstr_sconn.sconn288_h44441004(chips)!SCONN288_H44441004_PIP-SCONN,HA!!!F137!VDD(11)!!!!
S!PVDDQ_ABC!J4G3!204!@baseboard_fab2_lib.baseboard_fab2(sch_1):page47_i179@mstr_sconn.sconn288_h44441004(chips)!SCONN288_H44441004_PIP-SCONN,HA!!!F137!VDD(12)!!!!
S!PVDDQ_ABC!J4G3!92!@baseboard_fab2_lib.baseboard_fab2(sch_1):page47_i179@mstr_sconn.sconn288_h44441004(chips)!SCONN288_H44441004_PIP-SCONN,HA!!!F137!VDD(13)!!!!
S!PVDDQ_ABC!J4G3!90!@baseboard_fab2_lib.baseboard_fab2(sch_1):page47_i179@mstr_sconn.sconn288_h44441004(chips)!SCONN288_H44441004_PIP-SCONN,HA!!!F137!VDD(14)!!!!
S!PVDDQ_ABC!J4G3!88!@baseboard_fab2_lib.baseboard_fab2(sch_1):page47_i179@mstr_sconn.sconn288_h44441004(chips)!SCONN288_H44441004_PIP-SCONN,HA!!!F137!VDD(15)!!!!
S!PVDDQ_ABC!J4G3!85!@baseboard_fab2_lib.baseboard_fab2(sch_1):page47_i179@mstr_sconn.sconn288_h44441004(chips)!SCONN288_H44441004_PIP-SCONN,HA!!!F137!VDD(16)!!!!
S!PVDDQ_ABC!J4G3!83!@baseboard_fab2_lib.baseboard_fab2(sch_1):page47_i179@mstr_sconn.sconn288_h44441004(chips)!SCONN288_H44441004_PIP-SCONN,HA!!!F137!VDD(17)!!!!
S!PVDDQ_ABC!J4G3!80!@baseboard_fab2_lib.baseboard_fab2(sch_1):page47_i179@mstr_sconn.sconn288_h44441004(chips)!SCONN288_H44441004_PIP-SCONN,HA!!!F137!VDD(18)!!!!
S!PVDDQ_ABC!J4G3!76!@baseboard_fab2_lib.baseboard_fab2(sch_1):page47_i179@mstr_sconn.sconn288_h44441004(chips)!SCONN288_H44441004_PIP-SCONN,HA!!!F137!VDD(19)!!!!
S!PVDDQ_ABC!J4G3!233!@baseboard_fab2_lib.baseboard_fab2(sch_1):page47_i179@mstr_sconn.sconn288_h44441004(chips)!SCONN288_H44441004_PIP-SCONN,HA!!!F137!VDD(1)!!!!
S!PVDDQ_ABC!J4G3!73!@baseboard_fab2_lib.baseboard_fab2(sch_1):page47_i179@mstr_sconn.sconn288_h44441004(chips)!SCONN288_H44441004_PIP-SCONN,HA!!!F137!VDD(20)!!!!
S!PVDDQ_ABC!J4G3!70!@baseboard_fab2_lib.baseboard_fab2(sch_1):page47_i179@mstr_sconn.sconn288_h44441004(chips)!SCONN288_H44441004_PIP-SCONN,HA!!!F137!VDD(21)!!!!
S!PVDDQ_ABC!J4G3!67!@baseboard_fab2_lib.baseboard_fab2(sch_1):page47_i179@mstr_sconn.sconn288_h44441004(chips)!SCONN288_H44441004_PIP-SCONN,HA!!!F137!VDD(22)!!!!
S!PVDDQ_ABC!J4G3!64!@baseboard_fab2_lib.baseboard_fab2(sch_1):page47_i179@mstr_sconn.sconn288_h44441004(chips)!SCONN288_H44441004_PIP-SCONN,HA!!!F137!VDD(23)!!!!
S!PVDDQ_ABC!J4G3!61!@baseboard_fab2_lib.baseboard_fab2(sch_1):page47_i179@mstr_sconn.sconn288_h44441004(chips)!SCONN288_H44441004_PIP-SCONN,HA!!!F137!VDD(24)!!!!
S!PVDDQ_ABC!J4G3!59!@baseboard_fab2_lib.baseboard_fab2(sch_1):page47_i179@mstr_sconn.sconn288_h44441004(chips)!SCONN288_H44441004_PIP-SCONN,HA!!!F137!VDD(25)!!!!
S!PVDDQ_ABC!J4G3!231!@baseboard_fab2_lib.baseboard_fab2(sch_1):page47_i179@mstr_sconn.sconn288_h44441004(chips)!SCONN288_H44441004_PIP-SCONN,HA!!!F137!VDD(2)!!!!
S!PVDDQ_ABC!J4G3!229!@baseboard_fab2_lib.baseboard_fab2(sch_1):page47_i179@mstr_sconn.sconn288_h44441004(chips)!SCONN288_H44441004_PIP-SCONN,HA!!!F137!VDD(3)!!!!
S!PVDDQ_ABC!J4G3!226!@baseboard_fab2_lib.baseboard_fab2(sch_1):page47_i179@mstr_sconn.sconn288_h44441004(chips)!SCONN288_H44441004_PIP-SCONN,HA!!!F137!VDD(4)!!!!
S!PVDDQ_ABC!J4G3!223!@baseboard_fab2_lib.baseboard_fab2(sch_1):page47_i179@mstr_sconn.sconn288_h44441004(chips)!SCONN288_H44441004_PIP-SCONN,HA!!!F137!VDD(5)!!!!
S!PVDDQ_ABC!J4G3!220!@baseboard_fab2_lib.baseboard_fab2(sch_1):page47_i179@mstr_sconn.sconn288_h44441004(chips)!SCONN288_H44441004_PIP-SCONN,HA!!!F137!VDD(6)!!!!
S!PVDDQ_ABC!J4G3!217!@baseboard_fab2_lib.baseboard_fab2(sch_1):page47_i179@mstr_sconn.sconn288_h44441004(chips)!SCONN288_H44441004_PIP-SCONN,HA!!!F137!VDD(7)!!!!
S!PVDDQ_ABC!J4G3!215!@baseboard_fab2_lib.baseboard_fab2(sch_1):page47_i179@mstr_sconn.sconn288_h44441004(chips)!SCONN288_H44441004_PIP-SCONN,HA!!!F137!VDD(8)!!!!
S!PVDDQ_ABC!J4G3!212!@baseboard_fab2_lib.baseboard_fab2(sch_1):page47_i179@mstr_sconn.sconn288_h44441004(chips)!SCONN288_H44441004_PIP-SCONN,HA!!!F137!VDD(9)!!!!
S!PVPP_ABC!J4G3!287!@baseboard_fab2_lib.baseboard_fab2(sch_1):page47_i179@mstr_sconn.sconn288_h44441004(chips)!SCONN288_H44441004_PIP-SCONN,HA!!!F137!VPP(0)!!!!
S!PVPP_ABC!J4G3!286!@baseboard_fab2_lib.baseboard_fab2(sch_1):page47_i179@mstr_sconn.sconn288_h44441004(chips)!SCONN288_H44441004_PIP-SCONN,HA!!!F137!VPP(1)!!!!
S!PVPP_ABC!J4G3!288!@baseboard_fab2_lib.baseboard_fab2(sch_1):page47_i179@mstr_sconn.sconn288_h44441004(chips)!SCONN288_H44441004_PIP-SCONN,HA!!!F137!VPP(2)!!!!
S!PVPP_ABC!J4G3!143!@baseboard_fab2_lib.baseboard_fab2(sch_1):page47_i179@mstr_sconn.sconn288_h44441004(chips)!SCONN288_H44441004_PIP-SCONN,HA!!!F137!VPP(3)!!!!
S!PVPP_ABC!J4G3!142!@baseboard_fab2_lib.baseboard_fab2(sch_1):page47_i179@mstr_sconn.sconn288_h44441004(chips)!SCONN288_H44441004_PIP-SCONN,HA!!!F137!VPP(4)!!!!
S!PVTT_ABC!J4G3!221!@baseboard_fab2_lib.baseboard_fab2(sch_1):page47_i179@mstr_sconn.sconn288_h44441004(chips)!SCONN288_H44441004_PIP-SCONN,HA!!!F137!VTT(0)!!!!
S!PVTT_ABC!J4G3!77!@baseboard_fab2_lib.baseboard_fab2(sch_1):page47_i179@mstr_sconn.sconn288_h44441004(chips)!SCONN288_H44441004_PIP-SCONN,HA!!!F137!VTT(1)!!!!
S!M_D_MA<0>!J4B1!79!@baseboard_fab2_lib.baseboard_fab2(sch_1):page49_i111@mstr_sconn.sconn288_h44441004(chips)!SCONN288_H44441004_PIP-SCONN,HA!!!F152!A0!!!!
S!M_D_MA<1>!J4B1!72!@baseboard_fab2_lib.baseboard_fab2(sch_1):page49_i111@mstr_sconn.sconn288_h44441004(chips)!SCONN288_H44441004_PIP-SCONN,HA!!!F152!A1!!!!
S!M_D_MA<10>!J4B1!225!@baseboard_fab2_lib.baseboard_fab2(sch_1):page49_i111@mstr_sconn.sconn288_h44441004(chips)!SCONN288_H44441004_PIP-SCONN,HA!!!F152!A10!!!!
S!M_D_MA<11>!J4B1!210!@baseboard_fab2_lib.baseboard_fab2(sch_1):page49_i111@mstr_sconn.sconn288_h44441004(chips)!SCONN288_H44441004_PIP-SCONN,HA!!!F152!A11!!!!
S!M_D_MA<12>!J4B1!65!@baseboard_fab2_lib.baseboard_fab2(sch_1):page49_i111@mstr_sconn.sconn288_h44441004(chips)!SCONN288_H44441004_PIP-SCONN,HA!!!F152!A12!!!!
S!M_D_MA<13>!J4B1!232!@baseboard_fab2_lib.baseboard_fab2(sch_1):page49_i111@mstr_sconn.sconn288_h44441004(chips)!SCONN288_H44441004_PIP-SCONN,HA!!!F152!A13!!!!
S!M_D_MA<14>!J4B1!228!@baseboard_fab2_lib.baseboard_fab2(sch_1):page49_i111@mstr_sconn.sconn288_h44441004(chips)!SCONN288_H44441004_PIP-SCONN,HA!!!F152!A14_WE_N!!!!
S!M_D_MA<15>!J4B1!86!@baseboard_fab2_lib.baseboard_fab2(sch_1):page49_i111@mstr_sconn.sconn288_h44441004(chips)!SCONN288_H44441004_PIP-SCONN,HA!!!F152!A15_CAS_N!!!!
S!M_D_MA<16>!J4B1!82!@baseboard_fab2_lib.baseboard_fab2(sch_1):page49_i111@mstr_sconn.sconn288_h44441004(chips)!SCONN288_H44441004_PIP-SCONN,HA!!!F152!A16_RAS_N!!!!
S!M_D_MA<17>!J4B1!234!@baseboard_fab2_lib.baseboard_fab2(sch_1):page49_i111@mstr_sconn.sconn288_h44441004(chips)!SCONN288_H44441004_PIP-SCONN,HA!!!F152!A17!!!!
S!M_D_MA<2>!J4B1!216!@baseboard_fab2_lib.baseboard_fab2(sch_1):page49_i111@mstr_sconn.sconn288_h44441004(chips)!SCONN288_H44441004_PIP-SCONN,HA!!!F152!A2!!!!
S!M_D_MA<3>!J4B1!71!@baseboard_fab2_lib.baseboard_fab2(sch_1):page49_i111@mstr_sconn.sconn288_h44441004(chips)!SCONN288_H44441004_PIP-SCONN,HA!!!F152!A3!!!!
S!M_D_MA<4>!J4B1!214!@baseboard_fab2_lib.baseboard_fab2(sch_1):page49_i111@mstr_sconn.sconn288_h44441004(chips)!SCONN288_H44441004_PIP-SCONN,HA!!!F152!A4!!!!
S!M_D_MA<5>!J4B1!213!@baseboard_fab2_lib.baseboard_fab2(sch_1):page49_i111@mstr_sconn.sconn288_h44441004(chips)!SCONN288_H44441004_PIP-SCONN,HA!!!F152!A5!!!!
S!M_D_MA<6>!J4B1!69!@baseboard_fab2_lib.baseboard_fab2(sch_1):page49_i111@mstr_sconn.sconn288_h44441004(chips)!SCONN288_H44441004_PIP-SCONN,HA!!!F152!A6!!!!
S!M_D_MA<7>!J4B1!211!@baseboard_fab2_lib.baseboard_fab2(sch_1):page49_i111@mstr_sconn.sconn288_h44441004(chips)!SCONN288_H44441004_PIP-SCONN,HA!!!F152!A7!!!!
S!M_D_MA<8>!J4B1!68!@baseboard_fab2_lib.baseboard_fab2(sch_1):page49_i111@mstr_sconn.sconn288_h44441004(chips)!SCONN288_H44441004_PIP-SCONN,HA!!!F152!A8!!!!
S!M_D_MA<9>!J4B1!66!@baseboard_fab2_lib.baseboard_fab2(sch_1):page49_i111@mstr_sconn.sconn288_h44441004(chips)!SCONN288_H44441004_PIP-SCONN,HA!!!F152!A9!!!!
S!M_D_ACT_N!J4B1!62!@baseboard_fab2_lib.baseboard_fab2(sch_1):page49_i111@mstr_sconn.sconn288_h44441004(chips)!SCONN288_H44441004_PIP-SCONN,HA!!!F152!ACT_N!!!!
S!M_D_ALERT_N!J4B1!208!@baseboard_fab2_lib.baseboard_fab2(sch_1):page49_i111@mstr_sconn.sconn288_h44441004(chips)!SCONN288_H44441004_PIP-SCONN,HA!!!F152!ALERT_N!!!!
S!M_D_BA<0>!J4B1!81!@baseboard_fab2_lib.baseboard_fab2(sch_1):page49_i111@mstr_sconn.sconn288_h44441004(chips)!SCONN288_H44441004_PIP-SCONN,HA!!!F152!BA(0)!!!!
S!M_D_BA<1>!J4B1!224!@baseboard_fab2_lib.baseboard_fab2(sch_1):page49_i111@mstr_sconn.sconn288_h44441004(chips)!SCONN288_H44441004_PIP-SCONN,HA!!!F152!BA(1)!!!!
S!M_D_BG<0>!J4B1!63!@baseboard_fab2_lib.baseboard_fab2(sch_1):page49_i111@mstr_sconn.sconn288_h44441004(chips)!SCONN288_H44441004_PIP-SCONN,HA!!!F152!BG(0)!!!!
S!M_D_BG<1>!J4B1!207!@baseboard_fab2_lib.baseboard_fab2(sch_1):page49_i111@mstr_sconn.sconn288_h44441004(chips)!SCONN288_H44441004_PIP-SCONN,HA!!!F152!BG(1)!!!!
S!M_D_C<2>!J4B1!235!@baseboard_fab2_lib.baseboard_fab2(sch_1):page49_i111@mstr_sconn.sconn288_h44441004(chips)!SCONN288_H44441004_PIP-SCONN,HA!!!F152!C(2)!!!!
S!M_D_ECC<1>!J4B1!49!@baseboard_fab2_lib.baseboard_fab2(sch_1):page49_i111@mstr_sconn.sconn288_h44441004(chips)!SCONN288_H44441004_PIP-SCONN,HA!!!F152!CB(0)!!!!
S!M_D_ECC<0>!J4B1!194!@baseboard_fab2_lib.baseboard_fab2(sch_1):page49_i111@mstr_sconn.sconn288_h44441004(chips)!SCONN288_H44441004_PIP-SCONN,HA!!!F152!CB(1)!!!!
S!M_D_ECC<3>!J4B1!56!@baseboard_fab2_lib.baseboard_fab2(sch_1):page49_i111@mstr_sconn.sconn288_h44441004(chips)!SCONN288_H44441004_PIP-SCONN,HA!!!F152!CB(2)!!!!
S!M_D_ECC<2>!J4B1!201!@baseboard_fab2_lib.baseboard_fab2(sch_1):page49_i111@mstr_sconn.sconn288_h44441004(chips)!SCONN288_H44441004_PIP-SCONN,HA!!!F152!CB(3)!!!!
S!M_D_ECC<5>!J4B1!47!@baseboard_fab2_lib.baseboard_fab2(sch_1):page49_i111@mstr_sconn.sconn288_h44441004(chips)!SCONN288_H44441004_PIP-SCONN,HA!!!F152!CB(4)!!!!
S!M_D_ECC<4>!J4B1!192!@baseboard_fab2_lib.baseboard_fab2(sch_1):page49_i111@mstr_sconn.sconn288_h44441004(chips)!SCONN288_H44441004_PIP-SCONN,HA!!!F152!CB(5)!!!!
S!M_D_ECC<7>!J4B1!54!@baseboard_fab2_lib.baseboard_fab2(sch_1):page49_i111@mstr_sconn.sconn288_h44441004(chips)!SCONN288_H44441004_PIP-SCONN,HA!!!F152!CB(6)!!!!
S!M_D_ECC<6>!J4B1!199!@baseboard_fab2_lib.baseboard_fab2(sch_1):page49_i111@mstr_sconn.sconn288_h44441004(chips)!SCONN288_H44441004_PIP-SCONN,HA!!!F152!CB(7)!!!!
S!M_D_CLK_DN<0>!J4B1!75!@baseboard_fab2_lib.baseboard_fab2(sch_1):page49_i111@mstr_sconn.sconn288_h44441004(chips)!SCONN288_H44441004_PIP-SCONN,HA!!!F152!CK0N!!!!
S!M_D_CLK_DP<0>!J4B1!74!@baseboard_fab2_lib.baseboard_fab2(sch_1):page49_i111@mstr_sconn.sconn288_h44441004(chips)!SCONN288_H44441004_PIP-SCONN,HA!!!F152!CK0P!!!!
S!M_D_CLK_DN<1>!J4B1!219!@baseboard_fab2_lib.baseboard_fab2(sch_1):page49_i111@mstr_sconn.sconn288_h44441004(chips)!SCONN288_H44441004_PIP-SCONN,HA!!!F152!CK1N!!!!
S!M_D_CLK_DP<1>!J4B1!218!@baseboard_fab2_lib.baseboard_fab2(sch_1):page49_i111@mstr_sconn.sconn288_h44441004(chips)!SCONN288_H44441004_PIP-SCONN,HA!!!F152!CK1P!!!!
S!M_D_CKE<0>!J4B1!60!@baseboard_fab2_lib.baseboard_fab2(sch_1):page49_i111@mstr_sconn.sconn288_h44441004(chips)!SCONN288_H44441004_PIP-SCONN,HA!!!F152!CKE(0)!!!!
S!M_D_CKE<1>!J4B1!203!@baseboard_fab2_lib.baseboard_fab2(sch_1):page49_i111@mstr_sconn.sconn288_h44441004(chips)!SCONN288_H44441004_PIP-SCONN,HA!!!F152!CKE(1)!!!!
S!M_D_DQ<1>!J4B1!5!@baseboard_fab2_lib.baseboard_fab2(sch_1):page49_i111@mstr_sconn.sconn288_h44441004(chips)!SCONN288_H44441004_PIP-SCONN,HA!!!F152!DQ(0)!!!!
S!M_D_DQ<11>!J4B1!23!@baseboard_fab2_lib.baseboard_fab2(sch_1):page49_i111@mstr_sconn.sconn288_h44441004(chips)!SCONN288_H44441004_PIP-SCONN,HA!!!F152!DQ(10)!!!!
S!M_D_DQ<10>!J4B1!168!@baseboard_fab2_lib.baseboard_fab2(sch_1):page49_i111@mstr_sconn.sconn288_h44441004(chips)!SCONN288_H44441004_PIP-SCONN,HA!!!F152!DQ(11)!!!!
S!M_D_DQ<13>!J4B1!14!@baseboard_fab2_lib.baseboard_fab2(sch_1):page49_i111@mstr_sconn.sconn288_h44441004(chips)!SCONN288_H44441004_PIP-SCONN,HA!!!F152!DQ(12)!!!!
S!M_D_DQ<12>!J4B1!159!@baseboard_fab2_lib.baseboard_fab2(sch_1):page49_i111@mstr_sconn.sconn288_h44441004(chips)!SCONN288_H44441004_PIP-SCONN,HA!!!F152!DQ(13)!!!!
S!M_D_DQ<15>!J4B1!21!@baseboard_fab2_lib.baseboard_fab2(sch_1):page49_i111@mstr_sconn.sconn288_h44441004(chips)!SCONN288_H44441004_PIP-SCONN,HA!!!F152!DQ(14)!!!!
S!M_D_DQ<14>!J4B1!166!@baseboard_fab2_lib.baseboard_fab2(sch_1):page49_i111@mstr_sconn.sconn288_h44441004(chips)!SCONN288_H44441004_PIP-SCONN,HA!!!F152!DQ(15)!!!!
S!M_D_DQ<17>!J4B1!27!@baseboard_fab2_lib.baseboard_fab2(sch_1):page49_i111@mstr_sconn.sconn288_h44441004(chips)!SCONN288_H44441004_PIP-SCONN,HA!!!F152!DQ(16)!!!!
S!M_D_DQ<16>!J4B1!172!@baseboard_fab2_lib.baseboard_fab2(sch_1):page49_i111@mstr_sconn.sconn288_h44441004(chips)!SCONN288_H44441004_PIP-SCONN,HA!!!F152!DQ(17)!!!!
S!M_D_DQ<19>!J4B1!34!@baseboard_fab2_lib.baseboard_fab2(sch_1):page49_i111@mstr_sconn.sconn288_h44441004(chips)!SCONN288_H44441004_PIP-SCONN,HA!!!F152!DQ(18)!!!!
S!M_D_DQ<18>!J4B1!179!@baseboard_fab2_lib.baseboard_fab2(sch_1):page49_i111@mstr_sconn.sconn288_h44441004(chips)!SCONN288_H44441004_PIP-SCONN,HA!!!F152!DQ(19)!!!!
S!M_D_DQ<0>!J4B1!150!@baseboard_fab2_lib.baseboard_fab2(sch_1):page49_i111@mstr_sconn.sconn288_h44441004(chips)!SCONN288_H44441004_PIP-SCONN,HA!!!F152!DQ(1)!!!!
S!M_D_DQ<21>!J4B1!25!@baseboard_fab2_lib.baseboard_fab2(sch_1):page49_i111@mstr_sconn.sconn288_h44441004(chips)!SCONN288_H44441004_PIP-SCONN,HA!!!F152!DQ(20)!!!!
S!M_D_DQ<20>!J4B1!170!@baseboard_fab2_lib.baseboard_fab2(sch_1):page49_i111@mstr_sconn.sconn288_h44441004(chips)!SCONN288_H44441004_PIP-SCONN,HA!!!F152!DQ(21)!!!!
S!M_D_DQ<23>!J4B1!32!@baseboard_fab2_lib.baseboard_fab2(sch_1):page49_i111@mstr_sconn.sconn288_h44441004(chips)!SCONN288_H44441004_PIP-SCONN,HA!!!F152!DQ(22)!!!!
S!M_D_DQ<22>!J4B1!177!@baseboard_fab2_lib.baseboard_fab2(sch_1):page49_i111@mstr_sconn.sconn288_h44441004(chips)!SCONN288_H44441004_PIP-SCONN,HA!!!F152!DQ(23)!!!!
S!M_D_DQ<25>!J4B1!38!@baseboard_fab2_lib.baseboard_fab2(sch_1):page49_i111@mstr_sconn.sconn288_h44441004(chips)!SCONN288_H44441004_PIP-SCONN,HA!!!F152!DQ(24)!!!!
S!M_D_DQ<24>!J4B1!183!@baseboard_fab2_lib.baseboard_fab2(sch_1):page49_i111@mstr_sconn.sconn288_h44441004(chips)!SCONN288_H44441004_PIP-SCONN,HA!!!F152!DQ(25)!!!!
S!M_D_DQ<27>!J4B1!45!@baseboard_fab2_lib.baseboard_fab2(sch_1):page49_i111@mstr_sconn.sconn288_h44441004(chips)!SCONN288_H44441004_PIP-SCONN,HA!!!F152!DQ(26)!!!!
S!M_D_DQ<26>!J4B1!190!@baseboard_fab2_lib.baseboard_fab2(sch_1):page49_i111@mstr_sconn.sconn288_h44441004(chips)!SCONN288_H44441004_PIP-SCONN,HA!!!F152!DQ(27)!!!!
S!M_D_DQ<29>!J4B1!36!@baseboard_fab2_lib.baseboard_fab2(sch_1):page49_i111@mstr_sconn.sconn288_h44441004(chips)!SCONN288_H44441004_PIP-SCONN,HA!!!F152!DQ(28)!!!!
S!M_D_DQ<28>!J4B1!181!@baseboard_fab2_lib.baseboard_fab2(sch_1):page49_i111@mstr_sconn.sconn288_h44441004(chips)!SCONN288_H44441004_PIP-SCONN,HA!!!F152!DQ(29)!!!!
S!M_D_DQ<3>!J4B1!12!@baseboard_fab2_lib.baseboard_fab2(sch_1):page49_i111@mstr_sconn.sconn288_h44441004(chips)!SCONN288_H44441004_PIP-SCONN,HA!!!F152!DQ(2)!!!!
S!M_D_DQ<31>!J4B1!43!@baseboard_fab2_lib.baseboard_fab2(sch_1):page49_i111@mstr_sconn.sconn288_h44441004(chips)!SCONN288_H44441004_PIP-SCONN,HA!!!F152!DQ(30)!!!!
S!M_D_DQ<30>!J4B1!188!@baseboard_fab2_lib.baseboard_fab2(sch_1):page49_i111@mstr_sconn.sconn288_h44441004(chips)!SCONN288_H44441004_PIP-SCONN,HA!!!F152!DQ(31)!!!!
S!M_D_DQ<33>!J4B1!97!@baseboard_fab2_lib.baseboard_fab2(sch_1):page49_i111@mstr_sconn.sconn288_h44441004(chips)!SCONN288_H44441004_PIP-SCONN,HA!!!F152!DQ(32)!!!!
S!M_D_DQ<32>!J4B1!242!@baseboard_fab2_lib.baseboard_fab2(sch_1):page49_i111@mstr_sconn.sconn288_h44441004(chips)!SCONN288_H44441004_PIP-SCONN,HA!!!F152!DQ(33)!!!!
S!M_D_DQ<35>!J4B1!104!@baseboard_fab2_lib.baseboard_fab2(sch_1):page49_i111@mstr_sconn.sconn288_h44441004(chips)!SCONN288_H44441004_PIP-SCONN,HA!!!F152!DQ(34)!!!!
S!M_D_DQ<34>!J4B1!249!@baseboard_fab2_lib.baseboard_fab2(sch_1):page49_i111@mstr_sconn.sconn288_h44441004(chips)!SCONN288_H44441004_PIP-SCONN,HA!!!F152!DQ(35)!!!!
S!M_D_DQ<37>!J4B1!95!@baseboard_fab2_lib.baseboard_fab2(sch_1):page49_i111@mstr_sconn.sconn288_h44441004(chips)!SCONN288_H44441004_PIP-SCONN,HA!!!F152!DQ(36)!!!!
S!M_D_DQ<36>!J4B1!240!@baseboard_fab2_lib.baseboard_fab2(sch_1):page49_i111@mstr_sconn.sconn288_h44441004(chips)!SCONN288_H44441004_PIP-SCONN,HA!!!F152!DQ(37)!!!!
S!M_D_DQ<39>!J4B1!102!@baseboard_fab2_lib.baseboard_fab2(sch_1):page49_i111@mstr_sconn.sconn288_h44441004(chips)!SCONN288_H44441004_PIP-SCONN,HA!!!F152!DQ(38)!!!!
S!M_D_DQ<38>!J4B1!247!@baseboard_fab2_lib.baseboard_fab2(sch_1):page49_i111@mstr_sconn.sconn288_h44441004(chips)!SCONN288_H44441004_PIP-SCONN,HA!!!F152!DQ(39)!!!!
S!M_D_DQ<2>!J4B1!157!@baseboard_fab2_lib.baseboard_fab2(sch_1):page49_i111@mstr_sconn.sconn288_h44441004(chips)!SCONN288_H44441004_PIP-SCONN,HA!!!F152!DQ(3)!!!!
S!M_D_DQ<41>!J4B1!108!@baseboard_fab2_lib.baseboard_fab2(sch_1):page49_i111@mstr_sconn.sconn288_h44441004(chips)!SCONN288_H44441004_PIP-SCONN,HA!!!F152!DQ(40)!!!!
S!M_D_DQ<40>!J4B1!253!@baseboard_fab2_lib.baseboard_fab2(sch_1):page49_i111@mstr_sconn.sconn288_h44441004(chips)!SCONN288_H44441004_PIP-SCONN,HA!!!F152!DQ(41)!!!!
S!M_D_DQ<43>!J4B1!115!@baseboard_fab2_lib.baseboard_fab2(sch_1):page49_i111@mstr_sconn.sconn288_h44441004(chips)!SCONN288_H44441004_PIP-SCONN,HA!!!F152!DQ(42)!!!!
S!M_D_DQ<42>!J4B1!260!@baseboard_fab2_lib.baseboard_fab2(sch_1):page49_i111@mstr_sconn.sconn288_h44441004(chips)!SCONN288_H44441004_PIP-SCONN,HA!!!F152!DQ(43)!!!!
S!M_D_DQ<45>!J4B1!106!@baseboard_fab2_lib.baseboard_fab2(sch_1):page49_i111@mstr_sconn.sconn288_h44441004(chips)!SCONN288_H44441004_PIP-SCONN,HA!!!F152!DQ(44)!!!!
S!M_D_DQ<44>!J4B1!251!@baseboard_fab2_lib.baseboard_fab2(sch_1):page49_i111@mstr_sconn.sconn288_h44441004(chips)!SCONN288_H44441004_PIP-SCONN,HA!!!F152!DQ(45)!!!!
S!M_D_DQ<47>!J4B1!113!@baseboard_fab2_lib.baseboard_fab2(sch_1):page49_i111@mstr_sconn.sconn288_h44441004(chips)!SCONN288_H44441004_PIP-SCONN,HA!!!F152!DQ(46)!!!!
S!M_D_DQ<46>!J4B1!258!@baseboard_fab2_lib.baseboard_fab2(sch_1):page49_i111@mstr_sconn.sconn288_h44441004(chips)!SCONN288_H44441004_PIP-SCONN,HA!!!F152!DQ(47)!!!!
S!M_D_DQ<49>!J4B1!119!@baseboard_fab2_lib.baseboard_fab2(sch_1):page49_i111@mstr_sconn.sconn288_h44441004(chips)!SCONN288_H44441004_PIP-SCONN,HA!!!F152!DQ(48)!!!!
S!M_D_DQ<48>!J4B1!264!@baseboard_fab2_lib.baseboard_fab2(sch_1):page49_i111@mstr_sconn.sconn288_h44441004(chips)!SCONN288_H44441004_PIP-SCONN,HA!!!F152!DQ(49)!!!!
S!M_D_DQ<5>!J4B1!3!@baseboard_fab2_lib.baseboard_fab2(sch_1):page49_i111@mstr_sconn.sconn288_h44441004(chips)!SCONN288_H44441004_PIP-SCONN,HA!!!F152!DQ(4)!!!!
S!M_D_DQ<51>!J4B1!126!@baseboard_fab2_lib.baseboard_fab2(sch_1):page49_i111@mstr_sconn.sconn288_h44441004(chips)!SCONN288_H44441004_PIP-SCONN,HA!!!F152!DQ(50)!!!!
S!M_D_DQ<50>!J4B1!271!@baseboard_fab2_lib.baseboard_fab2(sch_1):page49_i111@mstr_sconn.sconn288_h44441004(chips)!SCONN288_H44441004_PIP-SCONN,HA!!!F152!DQ(51)!!!!
S!M_D_DQ<53>!J4B1!117!@baseboard_fab2_lib.baseboard_fab2(sch_1):page49_i111@mstr_sconn.sconn288_h44441004(chips)!SCONN288_H44441004_PIP-SCONN,HA!!!F152!DQ(52)!!!!
S!M_D_DQ<52>!J4B1!262!@baseboard_fab2_lib.baseboard_fab2(sch_1):page49_i111@mstr_sconn.sconn288_h44441004(chips)!SCONN288_H44441004_PIP-SCONN,HA!!!F152!DQ(53)!!!!
S!M_D_DQ<55>!J4B1!124!@baseboard_fab2_lib.baseboard_fab2(sch_1):page49_i111@mstr_sconn.sconn288_h44441004(chips)!SCONN288_H44441004_PIP-SCONN,HA!!!F152!DQ(54)!!!!
S!M_D_DQ<54>!J4B1!269!@baseboard_fab2_lib.baseboard_fab2(sch_1):page49_i111@mstr_sconn.sconn288_h44441004(chips)!SCONN288_H44441004_PIP-SCONN,HA!!!F152!DQ(55)!!!!
S!M_D_DQ<57>!J4B1!130!@baseboard_fab2_lib.baseboard_fab2(sch_1):page49_i111@mstr_sconn.sconn288_h44441004(chips)!SCONN288_H44441004_PIP-SCONN,HA!!!F152!DQ(56)!!!!
S!M_D_DQ<56>!J4B1!275!@baseboard_fab2_lib.baseboard_fab2(sch_1):page49_i111@mstr_sconn.sconn288_h44441004(chips)!SCONN288_H44441004_PIP-SCONN,HA!!!F152!DQ(57)!!!!
S!M_D_DQ<59>!J4B1!137!@baseboard_fab2_lib.baseboard_fab2(sch_1):page49_i111@mstr_sconn.sconn288_h44441004(chips)!SCONN288_H44441004_PIP-SCONN,HA!!!F152!DQ(58)!!!!
S!M_D_DQ<58>!J4B1!282!@baseboard_fab2_lib.baseboard_fab2(sch_1):page49_i111@mstr_sconn.sconn288_h44441004(chips)!SCONN288_H44441004_PIP-SCONN,HA!!!F152!DQ(59)!!!!
S!M_D_DQ<4>!J4B1!148!@baseboard_fab2_lib.baseboard_fab2(sch_1):page49_i111@mstr_sconn.sconn288_h44441004(chips)!SCONN288_H44441004_PIP-SCONN,HA!!!F152!DQ(5)!!!!
S!M_D_DQ<61>!J4B1!128!@baseboard_fab2_lib.baseboard_fab2(sch_1):page49_i111@mstr_sconn.sconn288_h44441004(chips)!SCONN288_H44441004_PIP-SCONN,HA!!!F152!DQ(60)!!!!
S!M_D_DQ<60>!J4B1!273!@baseboard_fab2_lib.baseboard_fab2(sch_1):page49_i111@mstr_sconn.sconn288_h44441004(chips)!SCONN288_H44441004_PIP-SCONN,HA!!!F152!DQ(61)!!!!
S!M_D_DQ<63>!J4B1!135!@baseboard_fab2_lib.baseboard_fab2(sch_1):page49_i111@mstr_sconn.sconn288_h44441004(chips)!SCONN288_H44441004_PIP-SCONN,HA!!!F152!DQ(62)!!!!
S!M_D_DQ<62>!J4B1!280!@baseboard_fab2_lib.baseboard_fab2(sch_1):page49_i111@mstr_sconn.sconn288_h44441004(chips)!SCONN288_H44441004_PIP-SCONN,HA!!!F152!DQ(63)!!!!
S!M_D_DQ<7>!J4B1!10!@baseboard_fab2_lib.baseboard_fab2(sch_1):page49_i111@mstr_sconn.sconn288_h44441004(chips)!SCONN288_H44441004_PIP-SCONN,HA!!!F152!DQ(6)!!!!
S!M_D_DQ<6>!J4B1!155!@baseboard_fab2_lib.baseboard_fab2(sch_1):page49_i111@mstr_sconn.sconn288_h44441004(chips)!SCONN288_H44441004_PIP-SCONN,HA!!!F152!DQ(7)!!!!
S!M_D_DQ<9>!J4B1!16!@baseboard_fab2_lib.baseboard_fab2(sch_1):page49_i111@mstr_sconn.sconn288_h44441004(chips)!SCONN288_H44441004_PIP-SCONN,HA!!!F152!DQ(8)!!!!
S!M_D_DQ<8>!J4B1!161!@baseboard_fab2_lib.baseboard_fab2(sch_1):page49_i111@mstr_sconn.sconn288_h44441004(chips)!SCONN288_H44441004_PIP-SCONN,HA!!!F152!DQ(9)!!!!
S!FM_DIMM_EVENT_COD_N!J4B1!78!@baseboard_fab2_lib.baseboard_fab2(sch_1):page49_i111@mstr_sconn.sconn288_h44441004(chips)!SCONN288_H44441004_PIP-SCONN,HA!!!F152!EVENT_N!!!!
S!M_D_ODT<0>!J4B1!87!@baseboard_fab2_lib.baseboard_fab2(sch_1):page49_i111@mstr_sconn.sconn288_h44441004(chips)!SCONN288_H44441004_PIP-SCONN,HA!!!F152!ODT(0)!!!!
S!M_D_ODT<1>!J4B1!91!@baseboard_fab2_lib.baseboard_fab2(sch_1):page49_i111@mstr_sconn.sconn288_h44441004(chips)!SCONN288_H44441004_PIP-SCONN,HA!!!F152!ODT(1)!!!!
S!M_D_PAR!J4B1!222!@baseboard_fab2_lib.baseboard_fab2(sch_1):page49_i111@mstr_sconn.sconn288_h44441004(chips)!SCONN288_H44441004_PIP-SCONN,HA!!!F152!PAR!!!!
S!M_DEF_RST_N!J4B1!58!@baseboard_fab2_lib.baseboard_fab2(sch_1):page49_i111@mstr_sconn.sconn288_h44441004(chips)!SCONN288_H44441004_PIP-SCONN,HA!!!F152!RESET_N!!!!
S!TP_CH_D_DIMM_D0_RFU_0!J4B1!205!@baseboard_fab2_lib.baseboard_fab2(sch_1):page49_i111@mstr_sconn.sconn288_h44441004(chips)!SCONN288_H44441004_PIP-SCONN,HA!!!F152!RFU(0)!!!!
S!TP_CH_D_DIMM_D0_RFU_1!J4B1!227!@baseboard_fab2_lib.baseboard_fab2(sch_1):page49_i111@mstr_sconn.sconn288_h44441004(chips)!SCONN288_H44441004_PIP-SCONN,HA!!!F152!RFU(1)!!!!
S!TP_CH_D_DIMM_D0_RFU_2!J4B1!144!@baseboard_fab2_lib.baseboard_fab2(sch_1):page49_i111@mstr_sconn.sconn288_h44441004(chips)!SCONN288_H44441004_PIP-SCONN,HA!!!F152!RFU(2)!!!!
S!M_D_CS_N<0>!J4B1!84!@baseboard_fab2_lib.baseboard_fab2(sch_1):page49_i111@mstr_sconn.sconn288_h44441004(chips)!SCONN288_H44441004_PIP-SCONN,HA!!!F152!S0_N!!!!
S!M_D_CS_N<1>!J4B1!89!@baseboard_fab2_lib.baseboard_fab2(sch_1):page49_i111@mstr_sconn.sconn288_h44441004(chips)!SCONN288_H44441004_PIP-SCONN,HA!!!F152!S1_N!!!!
S!M_D_CS_N<2>!J4B1!93!@baseboard_fab2_lib.baseboard_fab2(sch_1):page49_i111@mstr_sconn.sconn288_h44441004(chips)!SCONN288_H44441004_PIP-SCONN,HA!!!F152!S2_N_C(0)!!!!
S!M_D_CS_N<3>!J4B1!237!@baseboard_fab2_lib.baseboard_fab2(sch_1):page49_i111@mstr_sconn.sconn288_h44441004(chips)!SCONN288_H44441004_PIP-SCONN,HA!!!F152!S3_N_C(1)!!!!
S!GND!J4B1!139!@baseboard_fab2_lib.baseboard_fab2(sch_1):page49_i111@mstr_sconn.sconn288_h44441004(chips)!SCONN288_H44441004_PIP-SCONN,HA!!!F152!SA(0)!!!!
S!GND!J4B1!140!@baseboard_fab2_lib.baseboard_fab2(sch_1):page49_i111@mstr_sconn.sconn288_h44441004(chips)!SCONN288_H44441004_PIP-SCONN,HA!!!F152!SA(1)!!!!
S!GND!J4B1!238!@baseboard_fab2_lib.baseboard_fab2(sch_1):page49_i111@mstr_sconn.sconn288_h44441004(chips)!SCONN288_H44441004_PIP-SCONN,HA!!!F152!SA(2)!!!!
S!FM_ADR_COMPLETE_DEF_N!J4B1!230!@baseboard_fab2_lib.baseboard_fab2(sch_1):page49_i111@mstr_sconn.sconn288_h44441004(chips)!SCONN288_H44441004_PIP-SCONN,HA!!!F152!SAVE_N_NC!!!!
S!SMB_DDR_DEF_VPP_SCL!J4B1!141!@baseboard_fab2_lib.baseboard_fab2(sch_1):page49_i111@mstr_sconn.sconn288_h44441004(chips)!SCONN288_H44441004_PIP-SCONN,HA!!!F152!SCL!!!!
S!SMB_DDR_DEF_VPP_SDA!J4B1!285!@baseboard_fab2_lib.baseboard_fab2(sch_1):page49_i111@mstr_sconn.sconn288_h44441004(chips)!SCONN288_H44441004_PIP-SCONN,HA!!!F152!SDA!!!!
S!PVPP_DEF!J4B1!284!@baseboard_fab2_lib.baseboard_fab2(sch_1):page49_i111@mstr_sconn.sconn288_h44441004(chips)!SCONN288_H44441004_PIP-SCONN,HA!!!F152!VDDSPD!!!!
S!M_D_VREF!J4B1!146!@baseboard_fab2_lib.baseboard_fab2(sch_1):page49_i111@mstr_sconn.sconn288_h44441004(chips)!SCONN288_H44441004_PIP-SCONN,HA!!!F152!VREFCA!!!!
S!M_D_DQS_DN<0>!J4B1!152!@baseboard_fab2_lib.baseboard_fab2(sch_1):page49_i66@mstr_sconn.sconn288_h44441004(chips)!SCONN288_H44441004_PIP-SCONN,HA!!!F151!DQS0N!!!!
S!M_D_DQS_DP<0>!J4B1!153!@baseboard_fab2_lib.baseboard_fab2(sch_1):page49_i66@mstr_sconn.sconn288_h44441004(chips)!SCONN288_H44441004_PIP-SCONN,HA!!!F151!DQS0P!!!!
S!M_D_DQS_DN<10>!J4B1!19!@baseboard_fab2_lib.baseboard_fab2(sch_1):page49_i66@mstr_sconn.sconn288_h44441004(chips)!SCONN288_H44441004_PIP-SCONN,HA!!!F151!DQS10N!!!!
S!M_D_DQS_DP<10>!J4B1!18!@baseboard_fab2_lib.baseboard_fab2(sch_1):page49_i66@mstr_sconn.sconn288_h44441004(chips)!SCONN288_H44441004_PIP-SCONN,HA!!!F151!DQS10P!!!!
S!M_D_DQS_DN<11>!J4B1!30!@baseboard_fab2_lib.baseboard_fab2(sch_1):page49_i66@mstr_sconn.sconn288_h44441004(chips)!SCONN288_H44441004_PIP-SCONN,HA!!!F151!DQS11N!!!!
S!M_D_DQS_DP<11>!J4B1!29!@baseboard_fab2_lib.baseboard_fab2(sch_1):page49_i66@mstr_sconn.sconn288_h44441004(chips)!SCONN288_H44441004_PIP-SCONN,HA!!!F151!DQS11P!!!!
S!M_D_DQS_DN<12>!J4B1!41!@baseboard_fab2_lib.baseboard_fab2(sch_1):page49_i66@mstr_sconn.sconn288_h44441004(chips)!SCONN288_H44441004_PIP-SCONN,HA!!!F151!DQS12N!!!!
S!M_D_DQS_DP<12>!J4B1!40!@baseboard_fab2_lib.baseboard_fab2(sch_1):page49_i66@mstr_sconn.sconn288_h44441004(chips)!SCONN288_H44441004_PIP-SCONN,HA!!!F151!DQS12P!!!!
S!M_D_DQS_DN<13>!J4B1!100!@baseboard_fab2_lib.baseboard_fab2(sch_1):page49_i66@mstr_sconn.sconn288_h44441004(chips)!SCONN288_H44441004_PIP-SCONN,HA!!!F151!DQS13N!!!!
S!M_D_DQS_DP<13>!J4B1!99!@baseboard_fab2_lib.baseboard_fab2(sch_1):page49_i66@mstr_sconn.sconn288_h44441004(chips)!SCONN288_H44441004_PIP-SCONN,HA!!!F151!DQS13P!!!!
S!M_D_DQS_DN<14>!J4B1!111!@baseboard_fab2_lib.baseboard_fab2(sch_1):page49_i66@mstr_sconn.sconn288_h44441004(chips)!SCONN288_H44441004_PIP-SCONN,HA!!!F151!DQS14N!!!!
S!M_D_DQS_DP<14>!J4B1!110!@baseboard_fab2_lib.baseboard_fab2(sch_1):page49_i66@mstr_sconn.sconn288_h44441004(chips)!SCONN288_H44441004_PIP-SCONN,HA!!!F151!DQS14P!!!!
S!M_D_DQS_DN<15>!J4B1!122!@baseboard_fab2_lib.baseboard_fab2(sch_1):page49_i66@mstr_sconn.sconn288_h44441004(chips)!SCONN288_H44441004_PIP-SCONN,HA!!!F151!DQS15N!!!!
S!M_D_DQS_DP<15>!J4B1!121!@baseboard_fab2_lib.baseboard_fab2(sch_1):page49_i66@mstr_sconn.sconn288_h44441004(chips)!SCONN288_H44441004_PIP-SCONN,HA!!!F151!DQS15P!!!!
S!M_D_DQS_DN<16>!J4B1!133!@baseboard_fab2_lib.baseboard_fab2(sch_1):page49_i66@mstr_sconn.sconn288_h44441004(chips)!SCONN288_H44441004_PIP-SCONN,HA!!!F151!DQS16N!!!!
S!M_D_DQS_DP<16>!J4B1!132!@baseboard_fab2_lib.baseboard_fab2(sch_1):page49_i66@mstr_sconn.sconn288_h44441004(chips)!SCONN288_H44441004_PIP-SCONN,HA!!!F151!DQS16P!!!!
S!M_D_DQS_DN<17>!J4B1!52!@baseboard_fab2_lib.baseboard_fab2(sch_1):page49_i66@mstr_sconn.sconn288_h44441004(chips)!SCONN288_H44441004_PIP-SCONN,HA!!!F151!DQS17N!!!!
S!M_D_DQS_DP<17>!J4B1!51!@baseboard_fab2_lib.baseboard_fab2(sch_1):page49_i66@mstr_sconn.sconn288_h44441004(chips)!SCONN288_H44441004_PIP-SCONN,HA!!!F151!DQS17P!!!!
S!M_D_DQS_DN<1>!J4B1!163!@baseboard_fab2_lib.baseboard_fab2(sch_1):page49_i66@mstr_sconn.sconn288_h44441004(chips)!SCONN288_H44441004_PIP-SCONN,HA!!!F151!DQS1N!!!!
S!M_D_DQS_DP<1>!J4B1!164!@baseboard_fab2_lib.baseboard_fab2(sch_1):page49_i66@mstr_sconn.sconn288_h44441004(chips)!SCONN288_H44441004_PIP-SCONN,HA!!!F151!DQS1P!!!!
S!M_D_DQS_DN<2>!J4B1!174!@baseboard_fab2_lib.baseboard_fab2(sch_1):page49_i66@mstr_sconn.sconn288_h44441004(chips)!SCONN288_H44441004_PIP-SCONN,HA!!!F151!DQS2N!!!!
S!M_D_DQS_DP<2>!J4B1!175!@baseboard_fab2_lib.baseboard_fab2(sch_1):page49_i66@mstr_sconn.sconn288_h44441004(chips)!SCONN288_H44441004_PIP-SCONN,HA!!!F151!DQS2P!!!!
S!M_D_DQS_DN<3>!J4B1!185!@baseboard_fab2_lib.baseboard_fab2(sch_1):page49_i66@mstr_sconn.sconn288_h44441004(chips)!SCONN288_H44441004_PIP-SCONN,HA!!!F151!DQS3N!!!!
S!M_D_DQS_DP<3>!J4B1!186!@baseboard_fab2_lib.baseboard_fab2(sch_1):page49_i66@mstr_sconn.sconn288_h44441004(chips)!SCONN288_H44441004_PIP-SCONN,HA!!!F151!DQS3P!!!!
S!M_D_DQS_DN<4>!J4B1!244!@baseboard_fab2_lib.baseboard_fab2(sch_1):page49_i66@mstr_sconn.sconn288_h44441004(chips)!SCONN288_H44441004_PIP-SCONN,HA!!!F151!DQS4N!!!!
S!M_D_DQS_DP<4>!J4B1!245!@baseboard_fab2_lib.baseboard_fab2(sch_1):page49_i66@mstr_sconn.sconn288_h44441004(chips)!SCONN288_H44441004_PIP-SCONN,HA!!!F151!DQS4P!!!!
S!M_D_DQS_DN<5>!J4B1!255!@baseboard_fab2_lib.baseboard_fab2(sch_1):page49_i66@mstr_sconn.sconn288_h44441004(chips)!SCONN288_H44441004_PIP-SCONN,HA!!!F151!DQS5N!!!!
S!M_D_DQS_DP<5>!J4B1!256!@baseboard_fab2_lib.baseboard_fab2(sch_1):page49_i66@mstr_sconn.sconn288_h44441004(chips)!SCONN288_H44441004_PIP-SCONN,HA!!!F151!DQS5P!!!!
S!M_D_DQS_DN<6>!J4B1!266!@baseboard_fab2_lib.baseboard_fab2(sch_1):page49_i66@mstr_sconn.sconn288_h44441004(chips)!SCONN288_H44441004_PIP-SCONN,HA!!!F151!DQS6N!!!!
S!M_D_DQS_DP<6>!J4B1!267!@baseboard_fab2_lib.baseboard_fab2(sch_1):page49_i66@mstr_sconn.sconn288_h44441004(chips)!SCONN288_H44441004_PIP-SCONN,HA!!!F151!DQS6P!!!!
S!M_D_DQS_DN<7>!J4B1!277!@baseboard_fab2_lib.baseboard_fab2(sch_1):page49_i66@mstr_sconn.sconn288_h44441004(chips)!SCONN288_H44441004_PIP-SCONN,HA!!!F151!DQS7N!!!!
S!M_D_DQS_DP<7>!J4B1!278!@baseboard_fab2_lib.baseboard_fab2(sch_1):page49_i66@mstr_sconn.sconn288_h44441004(chips)!SCONN288_H44441004_PIP-SCONN,HA!!!F151!DQS7P!!!!
S!M_D_DQS_DN<8>!J4B1!196!@baseboard_fab2_lib.baseboard_fab2(sch_1):page49_i66@mstr_sconn.sconn288_h44441004(chips)!SCONN288_H44441004_PIP-SCONN,HA!!!F151!DQS8N!!!!
S!M_D_DQS_DP<8>!J4B1!197!@baseboard_fab2_lib.baseboard_fab2(sch_1):page49_i66@mstr_sconn.sconn288_h44441004(chips)!SCONN288_H44441004_PIP-SCONN,HA!!!F151!DQS8P!!!!
S!M_D_DQS_DN<9>!J4B1!8!@baseboard_fab2_lib.baseboard_fab2(sch_1):page49_i66@mstr_sconn.sconn288_h44441004(chips)!SCONN288_H44441004_PIP-SCONN,HA!!!F151!DQS9N!!!!
S!M_D_DQS_DP<9>!J4B1!7!@baseboard_fab2_lib.baseboard_fab2(sch_1):page49_i66@mstr_sconn.sconn288_h44441004(chips)!SCONN288_H44441004_PIP-SCONN,HA!!!F151!DQS9P!!!!
S!GND!J4B1!283!@baseboard_fab2_lib.baseboard_fab2(sch_1):page49_i43@mstr_sconn.sconn288_h44441004(chips)!SCONN288_H44441004_PIP-SCONN,HA!!!F150!VSS(0)!!!!
S!GND!J4B1!261!@baseboard_fab2_lib.baseboard_fab2(sch_1):page49_i43@mstr_sconn.sconn288_h44441004(chips)!SCONN288_H44441004_PIP-SCONN,HA!!!F150!VSS(10)!!!!
S!GND!J4B1!259!@baseboard_fab2_lib.baseboard_fab2(sch_1):page49_i43@mstr_sconn.sconn288_h44441004(chips)!SCONN288_H44441004_PIP-SCONN,HA!!!F150!VSS(11)!!!!
S!GND!J4B1!257!@baseboard_fab2_lib.baseboard_fab2(sch_1):page49_i43@mstr_sconn.sconn288_h44441004(chips)!SCONN288_H44441004_PIP-SCONN,HA!!!F150!VSS(12)!!!!
S!GND!J4B1!254!@baseboard_fab2_lib.baseboard_fab2(sch_1):page49_i43@mstr_sconn.sconn288_h44441004(chips)!SCONN288_H44441004_PIP-SCONN,HA!!!F150!VSS(13)!!!!
S!GND!J4B1!252!@baseboard_fab2_lib.baseboard_fab2(sch_1):page49_i43@mstr_sconn.sconn288_h44441004(chips)!SCONN288_H44441004_PIP-SCONN,HA!!!F150!VSS(14)!!!!
S!GND!J4B1!250!@baseboard_fab2_lib.baseboard_fab2(sch_1):page49_i43@mstr_sconn.sconn288_h44441004(chips)!SCONN288_H44441004_PIP-SCONN,HA!!!F150!VSS(15)!!!!
S!GND!J4B1!248!@baseboard_fab2_lib.baseboard_fab2(sch_1):page49_i43@mstr_sconn.sconn288_h44441004(chips)!SCONN288_H44441004_PIP-SCONN,HA!!!F150!VSS(16)!!!!
S!GND!J4B1!246!@baseboard_fab2_lib.baseboard_fab2(sch_1):page49_i43@mstr_sconn.sconn288_h44441004(chips)!SCONN288_H44441004_PIP-SCONN,HA!!!F150!VSS(17)!!!!
S!GND!J4B1!243!@baseboard_fab2_lib.baseboard_fab2(sch_1):page49_i43@mstr_sconn.sconn288_h44441004(chips)!SCONN288_H44441004_PIP-SCONN,HA!!!F150!VSS(18)!!!!
S!GND!J4B1!241!@baseboard_fab2_lib.baseboard_fab2(sch_1):page49_i43@mstr_sconn.sconn288_h44441004(chips)!SCONN288_H44441004_PIP-SCONN,HA!!!F150!VSS(19)!!!!
S!GND!J4B1!281!@baseboard_fab2_lib.baseboard_fab2(sch_1):page49_i43@mstr_sconn.sconn288_h44441004(chips)!SCONN288_H44441004_PIP-SCONN,HA!!!F150!VSS(1)!!!!
S!GND!J4B1!239!@baseboard_fab2_lib.baseboard_fab2(sch_1):page49_i43@mstr_sconn.sconn288_h44441004(chips)!SCONN288_H44441004_PIP-SCONN,HA!!!F150!VSS(20)!!!!
S!GND!J4B1!202!@baseboard_fab2_lib.baseboard_fab2(sch_1):page49_i43@mstr_sconn.sconn288_h44441004(chips)!SCONN288_H44441004_PIP-SCONN,HA!!!F150!VSS(21)!!!!
S!GND!J4B1!200!@baseboard_fab2_lib.baseboard_fab2(sch_1):page49_i43@mstr_sconn.sconn288_h44441004(chips)!SCONN288_H44441004_PIP-SCONN,HA!!!F150!VSS(22)!!!!
S!GND!J4B1!198!@baseboard_fab2_lib.baseboard_fab2(sch_1):page49_i43@mstr_sconn.sconn288_h44441004(chips)!SCONN288_H44441004_PIP-SCONN,HA!!!F150!VSS(23)!!!!
S!GND!J4B1!195!@baseboard_fab2_lib.baseboard_fab2(sch_1):page49_i43@mstr_sconn.sconn288_h44441004(chips)!SCONN288_H44441004_PIP-SCONN,HA!!!F150!VSS(24)!!!!
S!GND!J4B1!193!@baseboard_fab2_lib.baseboard_fab2(sch_1):page49_i43@mstr_sconn.sconn288_h44441004(chips)!SCONN288_H44441004_PIP-SCONN,HA!!!F150!VSS(25)!!!!
S!GND!J4B1!191!@baseboard_fab2_lib.baseboard_fab2(sch_1):page49_i43@mstr_sconn.sconn288_h44441004(chips)!SCONN288_H44441004_PIP-SCONN,HA!!!F150!VSS(26)!!!!
S!GND!J4B1!189!@baseboard_fab2_lib.baseboard_fab2(sch_1):page49_i43@mstr_sconn.sconn288_h44441004(chips)!SCONN288_H44441004_PIP-SCONN,HA!!!F150!VSS(27)!!!!
S!GND!J4B1!187!@baseboard_fab2_lib.baseboard_fab2(sch_1):page49_i43@mstr_sconn.sconn288_h44441004(chips)!SCONN288_H44441004_PIP-SCONN,HA!!!F150!VSS(28)!!!!
S!GND!J4B1!184!@baseboard_fab2_lib.baseboard_fab2(sch_1):page49_i43@mstr_sconn.sconn288_h44441004(chips)!SCONN288_H44441004_PIP-SCONN,HA!!!F150!VSS(29)!!!!
S!GND!J4B1!279!@baseboard_fab2_lib.baseboard_fab2(sch_1):page49_i43@mstr_sconn.sconn288_h44441004(chips)!SCONN288_H44441004_PIP-SCONN,HA!!!F150!VSS(2)!!!!
S!GND!J4B1!182!@baseboard_fab2_lib.baseboard_fab2(sch_1):page49_i43@mstr_sconn.sconn288_h44441004(chips)!SCONN288_H44441004_PIP-SCONN,HA!!!F150!VSS(30)!!!!
S!GND!J4B1!180!@baseboard_fab2_lib.baseboard_fab2(sch_1):page49_i43@mstr_sconn.sconn288_h44441004(chips)!SCONN288_H44441004_PIP-SCONN,HA!!!F150!VSS(31)!!!!
S!GND!J4B1!178!@baseboard_fab2_lib.baseboard_fab2(sch_1):page49_i43@mstr_sconn.sconn288_h44441004(chips)!SCONN288_H44441004_PIP-SCONN,HA!!!F150!VSS(32)!!!!
S!GND!J4B1!176!@baseboard_fab2_lib.baseboard_fab2(sch_1):page49_i43@mstr_sconn.sconn288_h44441004(chips)!SCONN288_H44441004_PIP-SCONN,HA!!!F150!VSS(33)!!!!
S!GND!J4B1!173!@baseboard_fab2_lib.baseboard_fab2(sch_1):page49_i43@mstr_sconn.sconn288_h44441004(chips)!SCONN288_H44441004_PIP-SCONN,HA!!!F150!VSS(34)!!!!
S!GND!J4B1!171!@baseboard_fab2_lib.baseboard_fab2(sch_1):page49_i43@mstr_sconn.sconn288_h44441004(chips)!SCONN288_H44441004_PIP-SCONN,HA!!!F150!VSS(35)!!!!
S!GND!J4B1!169!@baseboard_fab2_lib.baseboard_fab2(sch_1):page49_i43@mstr_sconn.sconn288_h44441004(chips)!SCONN288_H44441004_PIP-SCONN,HA!!!F150!VSS(36)!!!!
S!GND!J4B1!167!@baseboard_fab2_lib.baseboard_fab2(sch_1):page49_i43@mstr_sconn.sconn288_h44441004(chips)!SCONN288_H44441004_PIP-SCONN,HA!!!F150!VSS(37)!!!!
S!GND!J4B1!165!@baseboard_fab2_lib.baseboard_fab2(sch_1):page49_i43@mstr_sconn.sconn288_h44441004(chips)!SCONN288_H44441004_PIP-SCONN,HA!!!F150!VSS(38)!!!!
S!GND!J4B1!162!@baseboard_fab2_lib.baseboard_fab2(sch_1):page49_i43@mstr_sconn.sconn288_h44441004(chips)!SCONN288_H44441004_PIP-SCONN,HA!!!F150!VSS(39)!!!!
S!GND!J4B1!276!@baseboard_fab2_lib.baseboard_fab2(sch_1):page49_i43@mstr_sconn.sconn288_h44441004(chips)!SCONN288_H44441004_PIP-SCONN,HA!!!F150!VSS(3)!!!!
S!GND!J4B1!160!@baseboard_fab2_lib.baseboard_fab2(sch_1):page49_i43@mstr_sconn.sconn288_h44441004(chips)!SCONN288_H44441004_PIP-SCONN,HA!!!F150!VSS(40)!!!!
S!GND!J4B1!158!@baseboard_fab2_lib.baseboard_fab2(sch_1):page49_i43@mstr_sconn.sconn288_h44441004(chips)!SCONN288_H44441004_PIP-SCONN,HA!!!F150!VSS(41)!!!!
S!GND!J4B1!156!@baseboard_fab2_lib.baseboard_fab2(sch_1):page49_i43@mstr_sconn.sconn288_h44441004(chips)!SCONN288_H44441004_PIP-SCONN,HA!!!F150!VSS(42)!!!!
S!GND!J4B1!154!@baseboard_fab2_lib.baseboard_fab2(sch_1):page49_i43@mstr_sconn.sconn288_h44441004(chips)!SCONN288_H44441004_PIP-SCONN,HA!!!F150!VSS(43)!!!!
S!GND!J4B1!151!@baseboard_fab2_lib.baseboard_fab2(sch_1):page49_i43@mstr_sconn.sconn288_h44441004(chips)!SCONN288_H44441004_PIP-SCONN,HA!!!F150!VSS(44)!!!!
S!GND!J4B1!149!@baseboard_fab2_lib.baseboard_fab2(sch_1):page49_i43@mstr_sconn.sconn288_h44441004(chips)!SCONN288_H44441004_PIP-SCONN,HA!!!F150!VSS(45)!!!!
S!GND!J4B1!147!@baseboard_fab2_lib.baseboard_fab2(sch_1):page49_i43@mstr_sconn.sconn288_h44441004(chips)!SCONN288_H44441004_PIP-SCONN,HA!!!F150!VSS(46)!!!!
S!GND!J4B1!138!@baseboard_fab2_lib.baseboard_fab2(sch_1):page49_i43@mstr_sconn.sconn288_h44441004(chips)!SCONN288_H44441004_PIP-SCONN,HA!!!F150!VSS(47)!!!!
S!GND!J4B1!136!@baseboard_fab2_lib.baseboard_fab2(sch_1):page49_i43@mstr_sconn.sconn288_h44441004(chips)!SCONN288_H44441004_PIP-SCONN,HA!!!F150!VSS(48)!!!!
S!GND!J4B1!134!@baseboard_fab2_lib.baseboard_fab2(sch_1):page49_i43@mstr_sconn.sconn288_h44441004(chips)!SCONN288_H44441004_PIP-SCONN,HA!!!F150!VSS(49)!!!!
S!GND!J4B1!274!@baseboard_fab2_lib.baseboard_fab2(sch_1):page49_i43@mstr_sconn.sconn288_h44441004(chips)!SCONN288_H44441004_PIP-SCONN,HA!!!F150!VSS(4)!!!!
S!GND!J4B1!131!@baseboard_fab2_lib.baseboard_fab2(sch_1):page49_i43@mstr_sconn.sconn288_h44441004(chips)!SCONN288_H44441004_PIP-SCONN,HA!!!F150!VSS(50)!!!!
S!GND!J4B1!129!@baseboard_fab2_lib.baseboard_fab2(sch_1):page49_i43@mstr_sconn.sconn288_h44441004(chips)!SCONN288_H44441004_PIP-SCONN,HA!!!F150!VSS(51)!!!!
S!GND!J4B1!127!@baseboard_fab2_lib.baseboard_fab2(sch_1):page49_i43@mstr_sconn.sconn288_h44441004(chips)!SCONN288_H44441004_PIP-SCONN,HA!!!F150!VSS(52)!!!!
S!GND!J4B1!125!@baseboard_fab2_lib.baseboard_fab2(sch_1):page49_i43@mstr_sconn.sconn288_h44441004(chips)!SCONN288_H44441004_PIP-SCONN,HA!!!F150!VSS(53)!!!!
S!GND!J4B1!123!@baseboard_fab2_lib.baseboard_fab2(sch_1):page49_i43@mstr_sconn.sconn288_h44441004(chips)!SCONN288_H44441004_PIP-SCONN,HA!!!F150!VSS(54)!!!!
S!GND!J4B1!120!@baseboard_fab2_lib.baseboard_fab2(sch_1):page49_i43@mstr_sconn.sconn288_h44441004(chips)!SCONN288_H44441004_PIP-SCONN,HA!!!F150!VSS(55)!!!!
S!GND!J4B1!118!@baseboard_fab2_lib.baseboard_fab2(sch_1):page49_i43@mstr_sconn.sconn288_h44441004(chips)!SCONN288_H44441004_PIP-SCONN,HA!!!F150!VSS(56)!!!!
S!GND!J4B1!116!@baseboard_fab2_lib.baseboard_fab2(sch_1):page49_i43@mstr_sconn.sconn288_h44441004(chips)!SCONN288_H44441004_PIP-SCONN,HA!!!F150!VSS(57)!!!!
S!GND!J4B1!114!@baseboard_fab2_lib.baseboard_fab2(sch_1):page49_i43@mstr_sconn.sconn288_h44441004(chips)!SCONN288_H44441004_PIP-SCONN,HA!!!F150!VSS(58)!!!!
S!GND!J4B1!112!@baseboard_fab2_lib.baseboard_fab2(sch_1):page49_i43@mstr_sconn.sconn288_h44441004(chips)!SCONN288_H44441004_PIP-SCONN,HA!!!F150!VSS(59)!!!!
S!GND!J4B1!272!@baseboard_fab2_lib.baseboard_fab2(sch_1):page49_i43@mstr_sconn.sconn288_h44441004(chips)!SCONN288_H44441004_PIP-SCONN,HA!!!F150!VSS(5)!!!!
S!GND!J4B1!109!@baseboard_fab2_lib.baseboard_fab2(sch_1):page49_i43@mstr_sconn.sconn288_h44441004(chips)!SCONN288_H44441004_PIP-SCONN,HA!!!F150!VSS(60)!!!!
S!GND!J4B1!107!@baseboard_fab2_lib.baseboard_fab2(sch_1):page49_i43@mstr_sconn.sconn288_h44441004(chips)!SCONN288_H44441004_PIP-SCONN,HA!!!F150!VSS(61)!!!!
S!GND!J4B1!105!@baseboard_fab2_lib.baseboard_fab2(sch_1):page49_i43@mstr_sconn.sconn288_h44441004(chips)!SCONN288_H44441004_PIP-SCONN,HA!!!F150!VSS(62)!!!!
S!GND!J4B1!103!@baseboard_fab2_lib.baseboard_fab2(sch_1):page49_i43@mstr_sconn.sconn288_h44441004(chips)!SCONN288_H44441004_PIP-SCONN,HA!!!F150!VSS(63)!!!!
S!GND!J4B1!101!@baseboard_fab2_lib.baseboard_fab2(sch_1):page49_i43@mstr_sconn.sconn288_h44441004(chips)!SCONN288_H44441004_PIP-SCONN,HA!!!F150!VSS(64)!!!!
S!GND!J4B1!98!@baseboard_fab2_lib.baseboard_fab2(sch_1):page49_i43@mstr_sconn.sconn288_h44441004(chips)!SCONN288_H44441004_PIP-SCONN,HA!!!F150!VSS(65)!!!!
S!GND!J4B1!96!@baseboard_fab2_lib.baseboard_fab2(sch_1):page49_i43@mstr_sconn.sconn288_h44441004(chips)!SCONN288_H44441004_PIP-SCONN,HA!!!F150!VSS(66)!!!!
S!GND!J4B1!94!@baseboard_fab2_lib.baseboard_fab2(sch_1):page49_i43@mstr_sconn.sconn288_h44441004(chips)!SCONN288_H44441004_PIP-SCONN,HA!!!F150!VSS(67)!!!!
S!GND!J4B1!57!@baseboard_fab2_lib.baseboard_fab2(sch_1):page49_i43@mstr_sconn.sconn288_h44441004(chips)!SCONN288_H44441004_PIP-SCONN,HA!!!F150!VSS(68)!!!!
S!GND!J4B1!55!@baseboard_fab2_lib.baseboard_fab2(sch_1):page49_i43@mstr_sconn.sconn288_h44441004(chips)!SCONN288_H44441004_PIP-SCONN,HA!!!F150!VSS(69)!!!!
S!GND!J4B1!270!@baseboard_fab2_lib.baseboard_fab2(sch_1):page49_i43@mstr_sconn.sconn288_h44441004(chips)!SCONN288_H44441004_PIP-SCONN,HA!!!F150!VSS(6)!!!!
S!GND!J4B1!53!@baseboard_fab2_lib.baseboard_fab2(sch_1):page49_i43@mstr_sconn.sconn288_h44441004(chips)!SCONN288_H44441004_PIP-SCONN,HA!!!F150!VSS(70)!!!!
S!GND!J4B1!50!@baseboard_fab2_lib.baseboard_fab2(sch_1):page49_i43@mstr_sconn.sconn288_h44441004(chips)!SCONN288_H44441004_PIP-SCONN,HA!!!F150!VSS(71)!!!!
S!GND!J4B1!48!@baseboard_fab2_lib.baseboard_fab2(sch_1):page49_i43@mstr_sconn.sconn288_h44441004(chips)!SCONN288_H44441004_PIP-SCONN,HA!!!F150!VSS(72)!!!!
S!GND!J4B1!46!@baseboard_fab2_lib.baseboard_fab2(sch_1):page49_i43@mstr_sconn.sconn288_h44441004(chips)!SCONN288_H44441004_PIP-SCONN,HA!!!F150!VSS(73)!!!!
S!GND!J4B1!44!@baseboard_fab2_lib.baseboard_fab2(sch_1):page49_i43@mstr_sconn.sconn288_h44441004(chips)!SCONN288_H44441004_PIP-SCONN,HA!!!F150!VSS(74)!!!!
S!GND!J4B1!42!@baseboard_fab2_lib.baseboard_fab2(sch_1):page49_i43@mstr_sconn.sconn288_h44441004(chips)!SCONN288_H44441004_PIP-SCONN,HA!!!F150!VSS(75)!!!!
S!GND!J4B1!39!@baseboard_fab2_lib.baseboard_fab2(sch_1):page49_i43@mstr_sconn.sconn288_h44441004(chips)!SCONN288_H44441004_PIP-SCONN,HA!!!F150!VSS(76)!!!!
S!GND!J4B1!37!@baseboard_fab2_lib.baseboard_fab2(sch_1):page49_i43@mstr_sconn.sconn288_h44441004(chips)!SCONN288_H44441004_PIP-SCONN,HA!!!F150!VSS(77)!!!!
S!GND!J4B1!35!@baseboard_fab2_lib.baseboard_fab2(sch_1):page49_i43@mstr_sconn.sconn288_h44441004(chips)!SCONN288_H44441004_PIP-SCONN,HA!!!F150!VSS(78)!!!!
S!GND!J4B1!33!@baseboard_fab2_lib.baseboard_fab2(sch_1):page49_i43@mstr_sconn.sconn288_h44441004(chips)!SCONN288_H44441004_PIP-SCONN,HA!!!F150!VSS(79)!!!!
S!GND!J4B1!268!@baseboard_fab2_lib.baseboard_fab2(sch_1):page49_i43@mstr_sconn.sconn288_h44441004(chips)!SCONN288_H44441004_PIP-SCONN,HA!!!F150!VSS(7)!!!!
S!GND!J4B1!31!@baseboard_fab2_lib.baseboard_fab2(sch_1):page49_i43@mstr_sconn.sconn288_h44441004(chips)!SCONN288_H44441004_PIP-SCONN,HA!!!F150!VSS(80)!!!!
S!GND!J4B1!28!@baseboard_fab2_lib.baseboard_fab2(sch_1):page49_i43@mstr_sconn.sconn288_h44441004(chips)!SCONN288_H44441004_PIP-SCONN,HA!!!F150!VSS(81)!!!!
S!GND!J4B1!26!@baseboard_fab2_lib.baseboard_fab2(sch_1):page49_i43@mstr_sconn.sconn288_h44441004(chips)!SCONN288_H44441004_PIP-SCONN,HA!!!F150!VSS(82)!!!!
S!GND!J4B1!24!@baseboard_fab2_lib.baseboard_fab2(sch_1):page49_i43@mstr_sconn.sconn288_h44441004(chips)!SCONN288_H44441004_PIP-SCONN,HA!!!F150!VSS(83)!!!!
S!GND!J4B1!22!@baseboard_fab2_lib.baseboard_fab2(sch_1):page49_i43@mstr_sconn.sconn288_h44441004(chips)!SCONN288_H44441004_PIP-SCONN,HA!!!F150!VSS(84)!!!!
S!GND!J4B1!20!@baseboard_fab2_lib.baseboard_fab2(sch_1):page49_i43@mstr_sconn.sconn288_h44441004(chips)!SCONN288_H44441004_PIP-SCONN,HA!!!F150!VSS(85)!!!!
S!GND!J4B1!17!@baseboard_fab2_lib.baseboard_fab2(sch_1):page49_i43@mstr_sconn.sconn288_h44441004(chips)!SCONN288_H44441004_PIP-SCONN,HA!!!F150!VSS(86)!!!!
S!GND!J4B1!15!@baseboard_fab2_lib.baseboard_fab2(sch_1):page49_i43@mstr_sconn.sconn288_h44441004(chips)!SCONN288_H44441004_PIP-SCONN,HA!!!F150!VSS(87)!!!!
S!GND!J4B1!13!@baseboard_fab2_lib.baseboard_fab2(sch_1):page49_i43@mstr_sconn.sconn288_h44441004(chips)!SCONN288_H44441004_PIP-SCONN,HA!!!F150!VSS(88)!!!!
S!GND!J4B1!11!@baseboard_fab2_lib.baseboard_fab2(sch_1):page49_i43@mstr_sconn.sconn288_h44441004(chips)!SCONN288_H44441004_PIP-SCONN,HA!!!F150!VSS(89)!!!!
S!GND!J4B1!265!@baseboard_fab2_lib.baseboard_fab2(sch_1):page49_i43@mstr_sconn.sconn288_h44441004(chips)!SCONN288_H44441004_PIP-SCONN,HA!!!F150!VSS(8)!!!!
S!GND!J4B1!9!@baseboard_fab2_lib.baseboard_fab2(sch_1):page49_i43@mstr_sconn.sconn288_h44441004(chips)!SCONN288_H44441004_PIP-SCONN,HA!!!F150!VSS(90)!!!!
S!GND!J4B1!6!@baseboard_fab2_lib.baseboard_fab2(sch_1):page49_i43@mstr_sconn.sconn288_h44441004(chips)!SCONN288_H44441004_PIP-SCONN,HA!!!F150!VSS(91)!!!!
S!GND!J4B1!4!@baseboard_fab2_lib.baseboard_fab2(sch_1):page49_i43@mstr_sconn.sconn288_h44441004(chips)!SCONN288_H44441004_PIP-SCONN,HA!!!F150!VSS(92)!!!!
S!GND!J4B1!2!@baseboard_fab2_lib.baseboard_fab2(sch_1):page49_i43@mstr_sconn.sconn288_h44441004(chips)!SCONN288_H44441004_PIP-SCONN,HA!!!F150!VSS(93)!!!!
S!GND!J4B1!263!@baseboard_fab2_lib.baseboard_fab2(sch_1):page49_i43@mstr_sconn.sconn288_h44441004(chips)!SCONN288_H44441004_PIP-SCONN,HA!!!F150!VSS(9)!!!!
S!P12V_NVDIMM_DEF!J4B1!145!@baseboard_fab2_lib.baseboard_fab2(sch_1):page49_i169@mstr_sconn.sconn288_h44441004(chips)!SCONN288_H44441004_PIP-SCONN,HA!!!F149!\12v\(0)!!!!
S!P12V_NVDIMM_DEF!J4B1!1!@baseboard_fab2_lib.baseboard_fab2(sch_1):page49_i169@mstr_sconn.sconn288_h44441004(chips)!SCONN288_H44441004_PIP-SCONN,HA!!!F149!\12v\(1)!!!!
S!PVDDQ_DEF!J4B1!236!@baseboard_fab2_lib.baseboard_fab2(sch_1):page49_i169@mstr_sconn.sconn288_h44441004(chips)!SCONN288_H44441004_PIP-SCONN,HA!!!F149!VDD(0)!!!!
S!PVDDQ_DEF!J4B1!209!@baseboard_fab2_lib.baseboard_fab2(sch_1):page49_i169@mstr_sconn.sconn288_h44441004(chips)!SCONN288_H44441004_PIP-SCONN,HA!!!F149!VDD(10)!!!!
S!PVDDQ_DEF!J4B1!206!@baseboard_fab2_lib.baseboard_fab2(sch_1):page49_i169@mstr_sconn.sconn288_h44441004(chips)!SCONN288_H44441004_PIP-SCONN,HA!!!F149!VDD(11)!!!!
S!PVDDQ_DEF!J4B1!204!@baseboard_fab2_lib.baseboard_fab2(sch_1):page49_i169@mstr_sconn.sconn288_h44441004(chips)!SCONN288_H44441004_PIP-SCONN,HA!!!F149!VDD(12)!!!!
S!PVDDQ_DEF!J4B1!92!@baseboard_fab2_lib.baseboard_fab2(sch_1):page49_i169@mstr_sconn.sconn288_h44441004(chips)!SCONN288_H44441004_PIP-SCONN,HA!!!F149!VDD(13)!!!!
S!PVDDQ_DEF!J4B1!90!@baseboard_fab2_lib.baseboard_fab2(sch_1):page49_i169@mstr_sconn.sconn288_h44441004(chips)!SCONN288_H44441004_PIP-SCONN,HA!!!F149!VDD(14)!!!!
S!PVDDQ_DEF!J4B1!88!@baseboard_fab2_lib.baseboard_fab2(sch_1):page49_i169@mstr_sconn.sconn288_h44441004(chips)!SCONN288_H44441004_PIP-SCONN,HA!!!F149!VDD(15)!!!!
S!PVDDQ_DEF!J4B1!85!@baseboard_fab2_lib.baseboard_fab2(sch_1):page49_i169@mstr_sconn.sconn288_h44441004(chips)!SCONN288_H44441004_PIP-SCONN,HA!!!F149!VDD(16)!!!!
S!PVDDQ_DEF!J4B1!83!@baseboard_fab2_lib.baseboard_fab2(sch_1):page49_i169@mstr_sconn.sconn288_h44441004(chips)!SCONN288_H44441004_PIP-SCONN,HA!!!F149!VDD(17)!!!!
S!PVDDQ_DEF!J4B1!80!@baseboard_fab2_lib.baseboard_fab2(sch_1):page49_i169@mstr_sconn.sconn288_h44441004(chips)!SCONN288_H44441004_PIP-SCONN,HA!!!F149!VDD(18)!!!!
S!PVDDQ_DEF!J4B1!76!@baseboard_fab2_lib.baseboard_fab2(sch_1):page49_i169@mstr_sconn.sconn288_h44441004(chips)!SCONN288_H44441004_PIP-SCONN,HA!!!F149!VDD(19)!!!!
S!PVDDQ_DEF!J4B1!233!@baseboard_fab2_lib.baseboard_fab2(sch_1):page49_i169@mstr_sconn.sconn288_h44441004(chips)!SCONN288_H44441004_PIP-SCONN,HA!!!F149!VDD(1)!!!!
S!PVDDQ_DEF!J4B1!73!@baseboard_fab2_lib.baseboard_fab2(sch_1):page49_i169@mstr_sconn.sconn288_h44441004(chips)!SCONN288_H44441004_PIP-SCONN,HA!!!F149!VDD(20)!!!!
S!PVDDQ_DEF!J4B1!70!@baseboard_fab2_lib.baseboard_fab2(sch_1):page49_i169@mstr_sconn.sconn288_h44441004(chips)!SCONN288_H44441004_PIP-SCONN,HA!!!F149!VDD(21)!!!!
S!PVDDQ_DEF!J4B1!67!@baseboard_fab2_lib.baseboard_fab2(sch_1):page49_i169@mstr_sconn.sconn288_h44441004(chips)!SCONN288_H44441004_PIP-SCONN,HA!!!F149!VDD(22)!!!!
S!PVDDQ_DEF!J4B1!64!@baseboard_fab2_lib.baseboard_fab2(sch_1):page49_i169@mstr_sconn.sconn288_h44441004(chips)!SCONN288_H44441004_PIP-SCONN,HA!!!F149!VDD(23)!!!!
S!PVDDQ_DEF!J4B1!61!@baseboard_fab2_lib.baseboard_fab2(sch_1):page49_i169@mstr_sconn.sconn288_h44441004(chips)!SCONN288_H44441004_PIP-SCONN,HA!!!F149!VDD(24)!!!!
S!PVDDQ_DEF!J4B1!59!@baseboard_fab2_lib.baseboard_fab2(sch_1):page49_i169@mstr_sconn.sconn288_h44441004(chips)!SCONN288_H44441004_PIP-SCONN,HA!!!F149!VDD(25)!!!!
S!PVDDQ_DEF!J4B1!231!@baseboard_fab2_lib.baseboard_fab2(sch_1):page49_i169@mstr_sconn.sconn288_h44441004(chips)!SCONN288_H44441004_PIP-SCONN,HA!!!F149!VDD(2)!!!!
S!PVDDQ_DEF!J4B1!229!@baseboard_fab2_lib.baseboard_fab2(sch_1):page49_i169@mstr_sconn.sconn288_h44441004(chips)!SCONN288_H44441004_PIP-SCONN,HA!!!F149!VDD(3)!!!!
S!PVDDQ_DEF!J4B1!226!@baseboard_fab2_lib.baseboard_fab2(sch_1):page49_i169@mstr_sconn.sconn288_h44441004(chips)!SCONN288_H44441004_PIP-SCONN,HA!!!F149!VDD(4)!!!!
S!PVDDQ_DEF!J4B1!223!@baseboard_fab2_lib.baseboard_fab2(sch_1):page49_i169@mstr_sconn.sconn288_h44441004(chips)!SCONN288_H44441004_PIP-SCONN,HA!!!F149!VDD(5)!!!!
S!PVDDQ_DEF!J4B1!220!@baseboard_fab2_lib.baseboard_fab2(sch_1):page49_i169@mstr_sconn.sconn288_h44441004(chips)!SCONN288_H44441004_PIP-SCONN,HA!!!F149!VDD(6)!!!!
S!PVDDQ_DEF!J4B1!217!@baseboard_fab2_lib.baseboard_fab2(sch_1):page49_i169@mstr_sconn.sconn288_h44441004(chips)!SCONN288_H44441004_PIP-SCONN,HA!!!F149!VDD(7)!!!!
S!PVDDQ_DEF!J4B1!215!@baseboard_fab2_lib.baseboard_fab2(sch_1):page49_i169@mstr_sconn.sconn288_h44441004(chips)!SCONN288_H44441004_PIP-SCONN,HA!!!F149!VDD(8)!!!!
S!PVDDQ_DEF!J4B1!212!@baseboard_fab2_lib.baseboard_fab2(sch_1):page49_i169@mstr_sconn.sconn288_h44441004(chips)!SCONN288_H44441004_PIP-SCONN,HA!!!F149!VDD(9)!!!!
S!PVPP_DEF!J4B1!287!@baseboard_fab2_lib.baseboard_fab2(sch_1):page49_i169@mstr_sconn.sconn288_h44441004(chips)!SCONN288_H44441004_PIP-SCONN,HA!!!F149!VPP(0)!!!!
S!PVPP_DEF!J4B1!286!@baseboard_fab2_lib.baseboard_fab2(sch_1):page49_i169@mstr_sconn.sconn288_h44441004(chips)!SCONN288_H44441004_PIP-SCONN,HA!!!F149!VPP(1)!!!!
S!PVPP_DEF!J4B1!288!@baseboard_fab2_lib.baseboard_fab2(sch_1):page49_i169@mstr_sconn.sconn288_h44441004(chips)!SCONN288_H44441004_PIP-SCONN,HA!!!F149!VPP(2)!!!!
S!PVPP_DEF!J4B1!143!@baseboard_fab2_lib.baseboard_fab2(sch_1):page49_i169@mstr_sconn.sconn288_h44441004(chips)!SCONN288_H44441004_PIP-SCONN,HA!!!F149!VPP(3)!!!!
S!PVPP_DEF!J4B1!142!@baseboard_fab2_lib.baseboard_fab2(sch_1):page49_i169@mstr_sconn.sconn288_h44441004(chips)!SCONN288_H44441004_PIP-SCONN,HA!!!F149!VPP(4)!!!!
S!PVTT_DEF!J4B1!221!@baseboard_fab2_lib.baseboard_fab2(sch_1):page49_i169@mstr_sconn.sconn288_h44441004(chips)!SCONN288_H44441004_PIP-SCONN,HA!!!F149!VTT(0)!!!!
S!PVTT_DEF!J4B1!77!@baseboard_fab2_lib.baseboard_fab2(sch_1):page49_i169@mstr_sconn.sconn288_h44441004(chips)!SCONN288_H44441004_PIP-SCONN,HA!!!F149!VTT(1)!!!!
S!M_E_MA<0>!J4A2!79!@baseboard_fab2_lib.baseboard_fab2(sch_1):page51_i111@mstr_sconn.sconn288_h44441004(chips)!SCONN288_H44441004_PIP-SCONN,HA!!!F156!A0!!!!
S!M_E_MA<1>!J4A2!72!@baseboard_fab2_lib.baseboard_fab2(sch_1):page51_i111@mstr_sconn.sconn288_h44441004(chips)!SCONN288_H44441004_PIP-SCONN,HA!!!F156!A1!!!!
S!M_E_MA<10>!J4A2!225!@baseboard_fab2_lib.baseboard_fab2(sch_1):page51_i111@mstr_sconn.sconn288_h44441004(chips)!SCONN288_H44441004_PIP-SCONN,HA!!!F156!A10!!!!
S!M_E_MA<11>!J4A2!210!@baseboard_fab2_lib.baseboard_fab2(sch_1):page51_i111@mstr_sconn.sconn288_h44441004(chips)!SCONN288_H44441004_PIP-SCONN,HA!!!F156!A11!!!!
S!M_E_MA<12>!J4A2!65!@baseboard_fab2_lib.baseboard_fab2(sch_1):page51_i111@mstr_sconn.sconn288_h44441004(chips)!SCONN288_H44441004_PIP-SCONN,HA!!!F156!A12!!!!
S!M_E_MA<13>!J4A2!232!@baseboard_fab2_lib.baseboard_fab2(sch_1):page51_i111@mstr_sconn.sconn288_h44441004(chips)!SCONN288_H44441004_PIP-SCONN,HA!!!F156!A13!!!!
S!M_E_MA<14>!J4A2!228!@baseboard_fab2_lib.baseboard_fab2(sch_1):page51_i111@mstr_sconn.sconn288_h44441004(chips)!SCONN288_H44441004_PIP-SCONN,HA!!!F156!A14_WE_N!!!!
S!M_E_MA<15>!J4A2!86!@baseboard_fab2_lib.baseboard_fab2(sch_1):page51_i111@mstr_sconn.sconn288_h44441004(chips)!SCONN288_H44441004_PIP-SCONN,HA!!!F156!A15_CAS_N!!!!
S!M_E_MA<16>!J4A2!82!@baseboard_fab2_lib.baseboard_fab2(sch_1):page51_i111@mstr_sconn.sconn288_h44441004(chips)!SCONN288_H44441004_PIP-SCONN,HA!!!F156!A16_RAS_N!!!!
S!M_E_MA<17>!J4A2!234!@baseboard_fab2_lib.baseboard_fab2(sch_1):page51_i111@mstr_sconn.sconn288_h44441004(chips)!SCONN288_H44441004_PIP-SCONN,HA!!!F156!A17!!!!
S!M_E_MA<2>!J4A2!216!@baseboard_fab2_lib.baseboard_fab2(sch_1):page51_i111@mstr_sconn.sconn288_h44441004(chips)!SCONN288_H44441004_PIP-SCONN,HA!!!F156!A2!!!!
S!M_E_MA<3>!J4A2!71!@baseboard_fab2_lib.baseboard_fab2(sch_1):page51_i111@mstr_sconn.sconn288_h44441004(chips)!SCONN288_H44441004_PIP-SCONN,HA!!!F156!A3!!!!
S!M_E_MA<4>!J4A2!214!@baseboard_fab2_lib.baseboard_fab2(sch_1):page51_i111@mstr_sconn.sconn288_h44441004(chips)!SCONN288_H44441004_PIP-SCONN,HA!!!F156!A4!!!!
S!M_E_MA<5>!J4A2!213!@baseboard_fab2_lib.baseboard_fab2(sch_1):page51_i111@mstr_sconn.sconn288_h44441004(chips)!SCONN288_H44441004_PIP-SCONN,HA!!!F156!A5!!!!
S!M_E_MA<6>!J4A2!69!@baseboard_fab2_lib.baseboard_fab2(sch_1):page51_i111@mstr_sconn.sconn288_h44441004(chips)!SCONN288_H44441004_PIP-SCONN,HA!!!F156!A6!!!!
S!M_E_MA<7>!J4A2!211!@baseboard_fab2_lib.baseboard_fab2(sch_1):page51_i111@mstr_sconn.sconn288_h44441004(chips)!SCONN288_H44441004_PIP-SCONN,HA!!!F156!A7!!!!
S!M_E_MA<8>!J4A2!68!@baseboard_fab2_lib.baseboard_fab2(sch_1):page51_i111@mstr_sconn.sconn288_h44441004(chips)!SCONN288_H44441004_PIP-SCONN,HA!!!F156!A8!!!!
S!M_E_MA<9>!J4A2!66!@baseboard_fab2_lib.baseboard_fab2(sch_1):page51_i111@mstr_sconn.sconn288_h44441004(chips)!SCONN288_H44441004_PIP-SCONN,HA!!!F156!A9!!!!
S!M_E_ACT_N!J4A2!62!@baseboard_fab2_lib.baseboard_fab2(sch_1):page51_i111@mstr_sconn.sconn288_h44441004(chips)!SCONN288_H44441004_PIP-SCONN,HA!!!F156!ACT_N!!!!
S!M_E_ALERT_N!J4A2!208!@baseboard_fab2_lib.baseboard_fab2(sch_1):page51_i111@mstr_sconn.sconn288_h44441004(chips)!SCONN288_H44441004_PIP-SCONN,HA!!!F156!ALERT_N!!!!
S!M_E_BA<0>!J4A2!81!@baseboard_fab2_lib.baseboard_fab2(sch_1):page51_i111@mstr_sconn.sconn288_h44441004(chips)!SCONN288_H44441004_PIP-SCONN,HA!!!F156!BA(0)!!!!
S!M_E_BA<1>!J4A2!224!@baseboard_fab2_lib.baseboard_fab2(sch_1):page51_i111@mstr_sconn.sconn288_h44441004(chips)!SCONN288_H44441004_PIP-SCONN,HA!!!F156!BA(1)!!!!
S!M_E_BG<0>!J4A2!63!@baseboard_fab2_lib.baseboard_fab2(sch_1):page51_i111@mstr_sconn.sconn288_h44441004(chips)!SCONN288_H44441004_PIP-SCONN,HA!!!F156!BG(0)!!!!
S!M_E_BG<1>!J4A2!207!@baseboard_fab2_lib.baseboard_fab2(sch_1):page51_i111@mstr_sconn.sconn288_h44441004(chips)!SCONN288_H44441004_PIP-SCONN,HA!!!F156!BG(1)!!!!
S!M_E_C<2>!J4A2!235!@baseboard_fab2_lib.baseboard_fab2(sch_1):page51_i111@mstr_sconn.sconn288_h44441004(chips)!SCONN288_H44441004_PIP-SCONN,HA!!!F156!C(2)!!!!
S!M_E_ECC<1>!J4A2!49!@baseboard_fab2_lib.baseboard_fab2(sch_1):page51_i111@mstr_sconn.sconn288_h44441004(chips)!SCONN288_H44441004_PIP-SCONN,HA!!!F156!CB(0)!!!!
S!M_E_ECC<0>!J4A2!194!@baseboard_fab2_lib.baseboard_fab2(sch_1):page51_i111@mstr_sconn.sconn288_h44441004(chips)!SCONN288_H44441004_PIP-SCONN,HA!!!F156!CB(1)!!!!
S!M_E_ECC<3>!J4A2!56!@baseboard_fab2_lib.baseboard_fab2(sch_1):page51_i111@mstr_sconn.sconn288_h44441004(chips)!SCONN288_H44441004_PIP-SCONN,HA!!!F156!CB(2)!!!!
S!M_E_ECC<2>!J4A2!201!@baseboard_fab2_lib.baseboard_fab2(sch_1):page51_i111@mstr_sconn.sconn288_h44441004(chips)!SCONN288_H44441004_PIP-SCONN,HA!!!F156!CB(3)!!!!
S!M_E_ECC<5>!J4A2!47!@baseboard_fab2_lib.baseboard_fab2(sch_1):page51_i111@mstr_sconn.sconn288_h44441004(chips)!SCONN288_H44441004_PIP-SCONN,HA!!!F156!CB(4)!!!!
S!M_E_ECC<4>!J4A2!192!@baseboard_fab2_lib.baseboard_fab2(sch_1):page51_i111@mstr_sconn.sconn288_h44441004(chips)!SCONN288_H44441004_PIP-SCONN,HA!!!F156!CB(5)!!!!
S!M_E_ECC<7>!J4A2!54!@baseboard_fab2_lib.baseboard_fab2(sch_1):page51_i111@mstr_sconn.sconn288_h44441004(chips)!SCONN288_H44441004_PIP-SCONN,HA!!!F156!CB(6)!!!!
S!M_E_ECC<6>!J4A2!199!@baseboard_fab2_lib.baseboard_fab2(sch_1):page51_i111@mstr_sconn.sconn288_h44441004(chips)!SCONN288_H44441004_PIP-SCONN,HA!!!F156!CB(7)!!!!
S!M_E_CLK_DN<0>!J4A2!75!@baseboard_fab2_lib.baseboard_fab2(sch_1):page51_i111@mstr_sconn.sconn288_h44441004(chips)!SCONN288_H44441004_PIP-SCONN,HA!!!F156!CK0N!!!!
S!M_E_CLK_DP<0>!J4A2!74!@baseboard_fab2_lib.baseboard_fab2(sch_1):page51_i111@mstr_sconn.sconn288_h44441004(chips)!SCONN288_H44441004_PIP-SCONN,HA!!!F156!CK0P!!!!
S!M_E_CLK_DN<1>!J4A2!219!@baseboard_fab2_lib.baseboard_fab2(sch_1):page51_i111@mstr_sconn.sconn288_h44441004(chips)!SCONN288_H44441004_PIP-SCONN,HA!!!F156!CK1N!!!!
S!M_E_CLK_DP<1>!J4A2!218!@baseboard_fab2_lib.baseboard_fab2(sch_1):page51_i111@mstr_sconn.sconn288_h44441004(chips)!SCONN288_H44441004_PIP-SCONN,HA!!!F156!CK1P!!!!
S!M_E_CKE<0>!J4A2!60!@baseboard_fab2_lib.baseboard_fab2(sch_1):page51_i111@mstr_sconn.sconn288_h44441004(chips)!SCONN288_H44441004_PIP-SCONN,HA!!!F156!CKE(0)!!!!
S!M_E_CKE<1>!J4A2!203!@baseboard_fab2_lib.baseboard_fab2(sch_1):page51_i111@mstr_sconn.sconn288_h44441004(chips)!SCONN288_H44441004_PIP-SCONN,HA!!!F156!CKE(1)!!!!
S!M_E_DQ<1>!J4A2!5!@baseboard_fab2_lib.baseboard_fab2(sch_1):page51_i111@mstr_sconn.sconn288_h44441004(chips)!SCONN288_H44441004_PIP-SCONN,HA!!!F156!DQ(0)!!!!
S!M_E_DQ<11>!J4A2!23!@baseboard_fab2_lib.baseboard_fab2(sch_1):page51_i111@mstr_sconn.sconn288_h44441004(chips)!SCONN288_H44441004_PIP-SCONN,HA!!!F156!DQ(10)!!!!
S!M_E_DQ<10>!J4A2!168!@baseboard_fab2_lib.baseboard_fab2(sch_1):page51_i111@mstr_sconn.sconn288_h44441004(chips)!SCONN288_H44441004_PIP-SCONN,HA!!!F156!DQ(11)!!!!
S!M_E_DQ<13>!J4A2!14!@baseboard_fab2_lib.baseboard_fab2(sch_1):page51_i111@mstr_sconn.sconn288_h44441004(chips)!SCONN288_H44441004_PIP-SCONN,HA!!!F156!DQ(12)!!!!
S!M_E_DQ<12>!J4A2!159!@baseboard_fab2_lib.baseboard_fab2(sch_1):page51_i111@mstr_sconn.sconn288_h44441004(chips)!SCONN288_H44441004_PIP-SCONN,HA!!!F156!DQ(13)!!!!
S!M_E_DQ<15>!J4A2!21!@baseboard_fab2_lib.baseboard_fab2(sch_1):page51_i111@mstr_sconn.sconn288_h44441004(chips)!SCONN288_H44441004_PIP-SCONN,HA!!!F156!DQ(14)!!!!
S!M_E_DQ<14>!J4A2!166!@baseboard_fab2_lib.baseboard_fab2(sch_1):page51_i111@mstr_sconn.sconn288_h44441004(chips)!SCONN288_H44441004_PIP-SCONN,HA!!!F156!DQ(15)!!!!
S!M_E_DQ<17>!J4A2!27!@baseboard_fab2_lib.baseboard_fab2(sch_1):page51_i111@mstr_sconn.sconn288_h44441004(chips)!SCONN288_H44441004_PIP-SCONN,HA!!!F156!DQ(16)!!!!
S!M_E_DQ<16>!J4A2!172!@baseboard_fab2_lib.baseboard_fab2(sch_1):page51_i111@mstr_sconn.sconn288_h44441004(chips)!SCONN288_H44441004_PIP-SCONN,HA!!!F156!DQ(17)!!!!
S!M_E_DQ<19>!J4A2!34!@baseboard_fab2_lib.baseboard_fab2(sch_1):page51_i111@mstr_sconn.sconn288_h44441004(chips)!SCONN288_H44441004_PIP-SCONN,HA!!!F156!DQ(18)!!!!
S!M_E_DQ<18>!J4A2!179!@baseboard_fab2_lib.baseboard_fab2(sch_1):page51_i111@mstr_sconn.sconn288_h44441004(chips)!SCONN288_H44441004_PIP-SCONN,HA!!!F156!DQ(19)!!!!
S!M_E_DQ<0>!J4A2!150!@baseboard_fab2_lib.baseboard_fab2(sch_1):page51_i111@mstr_sconn.sconn288_h44441004(chips)!SCONN288_H44441004_PIP-SCONN,HA!!!F156!DQ(1)!!!!
S!M_E_DQ<21>!J4A2!25!@baseboard_fab2_lib.baseboard_fab2(sch_1):page51_i111@mstr_sconn.sconn288_h44441004(chips)!SCONN288_H44441004_PIP-SCONN,HA!!!F156!DQ(20)!!!!
S!M_E_DQ<20>!J4A2!170!@baseboard_fab2_lib.baseboard_fab2(sch_1):page51_i111@mstr_sconn.sconn288_h44441004(chips)!SCONN288_H44441004_PIP-SCONN,HA!!!F156!DQ(21)!!!!
S!M_E_DQ<23>!J4A2!32!@baseboard_fab2_lib.baseboard_fab2(sch_1):page51_i111@mstr_sconn.sconn288_h44441004(chips)!SCONN288_H44441004_PIP-SCONN,HA!!!F156!DQ(22)!!!!
S!M_E_DQ<22>!J4A2!177!@baseboard_fab2_lib.baseboard_fab2(sch_1):page51_i111@mstr_sconn.sconn288_h44441004(chips)!SCONN288_H44441004_PIP-SCONN,HA!!!F156!DQ(23)!!!!
S!M_E_DQ<25>!J4A2!38!@baseboard_fab2_lib.baseboard_fab2(sch_1):page51_i111@mstr_sconn.sconn288_h44441004(chips)!SCONN288_H44441004_PIP-SCONN,HA!!!F156!DQ(24)!!!!
S!M_E_DQ<24>!J4A2!183!@baseboard_fab2_lib.baseboard_fab2(sch_1):page51_i111@mstr_sconn.sconn288_h44441004(chips)!SCONN288_H44441004_PIP-SCONN,HA!!!F156!DQ(25)!!!!
S!M_E_DQ<27>!J4A2!45!@baseboard_fab2_lib.baseboard_fab2(sch_1):page51_i111@mstr_sconn.sconn288_h44441004(chips)!SCONN288_H44441004_PIP-SCONN,HA!!!F156!DQ(26)!!!!
S!M_E_DQ<26>!J4A2!190!@baseboard_fab2_lib.baseboard_fab2(sch_1):page51_i111@mstr_sconn.sconn288_h44441004(chips)!SCONN288_H44441004_PIP-SCONN,HA!!!F156!DQ(27)!!!!
S!M_E_DQ<29>!J4A2!36!@baseboard_fab2_lib.baseboard_fab2(sch_1):page51_i111@mstr_sconn.sconn288_h44441004(chips)!SCONN288_H44441004_PIP-SCONN,HA!!!F156!DQ(28)!!!!
S!M_E_DQ<28>!J4A2!181!@baseboard_fab2_lib.baseboard_fab2(sch_1):page51_i111@mstr_sconn.sconn288_h44441004(chips)!SCONN288_H44441004_PIP-SCONN,HA!!!F156!DQ(29)!!!!
S!M_E_DQ<3>!J4A2!12!@baseboard_fab2_lib.baseboard_fab2(sch_1):page51_i111@mstr_sconn.sconn288_h44441004(chips)!SCONN288_H44441004_PIP-SCONN,HA!!!F156!DQ(2)!!!!
S!M_E_DQ<31>!J4A2!43!@baseboard_fab2_lib.baseboard_fab2(sch_1):page51_i111@mstr_sconn.sconn288_h44441004(chips)!SCONN288_H44441004_PIP-SCONN,HA!!!F156!DQ(30)!!!!
S!M_E_DQ<30>!J4A2!188!@baseboard_fab2_lib.baseboard_fab2(sch_1):page51_i111@mstr_sconn.sconn288_h44441004(chips)!SCONN288_H44441004_PIP-SCONN,HA!!!F156!DQ(31)!!!!
S!M_E_DQ<33>!J4A2!97!@baseboard_fab2_lib.baseboard_fab2(sch_1):page51_i111@mstr_sconn.sconn288_h44441004(chips)!SCONN288_H44441004_PIP-SCONN,HA!!!F156!DQ(32)!!!!
S!M_E_DQ<32>!J4A2!242!@baseboard_fab2_lib.baseboard_fab2(sch_1):page51_i111@mstr_sconn.sconn288_h44441004(chips)!SCONN288_H44441004_PIP-SCONN,HA!!!F156!DQ(33)!!!!
S!M_E_DQ<35>!J4A2!104!@baseboard_fab2_lib.baseboard_fab2(sch_1):page51_i111@mstr_sconn.sconn288_h44441004(chips)!SCONN288_H44441004_PIP-SCONN,HA!!!F156!DQ(34)!!!!
S!M_E_DQ<34>!J4A2!249!@baseboard_fab2_lib.baseboard_fab2(sch_1):page51_i111@mstr_sconn.sconn288_h44441004(chips)!SCONN288_H44441004_PIP-SCONN,HA!!!F156!DQ(35)!!!!
S!M_E_DQ<37>!J4A2!95!@baseboard_fab2_lib.baseboard_fab2(sch_1):page51_i111@mstr_sconn.sconn288_h44441004(chips)!SCONN288_H44441004_PIP-SCONN,HA!!!F156!DQ(36)!!!!
S!M_E_DQ<36>!J4A2!240!@baseboard_fab2_lib.baseboard_fab2(sch_1):page51_i111@mstr_sconn.sconn288_h44441004(chips)!SCONN288_H44441004_PIP-SCONN,HA!!!F156!DQ(37)!!!!
S!M_E_DQ<39>!J4A2!102!@baseboard_fab2_lib.baseboard_fab2(sch_1):page51_i111@mstr_sconn.sconn288_h44441004(chips)!SCONN288_H44441004_PIP-SCONN,HA!!!F156!DQ(38)!!!!
S!M_E_DQ<38>!J4A2!247!@baseboard_fab2_lib.baseboard_fab2(sch_1):page51_i111@mstr_sconn.sconn288_h44441004(chips)!SCONN288_H44441004_PIP-SCONN,HA!!!F156!DQ(39)!!!!
S!M_E_DQ<2>!J4A2!157!@baseboard_fab2_lib.baseboard_fab2(sch_1):page51_i111@mstr_sconn.sconn288_h44441004(chips)!SCONN288_H44441004_PIP-SCONN,HA!!!F156!DQ(3)!!!!
S!M_E_DQ<41>!J4A2!108!@baseboard_fab2_lib.baseboard_fab2(sch_1):page51_i111@mstr_sconn.sconn288_h44441004(chips)!SCONN288_H44441004_PIP-SCONN,HA!!!F156!DQ(40)!!!!
S!M_E_DQ<40>!J4A2!253!@baseboard_fab2_lib.baseboard_fab2(sch_1):page51_i111@mstr_sconn.sconn288_h44441004(chips)!SCONN288_H44441004_PIP-SCONN,HA!!!F156!DQ(41)!!!!
S!M_E_DQ<43>!J4A2!115!@baseboard_fab2_lib.baseboard_fab2(sch_1):page51_i111@mstr_sconn.sconn288_h44441004(chips)!SCONN288_H44441004_PIP-SCONN,HA!!!F156!DQ(42)!!!!
S!M_E_DQ<42>!J4A2!260!@baseboard_fab2_lib.baseboard_fab2(sch_1):page51_i111@mstr_sconn.sconn288_h44441004(chips)!SCONN288_H44441004_PIP-SCONN,HA!!!F156!DQ(43)!!!!
S!M_E_DQ<45>!J4A2!106!@baseboard_fab2_lib.baseboard_fab2(sch_1):page51_i111@mstr_sconn.sconn288_h44441004(chips)!SCONN288_H44441004_PIP-SCONN,HA!!!F156!DQ(44)!!!!
S!M_E_DQ<44>!J4A2!251!@baseboard_fab2_lib.baseboard_fab2(sch_1):page51_i111@mstr_sconn.sconn288_h44441004(chips)!SCONN288_H44441004_PIP-SCONN,HA!!!F156!DQ(45)!!!!
S!M_E_DQ<47>!J4A2!113!@baseboard_fab2_lib.baseboard_fab2(sch_1):page51_i111@mstr_sconn.sconn288_h44441004(chips)!SCONN288_H44441004_PIP-SCONN,HA!!!F156!DQ(46)!!!!
S!M_E_DQ<46>!J4A2!258!@baseboard_fab2_lib.baseboard_fab2(sch_1):page51_i111@mstr_sconn.sconn288_h44441004(chips)!SCONN288_H44441004_PIP-SCONN,HA!!!F156!DQ(47)!!!!
S!M_E_DQ<49>!J4A2!119!@baseboard_fab2_lib.baseboard_fab2(sch_1):page51_i111@mstr_sconn.sconn288_h44441004(chips)!SCONN288_H44441004_PIP-SCONN,HA!!!F156!DQ(48)!!!!
S!M_E_DQ<48>!J4A2!264!@baseboard_fab2_lib.baseboard_fab2(sch_1):page51_i111@mstr_sconn.sconn288_h44441004(chips)!SCONN288_H44441004_PIP-SCONN,HA!!!F156!DQ(49)!!!!
S!M_E_DQ<5>!J4A2!3!@baseboard_fab2_lib.baseboard_fab2(sch_1):page51_i111@mstr_sconn.sconn288_h44441004(chips)!SCONN288_H44441004_PIP-SCONN,HA!!!F156!DQ(4)!!!!
S!M_E_DQ<51>!J4A2!126!@baseboard_fab2_lib.baseboard_fab2(sch_1):page51_i111@mstr_sconn.sconn288_h44441004(chips)!SCONN288_H44441004_PIP-SCONN,HA!!!F156!DQ(50)!!!!
S!M_E_DQ<50>!J4A2!271!@baseboard_fab2_lib.baseboard_fab2(sch_1):page51_i111@mstr_sconn.sconn288_h44441004(chips)!SCONN288_H44441004_PIP-SCONN,HA!!!F156!DQ(51)!!!!
S!M_E_DQ<53>!J4A2!117!@baseboard_fab2_lib.baseboard_fab2(sch_1):page51_i111@mstr_sconn.sconn288_h44441004(chips)!SCONN288_H44441004_PIP-SCONN,HA!!!F156!DQ(52)!!!!
S!M_E_DQ<52>!J4A2!262!@baseboard_fab2_lib.baseboard_fab2(sch_1):page51_i111@mstr_sconn.sconn288_h44441004(chips)!SCONN288_H44441004_PIP-SCONN,HA!!!F156!DQ(53)!!!!
S!M_E_DQ<55>!J4A2!124!@baseboard_fab2_lib.baseboard_fab2(sch_1):page51_i111@mstr_sconn.sconn288_h44441004(chips)!SCONN288_H44441004_PIP-SCONN,HA!!!F156!DQ(54)!!!!
S!M_E_DQ<54>!J4A2!269!@baseboard_fab2_lib.baseboard_fab2(sch_1):page51_i111@mstr_sconn.sconn288_h44441004(chips)!SCONN288_H44441004_PIP-SCONN,HA!!!F156!DQ(55)!!!!
S!M_E_DQ<57>!J4A2!130!@baseboard_fab2_lib.baseboard_fab2(sch_1):page51_i111@mstr_sconn.sconn288_h44441004(chips)!SCONN288_H44441004_PIP-SCONN,HA!!!F156!DQ(56)!!!!
S!M_E_DQ<56>!J4A2!275!@baseboard_fab2_lib.baseboard_fab2(sch_1):page51_i111@mstr_sconn.sconn288_h44441004(chips)!SCONN288_H44441004_PIP-SCONN,HA!!!F156!DQ(57)!!!!
S!M_E_DQ<59>!J4A2!137!@baseboard_fab2_lib.baseboard_fab2(sch_1):page51_i111@mstr_sconn.sconn288_h44441004(chips)!SCONN288_H44441004_PIP-SCONN,HA!!!F156!DQ(58)!!!!
S!M_E_DQ<58>!J4A2!282!@baseboard_fab2_lib.baseboard_fab2(sch_1):page51_i111@mstr_sconn.sconn288_h44441004(chips)!SCONN288_H44441004_PIP-SCONN,HA!!!F156!DQ(59)!!!!
S!M_E_DQ<4>!J4A2!148!@baseboard_fab2_lib.baseboard_fab2(sch_1):page51_i111@mstr_sconn.sconn288_h44441004(chips)!SCONN288_H44441004_PIP-SCONN,HA!!!F156!DQ(5)!!!!
S!M_E_DQ<61>!J4A2!128!@baseboard_fab2_lib.baseboard_fab2(sch_1):page51_i111@mstr_sconn.sconn288_h44441004(chips)!SCONN288_H44441004_PIP-SCONN,HA!!!F156!DQ(60)!!!!
S!M_E_DQ<60>!J4A2!273!@baseboard_fab2_lib.baseboard_fab2(sch_1):page51_i111@mstr_sconn.sconn288_h44441004(chips)!SCONN288_H44441004_PIP-SCONN,HA!!!F156!DQ(61)!!!!
S!M_E_DQ<63>!J4A2!135!@baseboard_fab2_lib.baseboard_fab2(sch_1):page51_i111@mstr_sconn.sconn288_h44441004(chips)!SCONN288_H44441004_PIP-SCONN,HA!!!F156!DQ(62)!!!!
S!M_E_DQ<62>!J4A2!280!@baseboard_fab2_lib.baseboard_fab2(sch_1):page51_i111@mstr_sconn.sconn288_h44441004(chips)!SCONN288_H44441004_PIP-SCONN,HA!!!F156!DQ(63)!!!!
S!M_E_DQ<7>!J4A2!10!@baseboard_fab2_lib.baseboard_fab2(sch_1):page51_i111@mstr_sconn.sconn288_h44441004(chips)!SCONN288_H44441004_PIP-SCONN,HA!!!F156!DQ(6)!!!!
S!M_E_DQ<6>!J4A2!155!@baseboard_fab2_lib.baseboard_fab2(sch_1):page51_i111@mstr_sconn.sconn288_h44441004(chips)!SCONN288_H44441004_PIP-SCONN,HA!!!F156!DQ(7)!!!!
S!M_E_DQ<9>!J4A2!16!@baseboard_fab2_lib.baseboard_fab2(sch_1):page51_i111@mstr_sconn.sconn288_h44441004(chips)!SCONN288_H44441004_PIP-SCONN,HA!!!F156!DQ(8)!!!!
S!M_E_DQ<8>!J4A2!161!@baseboard_fab2_lib.baseboard_fab2(sch_1):page51_i111@mstr_sconn.sconn288_h44441004(chips)!SCONN288_H44441004_PIP-SCONN,HA!!!F156!DQ(9)!!!!
S!FM_DIMM_EVENT_COD_N!J4A2!78!@baseboard_fab2_lib.baseboard_fab2(sch_1):page51_i111@mstr_sconn.sconn288_h44441004(chips)!SCONN288_H44441004_PIP-SCONN,HA!!!F156!EVENT_N!!!!
S!M_E_ODT<0>!J4A2!87!@baseboard_fab2_lib.baseboard_fab2(sch_1):page51_i111@mstr_sconn.sconn288_h44441004(chips)!SCONN288_H44441004_PIP-SCONN,HA!!!F156!ODT(0)!!!!
S!M_E_ODT<1>!J4A2!91!@baseboard_fab2_lib.baseboard_fab2(sch_1):page51_i111@mstr_sconn.sconn288_h44441004(chips)!SCONN288_H44441004_PIP-SCONN,HA!!!F156!ODT(1)!!!!
S!M_E_PAR!J4A2!222!@baseboard_fab2_lib.baseboard_fab2(sch_1):page51_i111@mstr_sconn.sconn288_h44441004(chips)!SCONN288_H44441004_PIP-SCONN,HA!!!F156!PAR!!!!
S!M_DEF_RST_N!J4A2!58!@baseboard_fab2_lib.baseboard_fab2(sch_1):page51_i111@mstr_sconn.sconn288_h44441004(chips)!SCONN288_H44441004_PIP-SCONN,HA!!!F156!RESET_N!!!!
S!TP_CH_E_DIMM_E0_RFU_0!J4A2!205!@baseboard_fab2_lib.baseboard_fab2(sch_1):page51_i111@mstr_sconn.sconn288_h44441004(chips)!SCONN288_H44441004_PIP-SCONN,HA!!!F156!RFU(0)!!!!
S!TP_CH_E_DIMM_E0_RFU_1!J4A2!227!@baseboard_fab2_lib.baseboard_fab2(sch_1):page51_i111@mstr_sconn.sconn288_h44441004(chips)!SCONN288_H44441004_PIP-SCONN,HA!!!F156!RFU(1)!!!!
S!TP_CH_E_DIMM_E0_RFU_2!J4A2!144!@baseboard_fab2_lib.baseboard_fab2(sch_1):page51_i111@mstr_sconn.sconn288_h44441004(chips)!SCONN288_H44441004_PIP-SCONN,HA!!!F156!RFU(2)!!!!
S!M_E_CS_N<0>!J4A2!84!@baseboard_fab2_lib.baseboard_fab2(sch_1):page51_i111@mstr_sconn.sconn288_h44441004(chips)!SCONN288_H44441004_PIP-SCONN,HA!!!F156!S0_N!!!!
S!M_E_CS_N<1>!J4A2!89!@baseboard_fab2_lib.baseboard_fab2(sch_1):page51_i111@mstr_sconn.sconn288_h44441004(chips)!SCONN288_H44441004_PIP-SCONN,HA!!!F156!S1_N!!!!
S!M_E_CS_N<2>!J4A2!93!@baseboard_fab2_lib.baseboard_fab2(sch_1):page51_i111@mstr_sconn.sconn288_h44441004(chips)!SCONN288_H44441004_PIP-SCONN,HA!!!F156!S2_N_C(0)!!!!
S!M_E_CS_N<3>!J4A2!237!@baseboard_fab2_lib.baseboard_fab2(sch_1):page51_i111@mstr_sconn.sconn288_h44441004(chips)!SCONN288_H44441004_PIP-SCONN,HA!!!F156!S3_N_C(1)!!!!
S!GND!J4A2!139!@baseboard_fab2_lib.baseboard_fab2(sch_1):page51_i111@mstr_sconn.sconn288_h44441004(chips)!SCONN288_H44441004_PIP-SCONN,HA!!!F156!SA(0)!!!!
S!PVPP_DEF!J4A2!140!@baseboard_fab2_lib.baseboard_fab2(sch_1):page51_i111@mstr_sconn.sconn288_h44441004(chips)!SCONN288_H44441004_PIP-SCONN,HA!!!F156!SA(1)!!!!
S!GND!J4A2!238!@baseboard_fab2_lib.baseboard_fab2(sch_1):page51_i111@mstr_sconn.sconn288_h44441004(chips)!SCONN288_H44441004_PIP-SCONN,HA!!!F156!SA(2)!!!!
S!FM_ADR_COMPLETE_DEF_N!J4A2!230!@baseboard_fab2_lib.baseboard_fab2(sch_1):page51_i111@mstr_sconn.sconn288_h44441004(chips)!SCONN288_H44441004_PIP-SCONN,HA!!!F156!SAVE_N_NC!!!!
S!SMB_DDR_DEF_VPP_SCL!J4A2!141!@baseboard_fab2_lib.baseboard_fab2(sch_1):page51_i111@mstr_sconn.sconn288_h44441004(chips)!SCONN288_H44441004_PIP-SCONN,HA!!!F156!SCL!!!!
S!SMB_DDR_DEF_VPP_SDA!J4A2!285!@baseboard_fab2_lib.baseboard_fab2(sch_1):page51_i111@mstr_sconn.sconn288_h44441004(chips)!SCONN288_H44441004_PIP-SCONN,HA!!!F156!SDA!!!!
S!PVPP_DEF!J4A2!284!@baseboard_fab2_lib.baseboard_fab2(sch_1):page51_i111@mstr_sconn.sconn288_h44441004(chips)!SCONN288_H44441004_PIP-SCONN,HA!!!F156!VDDSPD!!!!
S!M_E_VREF!J4A2!146!@baseboard_fab2_lib.baseboard_fab2(sch_1):page51_i111@mstr_sconn.sconn288_h44441004(chips)!SCONN288_H44441004_PIP-SCONN,HA!!!F156!VREFCA!!!!
S!M_E_DQS_DN<0>!J4A2!152!@baseboard_fab2_lib.baseboard_fab2(sch_1):page51_i66@mstr_sconn.sconn288_h44441004(chips)!SCONN288_H44441004_PIP-SCONN,HA!!!F155!DQS0N!!!!
S!M_E_DQS_DP<0>!J4A2!153!@baseboard_fab2_lib.baseboard_fab2(sch_1):page51_i66@mstr_sconn.sconn288_h44441004(chips)!SCONN288_H44441004_PIP-SCONN,HA!!!F155!DQS0P!!!!
S!M_E_DQS_DN<10>!J4A2!19!@baseboard_fab2_lib.baseboard_fab2(sch_1):page51_i66@mstr_sconn.sconn288_h44441004(chips)!SCONN288_H44441004_PIP-SCONN,HA!!!F155!DQS10N!!!!
S!M_E_DQS_DP<10>!J4A2!18!@baseboard_fab2_lib.baseboard_fab2(sch_1):page51_i66@mstr_sconn.sconn288_h44441004(chips)!SCONN288_H44441004_PIP-SCONN,HA!!!F155!DQS10P!!!!
S!M_E_DQS_DN<11>!J4A2!30!@baseboard_fab2_lib.baseboard_fab2(sch_1):page51_i66@mstr_sconn.sconn288_h44441004(chips)!SCONN288_H44441004_PIP-SCONN,HA!!!F155!DQS11N!!!!
S!M_E_DQS_DP<11>!J4A2!29!@baseboard_fab2_lib.baseboard_fab2(sch_1):page51_i66@mstr_sconn.sconn288_h44441004(chips)!SCONN288_H44441004_PIP-SCONN,HA!!!F155!DQS11P!!!!
S!M_E_DQS_DN<12>!J4A2!41!@baseboard_fab2_lib.baseboard_fab2(sch_1):page51_i66@mstr_sconn.sconn288_h44441004(chips)!SCONN288_H44441004_PIP-SCONN,HA!!!F155!DQS12N!!!!
S!M_E_DQS_DP<12>!J4A2!40!@baseboard_fab2_lib.baseboard_fab2(sch_1):page51_i66@mstr_sconn.sconn288_h44441004(chips)!SCONN288_H44441004_PIP-SCONN,HA!!!F155!DQS12P!!!!
S!M_E_DQS_DN<13>!J4A2!100!@baseboard_fab2_lib.baseboard_fab2(sch_1):page51_i66@mstr_sconn.sconn288_h44441004(chips)!SCONN288_H44441004_PIP-SCONN,HA!!!F155!DQS13N!!!!
S!M_E_DQS_DP<13>!J4A2!99!@baseboard_fab2_lib.baseboard_fab2(sch_1):page51_i66@mstr_sconn.sconn288_h44441004(chips)!SCONN288_H44441004_PIP-SCONN,HA!!!F155!DQS13P!!!!
S!M_E_DQS_DN<14>!J4A2!111!@baseboard_fab2_lib.baseboard_fab2(sch_1):page51_i66@mstr_sconn.sconn288_h44441004(chips)!SCONN288_H44441004_PIP-SCONN,HA!!!F155!DQS14N!!!!
S!M_E_DQS_DP<14>!J4A2!110!@baseboard_fab2_lib.baseboard_fab2(sch_1):page51_i66@mstr_sconn.sconn288_h44441004(chips)!SCONN288_H44441004_PIP-SCONN,HA!!!F155!DQS14P!!!!
S!M_E_DQS_DN<15>!J4A2!122!@baseboard_fab2_lib.baseboard_fab2(sch_1):page51_i66@mstr_sconn.sconn288_h44441004(chips)!SCONN288_H44441004_PIP-SCONN,HA!!!F155!DQS15N!!!!
S!M_E_DQS_DP<15>!J4A2!121!@baseboard_fab2_lib.baseboard_fab2(sch_1):page51_i66@mstr_sconn.sconn288_h44441004(chips)!SCONN288_H44441004_PIP-SCONN,HA!!!F155!DQS15P!!!!
S!M_E_DQS_DN<16>!J4A2!133!@baseboard_fab2_lib.baseboard_fab2(sch_1):page51_i66@mstr_sconn.sconn288_h44441004(chips)!SCONN288_H44441004_PIP-SCONN,HA!!!F155!DQS16N!!!!
S!M_E_DQS_DP<16>!J4A2!132!@baseboard_fab2_lib.baseboard_fab2(sch_1):page51_i66@mstr_sconn.sconn288_h44441004(chips)!SCONN288_H44441004_PIP-SCONN,HA!!!F155!DQS16P!!!!
S!M_E_DQS_DN<17>!J4A2!52!@baseboard_fab2_lib.baseboard_fab2(sch_1):page51_i66@mstr_sconn.sconn288_h44441004(chips)!SCONN288_H44441004_PIP-SCONN,HA!!!F155!DQS17N!!!!
S!M_E_DQS_DP<17>!J4A2!51!@baseboard_fab2_lib.baseboard_fab2(sch_1):page51_i66@mstr_sconn.sconn288_h44441004(chips)!SCONN288_H44441004_PIP-SCONN,HA!!!F155!DQS17P!!!!
S!M_E_DQS_DN<1>!J4A2!163!@baseboard_fab2_lib.baseboard_fab2(sch_1):page51_i66@mstr_sconn.sconn288_h44441004(chips)!SCONN288_H44441004_PIP-SCONN,HA!!!F155!DQS1N!!!!
S!M_E_DQS_DP<1>!J4A2!164!@baseboard_fab2_lib.baseboard_fab2(sch_1):page51_i66@mstr_sconn.sconn288_h44441004(chips)!SCONN288_H44441004_PIP-SCONN,HA!!!F155!DQS1P!!!!
S!M_E_DQS_DN<2>!J4A2!174!@baseboard_fab2_lib.baseboard_fab2(sch_1):page51_i66@mstr_sconn.sconn288_h44441004(chips)!SCONN288_H44441004_PIP-SCONN,HA!!!F155!DQS2N!!!!
S!M_E_DQS_DP<2>!J4A2!175!@baseboard_fab2_lib.baseboard_fab2(sch_1):page51_i66@mstr_sconn.sconn288_h44441004(chips)!SCONN288_H44441004_PIP-SCONN,HA!!!F155!DQS2P!!!!
S!M_E_DQS_DN<3>!J4A2!185!@baseboard_fab2_lib.baseboard_fab2(sch_1):page51_i66@mstr_sconn.sconn288_h44441004(chips)!SCONN288_H44441004_PIP-SCONN,HA!!!F155!DQS3N!!!!
S!M_E_DQS_DP<3>!J4A2!186!@baseboard_fab2_lib.baseboard_fab2(sch_1):page51_i66@mstr_sconn.sconn288_h44441004(chips)!SCONN288_H44441004_PIP-SCONN,HA!!!F155!DQS3P!!!!
S!M_E_DQS_DN<4>!J4A2!244!@baseboard_fab2_lib.baseboard_fab2(sch_1):page51_i66@mstr_sconn.sconn288_h44441004(chips)!SCONN288_H44441004_PIP-SCONN,HA!!!F155!DQS4N!!!!
S!M_E_DQS_DP<4>!J4A2!245!@baseboard_fab2_lib.baseboard_fab2(sch_1):page51_i66@mstr_sconn.sconn288_h44441004(chips)!SCONN288_H44441004_PIP-SCONN,HA!!!F155!DQS4P!!!!
S!M_E_DQS_DN<5>!J4A2!255!@baseboard_fab2_lib.baseboard_fab2(sch_1):page51_i66@mstr_sconn.sconn288_h44441004(chips)!SCONN288_H44441004_PIP-SCONN,HA!!!F155!DQS5N!!!!
S!M_E_DQS_DP<5>!J4A2!256!@baseboard_fab2_lib.baseboard_fab2(sch_1):page51_i66@mstr_sconn.sconn288_h44441004(chips)!SCONN288_H44441004_PIP-SCONN,HA!!!F155!DQS5P!!!!
S!M_E_DQS_DN<6>!J4A2!266!@baseboard_fab2_lib.baseboard_fab2(sch_1):page51_i66@mstr_sconn.sconn288_h44441004(chips)!SCONN288_H44441004_PIP-SCONN,HA!!!F155!DQS6N!!!!
S!M_E_DQS_DP<6>!J4A2!267!@baseboard_fab2_lib.baseboard_fab2(sch_1):page51_i66@mstr_sconn.sconn288_h44441004(chips)!SCONN288_H44441004_PIP-SCONN,HA!!!F155!DQS6P!!!!
S!M_E_DQS_DN<7>!J4A2!277!@baseboard_fab2_lib.baseboard_fab2(sch_1):page51_i66@mstr_sconn.sconn288_h44441004(chips)!SCONN288_H44441004_PIP-SCONN,HA!!!F155!DQS7N!!!!
S!M_E_DQS_DP<7>!J4A2!278!@baseboard_fab2_lib.baseboard_fab2(sch_1):page51_i66@mstr_sconn.sconn288_h44441004(chips)!SCONN288_H44441004_PIP-SCONN,HA!!!F155!DQS7P!!!!
S!M_E_DQS_DN<8>!J4A2!196!@baseboard_fab2_lib.baseboard_fab2(sch_1):page51_i66@mstr_sconn.sconn288_h44441004(chips)!SCONN288_H44441004_PIP-SCONN,HA!!!F155!DQS8N!!!!
S!M_E_DQS_DP<8>!J4A2!197!@baseboard_fab2_lib.baseboard_fab2(sch_1):page51_i66@mstr_sconn.sconn288_h44441004(chips)!SCONN288_H44441004_PIP-SCONN,HA!!!F155!DQS8P!!!!
S!M_E_DQS_DN<9>!J4A2!8!@baseboard_fab2_lib.baseboard_fab2(sch_1):page51_i66@mstr_sconn.sconn288_h44441004(chips)!SCONN288_H44441004_PIP-SCONN,HA!!!F155!DQS9N!!!!
S!M_E_DQS_DP<9>!J4A2!7!@baseboard_fab2_lib.baseboard_fab2(sch_1):page51_i66@mstr_sconn.sconn288_h44441004(chips)!SCONN288_H44441004_PIP-SCONN,HA!!!F155!DQS9P!!!!
S!GND!J4A2!283!@baseboard_fab2_lib.baseboard_fab2(sch_1):page51_i43@mstr_sconn.sconn288_h44441004(chips)!SCONN288_H44441004_PIP-SCONN,HA!!!F154!VSS(0)!!!!
S!GND!J4A2!261!@baseboard_fab2_lib.baseboard_fab2(sch_1):page51_i43@mstr_sconn.sconn288_h44441004(chips)!SCONN288_H44441004_PIP-SCONN,HA!!!F154!VSS(10)!!!!
S!GND!J4A2!259!@baseboard_fab2_lib.baseboard_fab2(sch_1):page51_i43@mstr_sconn.sconn288_h44441004(chips)!SCONN288_H44441004_PIP-SCONN,HA!!!F154!VSS(11)!!!!
S!GND!J4A2!257!@baseboard_fab2_lib.baseboard_fab2(sch_1):page51_i43@mstr_sconn.sconn288_h44441004(chips)!SCONN288_H44441004_PIP-SCONN,HA!!!F154!VSS(12)!!!!
S!GND!J4A2!254!@baseboard_fab2_lib.baseboard_fab2(sch_1):page51_i43@mstr_sconn.sconn288_h44441004(chips)!SCONN288_H44441004_PIP-SCONN,HA!!!F154!VSS(13)!!!!
S!GND!J4A2!252!@baseboard_fab2_lib.baseboard_fab2(sch_1):page51_i43@mstr_sconn.sconn288_h44441004(chips)!SCONN288_H44441004_PIP-SCONN,HA!!!F154!VSS(14)!!!!
S!GND!J4A2!250!@baseboard_fab2_lib.baseboard_fab2(sch_1):page51_i43@mstr_sconn.sconn288_h44441004(chips)!SCONN288_H44441004_PIP-SCONN,HA!!!F154!VSS(15)!!!!
S!GND!J4A2!248!@baseboard_fab2_lib.baseboard_fab2(sch_1):page51_i43@mstr_sconn.sconn288_h44441004(chips)!SCONN288_H44441004_PIP-SCONN,HA!!!F154!VSS(16)!!!!
S!GND!J4A2!246!@baseboard_fab2_lib.baseboard_fab2(sch_1):page51_i43@mstr_sconn.sconn288_h44441004(chips)!SCONN288_H44441004_PIP-SCONN,HA!!!F154!VSS(17)!!!!
S!GND!J4A2!243!@baseboard_fab2_lib.baseboard_fab2(sch_1):page51_i43@mstr_sconn.sconn288_h44441004(chips)!SCONN288_H44441004_PIP-SCONN,HA!!!F154!VSS(18)!!!!
S!GND!J4A2!241!@baseboard_fab2_lib.baseboard_fab2(sch_1):page51_i43@mstr_sconn.sconn288_h44441004(chips)!SCONN288_H44441004_PIP-SCONN,HA!!!F154!VSS(19)!!!!
S!GND!J4A2!281!@baseboard_fab2_lib.baseboard_fab2(sch_1):page51_i43@mstr_sconn.sconn288_h44441004(chips)!SCONN288_H44441004_PIP-SCONN,HA!!!F154!VSS(1)!!!!
S!GND!J4A2!239!@baseboard_fab2_lib.baseboard_fab2(sch_1):page51_i43@mstr_sconn.sconn288_h44441004(chips)!SCONN288_H44441004_PIP-SCONN,HA!!!F154!VSS(20)!!!!
S!GND!J4A2!202!@baseboard_fab2_lib.baseboard_fab2(sch_1):page51_i43@mstr_sconn.sconn288_h44441004(chips)!SCONN288_H44441004_PIP-SCONN,HA!!!F154!VSS(21)!!!!
S!GND!J4A2!200!@baseboard_fab2_lib.baseboard_fab2(sch_1):page51_i43@mstr_sconn.sconn288_h44441004(chips)!SCONN288_H44441004_PIP-SCONN,HA!!!F154!VSS(22)!!!!
S!GND!J4A2!198!@baseboard_fab2_lib.baseboard_fab2(sch_1):page51_i43@mstr_sconn.sconn288_h44441004(chips)!SCONN288_H44441004_PIP-SCONN,HA!!!F154!VSS(23)!!!!
S!GND!J4A2!195!@baseboard_fab2_lib.baseboard_fab2(sch_1):page51_i43@mstr_sconn.sconn288_h44441004(chips)!SCONN288_H44441004_PIP-SCONN,HA!!!F154!VSS(24)!!!!
S!GND!J4A2!193!@baseboard_fab2_lib.baseboard_fab2(sch_1):page51_i43@mstr_sconn.sconn288_h44441004(chips)!SCONN288_H44441004_PIP-SCONN,HA!!!F154!VSS(25)!!!!
S!GND!J4A2!191!@baseboard_fab2_lib.baseboard_fab2(sch_1):page51_i43@mstr_sconn.sconn288_h44441004(chips)!SCONN288_H44441004_PIP-SCONN,HA!!!F154!VSS(26)!!!!
S!GND!J4A2!189!@baseboard_fab2_lib.baseboard_fab2(sch_1):page51_i43@mstr_sconn.sconn288_h44441004(chips)!SCONN288_H44441004_PIP-SCONN,HA!!!F154!VSS(27)!!!!
S!GND!J4A2!187!@baseboard_fab2_lib.baseboard_fab2(sch_1):page51_i43@mstr_sconn.sconn288_h44441004(chips)!SCONN288_H44441004_PIP-SCONN,HA!!!F154!VSS(28)!!!!
S!GND!J4A2!184!@baseboard_fab2_lib.baseboard_fab2(sch_1):page51_i43@mstr_sconn.sconn288_h44441004(chips)!SCONN288_H44441004_PIP-SCONN,HA!!!F154!VSS(29)!!!!
S!GND!J4A2!279!@baseboard_fab2_lib.baseboard_fab2(sch_1):page51_i43@mstr_sconn.sconn288_h44441004(chips)!SCONN288_H44441004_PIP-SCONN,HA!!!F154!VSS(2)!!!!
S!GND!J4A2!182!@baseboard_fab2_lib.baseboard_fab2(sch_1):page51_i43@mstr_sconn.sconn288_h44441004(chips)!SCONN288_H44441004_PIP-SCONN,HA!!!F154!VSS(30)!!!!
S!GND!J4A2!180!@baseboard_fab2_lib.baseboard_fab2(sch_1):page51_i43@mstr_sconn.sconn288_h44441004(chips)!SCONN288_H44441004_PIP-SCONN,HA!!!F154!VSS(31)!!!!
S!GND!J4A2!178!@baseboard_fab2_lib.baseboard_fab2(sch_1):page51_i43@mstr_sconn.sconn288_h44441004(chips)!SCONN288_H44441004_PIP-SCONN,HA!!!F154!VSS(32)!!!!
S!GND!J4A2!176!@baseboard_fab2_lib.baseboard_fab2(sch_1):page51_i43@mstr_sconn.sconn288_h44441004(chips)!SCONN288_H44441004_PIP-SCONN,HA!!!F154!VSS(33)!!!!
S!GND!J4A2!173!@baseboard_fab2_lib.baseboard_fab2(sch_1):page51_i43@mstr_sconn.sconn288_h44441004(chips)!SCONN288_H44441004_PIP-SCONN,HA!!!F154!VSS(34)!!!!
S!GND!J4A2!171!@baseboard_fab2_lib.baseboard_fab2(sch_1):page51_i43@mstr_sconn.sconn288_h44441004(chips)!SCONN288_H44441004_PIP-SCONN,HA!!!F154!VSS(35)!!!!
S!GND!J4A2!169!@baseboard_fab2_lib.baseboard_fab2(sch_1):page51_i43@mstr_sconn.sconn288_h44441004(chips)!SCONN288_H44441004_PIP-SCONN,HA!!!F154!VSS(36)!!!!
S!GND!J4A2!167!@baseboard_fab2_lib.baseboard_fab2(sch_1):page51_i43@mstr_sconn.sconn288_h44441004(chips)!SCONN288_H44441004_PIP-SCONN,HA!!!F154!VSS(37)!!!!
S!GND!J4A2!165!@baseboard_fab2_lib.baseboard_fab2(sch_1):page51_i43@mstr_sconn.sconn288_h44441004(chips)!SCONN288_H44441004_PIP-SCONN,HA!!!F154!VSS(38)!!!!
S!GND!J4A2!162!@baseboard_fab2_lib.baseboard_fab2(sch_1):page51_i43@mstr_sconn.sconn288_h44441004(chips)!SCONN288_H44441004_PIP-SCONN,HA!!!F154!VSS(39)!!!!
S!GND!J4A2!276!@baseboard_fab2_lib.baseboard_fab2(sch_1):page51_i43@mstr_sconn.sconn288_h44441004(chips)!SCONN288_H44441004_PIP-SCONN,HA!!!F154!VSS(3)!!!!
S!GND!J4A2!160!@baseboard_fab2_lib.baseboard_fab2(sch_1):page51_i43@mstr_sconn.sconn288_h44441004(chips)!SCONN288_H44441004_PIP-SCONN,HA!!!F154!VSS(40)!!!!
S!GND!J4A2!158!@baseboard_fab2_lib.baseboard_fab2(sch_1):page51_i43@mstr_sconn.sconn288_h44441004(chips)!SCONN288_H44441004_PIP-SCONN,HA!!!F154!VSS(41)!!!!
S!GND!J4A2!156!@baseboard_fab2_lib.baseboard_fab2(sch_1):page51_i43@mstr_sconn.sconn288_h44441004(chips)!SCONN288_H44441004_PIP-SCONN,HA!!!F154!VSS(42)!!!!
S!GND!J4A2!154!@baseboard_fab2_lib.baseboard_fab2(sch_1):page51_i43@mstr_sconn.sconn288_h44441004(chips)!SCONN288_H44441004_PIP-SCONN,HA!!!F154!VSS(43)!!!!
S!GND!J4A2!151!@baseboard_fab2_lib.baseboard_fab2(sch_1):page51_i43@mstr_sconn.sconn288_h44441004(chips)!SCONN288_H44441004_PIP-SCONN,HA!!!F154!VSS(44)!!!!
S!GND!J4A2!149!@baseboard_fab2_lib.baseboard_fab2(sch_1):page51_i43@mstr_sconn.sconn288_h44441004(chips)!SCONN288_H44441004_PIP-SCONN,HA!!!F154!VSS(45)!!!!
S!GND!J4A2!147!@baseboard_fab2_lib.baseboard_fab2(sch_1):page51_i43@mstr_sconn.sconn288_h44441004(chips)!SCONN288_H44441004_PIP-SCONN,HA!!!F154!VSS(46)!!!!
S!GND!J4A2!138!@baseboard_fab2_lib.baseboard_fab2(sch_1):page51_i43@mstr_sconn.sconn288_h44441004(chips)!SCONN288_H44441004_PIP-SCONN,HA!!!F154!VSS(47)!!!!
S!GND!J4A2!136!@baseboard_fab2_lib.baseboard_fab2(sch_1):page51_i43@mstr_sconn.sconn288_h44441004(chips)!SCONN288_H44441004_PIP-SCONN,HA!!!F154!VSS(48)!!!!
S!GND!J4A2!134!@baseboard_fab2_lib.baseboard_fab2(sch_1):page51_i43@mstr_sconn.sconn288_h44441004(chips)!SCONN288_H44441004_PIP-SCONN,HA!!!F154!VSS(49)!!!!
S!GND!J4A2!274!@baseboard_fab2_lib.baseboard_fab2(sch_1):page51_i43@mstr_sconn.sconn288_h44441004(chips)!SCONN288_H44441004_PIP-SCONN,HA!!!F154!VSS(4)!!!!
S!GND!J4A2!131!@baseboard_fab2_lib.baseboard_fab2(sch_1):page51_i43@mstr_sconn.sconn288_h44441004(chips)!SCONN288_H44441004_PIP-SCONN,HA!!!F154!VSS(50)!!!!
S!GND!J4A2!129!@baseboard_fab2_lib.baseboard_fab2(sch_1):page51_i43@mstr_sconn.sconn288_h44441004(chips)!SCONN288_H44441004_PIP-SCONN,HA!!!F154!VSS(51)!!!!
S!GND!J4A2!127!@baseboard_fab2_lib.baseboard_fab2(sch_1):page51_i43@mstr_sconn.sconn288_h44441004(chips)!SCONN288_H44441004_PIP-SCONN,HA!!!F154!VSS(52)!!!!
S!GND!J4A2!125!@baseboard_fab2_lib.baseboard_fab2(sch_1):page51_i43@mstr_sconn.sconn288_h44441004(chips)!SCONN288_H44441004_PIP-SCONN,HA!!!F154!VSS(53)!!!!
S!GND!J4A2!123!@baseboard_fab2_lib.baseboard_fab2(sch_1):page51_i43@mstr_sconn.sconn288_h44441004(chips)!SCONN288_H44441004_PIP-SCONN,HA!!!F154!VSS(54)!!!!
S!GND!J4A2!120!@baseboard_fab2_lib.baseboard_fab2(sch_1):page51_i43@mstr_sconn.sconn288_h44441004(chips)!SCONN288_H44441004_PIP-SCONN,HA!!!F154!VSS(55)!!!!
S!GND!J4A2!118!@baseboard_fab2_lib.baseboard_fab2(sch_1):page51_i43@mstr_sconn.sconn288_h44441004(chips)!SCONN288_H44441004_PIP-SCONN,HA!!!F154!VSS(56)!!!!
S!GND!J4A2!116!@baseboard_fab2_lib.baseboard_fab2(sch_1):page51_i43@mstr_sconn.sconn288_h44441004(chips)!SCONN288_H44441004_PIP-SCONN,HA!!!F154!VSS(57)!!!!
S!GND!J4A2!114!@baseboard_fab2_lib.baseboard_fab2(sch_1):page51_i43@mstr_sconn.sconn288_h44441004(chips)!SCONN288_H44441004_PIP-SCONN,HA!!!F154!VSS(58)!!!!
S!GND!J4A2!112!@baseboard_fab2_lib.baseboard_fab2(sch_1):page51_i43@mstr_sconn.sconn288_h44441004(chips)!SCONN288_H44441004_PIP-SCONN,HA!!!F154!VSS(59)!!!!
S!GND!J4A2!272!@baseboard_fab2_lib.baseboard_fab2(sch_1):page51_i43@mstr_sconn.sconn288_h44441004(chips)!SCONN288_H44441004_PIP-SCONN,HA!!!F154!VSS(5)!!!!
S!GND!J4A2!109!@baseboard_fab2_lib.baseboard_fab2(sch_1):page51_i43@mstr_sconn.sconn288_h44441004(chips)!SCONN288_H44441004_PIP-SCONN,HA!!!F154!VSS(60)!!!!
S!GND!J4A2!107!@baseboard_fab2_lib.baseboard_fab2(sch_1):page51_i43@mstr_sconn.sconn288_h44441004(chips)!SCONN288_H44441004_PIP-SCONN,HA!!!F154!VSS(61)!!!!
S!GND!J4A2!105!@baseboard_fab2_lib.baseboard_fab2(sch_1):page51_i43@mstr_sconn.sconn288_h44441004(chips)!SCONN288_H44441004_PIP-SCONN,HA!!!F154!VSS(62)!!!!
S!GND!J4A2!103!@baseboard_fab2_lib.baseboard_fab2(sch_1):page51_i43@mstr_sconn.sconn288_h44441004(chips)!SCONN288_H44441004_PIP-SCONN,HA!!!F154!VSS(63)!!!!
S!GND!J4A2!101!@baseboard_fab2_lib.baseboard_fab2(sch_1):page51_i43@mstr_sconn.sconn288_h44441004(chips)!SCONN288_H44441004_PIP-SCONN,HA!!!F154!VSS(64)!!!!
S!GND!J4A2!98!@baseboard_fab2_lib.baseboard_fab2(sch_1):page51_i43@mstr_sconn.sconn288_h44441004(chips)!SCONN288_H44441004_PIP-SCONN,HA!!!F154!VSS(65)!!!!
S!GND!J4A2!96!@baseboard_fab2_lib.baseboard_fab2(sch_1):page51_i43@mstr_sconn.sconn288_h44441004(chips)!SCONN288_H44441004_PIP-SCONN,HA!!!F154!VSS(66)!!!!
S!GND!J4A2!94!@baseboard_fab2_lib.baseboard_fab2(sch_1):page51_i43@mstr_sconn.sconn288_h44441004(chips)!SCONN288_H44441004_PIP-SCONN,HA!!!F154!VSS(67)!!!!
S!GND!J4A2!57!@baseboard_fab2_lib.baseboard_fab2(sch_1):page51_i43@mstr_sconn.sconn288_h44441004(chips)!SCONN288_H44441004_PIP-SCONN,HA!!!F154!VSS(68)!!!!
S!GND!J4A2!55!@baseboard_fab2_lib.baseboard_fab2(sch_1):page51_i43@mstr_sconn.sconn288_h44441004(chips)!SCONN288_H44441004_PIP-SCONN,HA!!!F154!VSS(69)!!!!
S!GND!J4A2!270!@baseboard_fab2_lib.baseboard_fab2(sch_1):page51_i43@mstr_sconn.sconn288_h44441004(chips)!SCONN288_H44441004_PIP-SCONN,HA!!!F154!VSS(6)!!!!
S!GND!J4A2!53!@baseboard_fab2_lib.baseboard_fab2(sch_1):page51_i43@mstr_sconn.sconn288_h44441004(chips)!SCONN288_H44441004_PIP-SCONN,HA!!!F154!VSS(70)!!!!
S!GND!J4A2!50!@baseboard_fab2_lib.baseboard_fab2(sch_1):page51_i43@mstr_sconn.sconn288_h44441004(chips)!SCONN288_H44441004_PIP-SCONN,HA!!!F154!VSS(71)!!!!
S!GND!J4A2!48!@baseboard_fab2_lib.baseboard_fab2(sch_1):page51_i43@mstr_sconn.sconn288_h44441004(chips)!SCONN288_H44441004_PIP-SCONN,HA!!!F154!VSS(72)!!!!
S!GND!J4A2!46!@baseboard_fab2_lib.baseboard_fab2(sch_1):page51_i43@mstr_sconn.sconn288_h44441004(chips)!SCONN288_H44441004_PIP-SCONN,HA!!!F154!VSS(73)!!!!
S!GND!J4A2!44!@baseboard_fab2_lib.baseboard_fab2(sch_1):page51_i43@mstr_sconn.sconn288_h44441004(chips)!SCONN288_H44441004_PIP-SCONN,HA!!!F154!VSS(74)!!!!
S!GND!J4A2!42!@baseboard_fab2_lib.baseboard_fab2(sch_1):page51_i43@mstr_sconn.sconn288_h44441004(chips)!SCONN288_H44441004_PIP-SCONN,HA!!!F154!VSS(75)!!!!
S!GND!J4A2!39!@baseboard_fab2_lib.baseboard_fab2(sch_1):page51_i43@mstr_sconn.sconn288_h44441004(chips)!SCONN288_H44441004_PIP-SCONN,HA!!!F154!VSS(76)!!!!
S!GND!J4A2!37!@baseboard_fab2_lib.baseboard_fab2(sch_1):page51_i43@mstr_sconn.sconn288_h44441004(chips)!SCONN288_H44441004_PIP-SCONN,HA!!!F154!VSS(77)!!!!
S!GND!J4A2!35!@baseboard_fab2_lib.baseboard_fab2(sch_1):page51_i43@mstr_sconn.sconn288_h44441004(chips)!SCONN288_H44441004_PIP-SCONN,HA!!!F154!VSS(78)!!!!
S!GND!J4A2!33!@baseboard_fab2_lib.baseboard_fab2(sch_1):page51_i43@mstr_sconn.sconn288_h44441004(chips)!SCONN288_H44441004_PIP-SCONN,HA!!!F154!VSS(79)!!!!
S!GND!J4A2!268!@baseboard_fab2_lib.baseboard_fab2(sch_1):page51_i43@mstr_sconn.sconn288_h44441004(chips)!SCONN288_H44441004_PIP-SCONN,HA!!!F154!VSS(7)!!!!
S!GND!J4A2!31!@baseboard_fab2_lib.baseboard_fab2(sch_1):page51_i43@mstr_sconn.sconn288_h44441004(chips)!SCONN288_H44441004_PIP-SCONN,HA!!!F154!VSS(80)!!!!
S!GND!J4A2!28!@baseboard_fab2_lib.baseboard_fab2(sch_1):page51_i43@mstr_sconn.sconn288_h44441004(chips)!SCONN288_H44441004_PIP-SCONN,HA!!!F154!VSS(81)!!!!
S!GND!J4A2!26!@baseboard_fab2_lib.baseboard_fab2(sch_1):page51_i43@mstr_sconn.sconn288_h44441004(chips)!SCONN288_H44441004_PIP-SCONN,HA!!!F154!VSS(82)!!!!
S!GND!J4A2!24!@baseboard_fab2_lib.baseboard_fab2(sch_1):page51_i43@mstr_sconn.sconn288_h44441004(chips)!SCONN288_H44441004_PIP-SCONN,HA!!!F154!VSS(83)!!!!
S!GND!J4A2!22!@baseboard_fab2_lib.baseboard_fab2(sch_1):page51_i43@mstr_sconn.sconn288_h44441004(chips)!SCONN288_H44441004_PIP-SCONN,HA!!!F154!VSS(84)!!!!
S!GND!J4A2!20!@baseboard_fab2_lib.baseboard_fab2(sch_1):page51_i43@mstr_sconn.sconn288_h44441004(chips)!SCONN288_H44441004_PIP-SCONN,HA!!!F154!VSS(85)!!!!
S!GND!J4A2!17!@baseboard_fab2_lib.baseboard_fab2(sch_1):page51_i43@mstr_sconn.sconn288_h44441004(chips)!SCONN288_H44441004_PIP-SCONN,HA!!!F154!VSS(86)!!!!
S!GND!J4A2!15!@baseboard_fab2_lib.baseboard_fab2(sch_1):page51_i43@mstr_sconn.sconn288_h44441004(chips)!SCONN288_H44441004_PIP-SCONN,HA!!!F154!VSS(87)!!!!
S!GND!J4A2!13!@baseboard_fab2_lib.baseboard_fab2(sch_1):page51_i43@mstr_sconn.sconn288_h44441004(chips)!SCONN288_H44441004_PIP-SCONN,HA!!!F154!VSS(88)!!!!
S!GND!J4A2!11!@baseboard_fab2_lib.baseboard_fab2(sch_1):page51_i43@mstr_sconn.sconn288_h44441004(chips)!SCONN288_H44441004_PIP-SCONN,HA!!!F154!VSS(89)!!!!
S!GND!J4A2!265!@baseboard_fab2_lib.baseboard_fab2(sch_1):page51_i43@mstr_sconn.sconn288_h44441004(chips)!SCONN288_H44441004_PIP-SCONN,HA!!!F154!VSS(8)!!!!
S!GND!J4A2!9!@baseboard_fab2_lib.baseboard_fab2(sch_1):page51_i43@mstr_sconn.sconn288_h44441004(chips)!SCONN288_H44441004_PIP-SCONN,HA!!!F154!VSS(90)!!!!
S!GND!J4A2!6!@baseboard_fab2_lib.baseboard_fab2(sch_1):page51_i43@mstr_sconn.sconn288_h44441004(chips)!SCONN288_H44441004_PIP-SCONN,HA!!!F154!VSS(91)!!!!
S!GND!J4A2!4!@baseboard_fab2_lib.baseboard_fab2(sch_1):page51_i43@mstr_sconn.sconn288_h44441004(chips)!SCONN288_H44441004_PIP-SCONN,HA!!!F154!VSS(92)!!!!
S!GND!J4A2!2!@baseboard_fab2_lib.baseboard_fab2(sch_1):page51_i43@mstr_sconn.sconn288_h44441004(chips)!SCONN288_H44441004_PIP-SCONN,HA!!!F154!VSS(93)!!!!
S!GND!J4A2!263!@baseboard_fab2_lib.baseboard_fab2(sch_1):page51_i43@mstr_sconn.sconn288_h44441004(chips)!SCONN288_H44441004_PIP-SCONN,HA!!!F154!VSS(9)!!!!
S!P12V_NVDIMM_DEF!J4A2!145!@baseboard_fab2_lib.baseboard_fab2(sch_1):page51_i167@mstr_sconn.sconn288_h44441004(chips)!SCONN288_H44441004_PIP-SCONN,HA!!!F153!\12v\(0)!!!!
S!P12V_NVDIMM_DEF!J4A2!1!@baseboard_fab2_lib.baseboard_fab2(sch_1):page51_i167@mstr_sconn.sconn288_h44441004(chips)!SCONN288_H44441004_PIP-SCONN,HA!!!F153!\12v\(1)!!!!
S!PVDDQ_DEF!J4A2!236!@baseboard_fab2_lib.baseboard_fab2(sch_1):page51_i167@mstr_sconn.sconn288_h44441004(chips)!SCONN288_H44441004_PIP-SCONN,HA!!!F153!VDD(0)!!!!
S!PVDDQ_DEF!J4A2!209!@baseboard_fab2_lib.baseboard_fab2(sch_1):page51_i167@mstr_sconn.sconn288_h44441004(chips)!SCONN288_H44441004_PIP-SCONN,HA!!!F153!VDD(10)!!!!
S!PVDDQ_DEF!J4A2!206!@baseboard_fab2_lib.baseboard_fab2(sch_1):page51_i167@mstr_sconn.sconn288_h44441004(chips)!SCONN288_H44441004_PIP-SCONN,HA!!!F153!VDD(11)!!!!
S!PVDDQ_DEF!J4A2!204!@baseboard_fab2_lib.baseboard_fab2(sch_1):page51_i167@mstr_sconn.sconn288_h44441004(chips)!SCONN288_H44441004_PIP-SCONN,HA!!!F153!VDD(12)!!!!
S!PVDDQ_DEF!J4A2!92!@baseboard_fab2_lib.baseboard_fab2(sch_1):page51_i167@mstr_sconn.sconn288_h44441004(chips)!SCONN288_H44441004_PIP-SCONN,HA!!!F153!VDD(13)!!!!
S!PVDDQ_DEF!J4A2!90!@baseboard_fab2_lib.baseboard_fab2(sch_1):page51_i167@mstr_sconn.sconn288_h44441004(chips)!SCONN288_H44441004_PIP-SCONN,HA!!!F153!VDD(14)!!!!
S!PVDDQ_DEF!J4A2!88!@baseboard_fab2_lib.baseboard_fab2(sch_1):page51_i167@mstr_sconn.sconn288_h44441004(chips)!SCONN288_H44441004_PIP-SCONN,HA!!!F153!VDD(15)!!!!
S!PVDDQ_DEF!J4A2!85!@baseboard_fab2_lib.baseboard_fab2(sch_1):page51_i167@mstr_sconn.sconn288_h44441004(chips)!SCONN288_H44441004_PIP-SCONN,HA!!!F153!VDD(16)!!!!
S!PVDDQ_DEF!J4A2!83!@baseboard_fab2_lib.baseboard_fab2(sch_1):page51_i167@mstr_sconn.sconn288_h44441004(chips)!SCONN288_H44441004_PIP-SCONN,HA!!!F153!VDD(17)!!!!
S!PVDDQ_DEF!J4A2!80!@baseboard_fab2_lib.baseboard_fab2(sch_1):page51_i167@mstr_sconn.sconn288_h44441004(chips)!SCONN288_H44441004_PIP-SCONN,HA!!!F153!VDD(18)!!!!
S!PVDDQ_DEF!J4A2!76!@baseboard_fab2_lib.baseboard_fab2(sch_1):page51_i167@mstr_sconn.sconn288_h44441004(chips)!SCONN288_H44441004_PIP-SCONN,HA!!!F153!VDD(19)!!!!
S!PVDDQ_DEF!J4A2!233!@baseboard_fab2_lib.baseboard_fab2(sch_1):page51_i167@mstr_sconn.sconn288_h44441004(chips)!SCONN288_H44441004_PIP-SCONN,HA!!!F153!VDD(1)!!!!
S!PVDDQ_DEF!J4A2!73!@baseboard_fab2_lib.baseboard_fab2(sch_1):page51_i167@mstr_sconn.sconn288_h44441004(chips)!SCONN288_H44441004_PIP-SCONN,HA!!!F153!VDD(20)!!!!
S!PVDDQ_DEF!J4A2!70!@baseboard_fab2_lib.baseboard_fab2(sch_1):page51_i167@mstr_sconn.sconn288_h44441004(chips)!SCONN288_H44441004_PIP-SCONN,HA!!!F153!VDD(21)!!!!
S!PVDDQ_DEF!J4A2!67!@baseboard_fab2_lib.baseboard_fab2(sch_1):page51_i167@mstr_sconn.sconn288_h44441004(chips)!SCONN288_H44441004_PIP-SCONN,HA!!!F153!VDD(22)!!!!
S!PVDDQ_DEF!J4A2!64!@baseboard_fab2_lib.baseboard_fab2(sch_1):page51_i167@mstr_sconn.sconn288_h44441004(chips)!SCONN288_H44441004_PIP-SCONN,HA!!!F153!VDD(23)!!!!
S!PVDDQ_DEF!J4A2!61!@baseboard_fab2_lib.baseboard_fab2(sch_1):page51_i167@mstr_sconn.sconn288_h44441004(chips)!SCONN288_H44441004_PIP-SCONN,HA!!!F153!VDD(24)!!!!
S!PVDDQ_DEF!J4A2!59!@baseboard_fab2_lib.baseboard_fab2(sch_1):page51_i167@mstr_sconn.sconn288_h44441004(chips)!SCONN288_H44441004_PIP-SCONN,HA!!!F153!VDD(25)!!!!
S!PVDDQ_DEF!J4A2!231!@baseboard_fab2_lib.baseboard_fab2(sch_1):page51_i167@mstr_sconn.sconn288_h44441004(chips)!SCONN288_H44441004_PIP-SCONN,HA!!!F153!VDD(2)!!!!
S!PVDDQ_DEF!J4A2!229!@baseboard_fab2_lib.baseboard_fab2(sch_1):page51_i167@mstr_sconn.sconn288_h44441004(chips)!SCONN288_H44441004_PIP-SCONN,HA!!!F153!VDD(3)!!!!
S!PVDDQ_DEF!J4A2!226!@baseboard_fab2_lib.baseboard_fab2(sch_1):page51_i167@mstr_sconn.sconn288_h44441004(chips)!SCONN288_H44441004_PIP-SCONN,HA!!!F153!VDD(4)!!!!
S!PVDDQ_DEF!J4A2!223!@baseboard_fab2_lib.baseboard_fab2(sch_1):page51_i167@mstr_sconn.sconn288_h44441004(chips)!SCONN288_H44441004_PIP-SCONN,HA!!!F153!VDD(5)!!!!
S!PVDDQ_DEF!J4A2!220!@baseboard_fab2_lib.baseboard_fab2(sch_1):page51_i167@mstr_sconn.sconn288_h44441004(chips)!SCONN288_H44441004_PIP-SCONN,HA!!!F153!VDD(6)!!!!
S!PVDDQ_DEF!J4A2!217!@baseboard_fab2_lib.baseboard_fab2(sch_1):page51_i167@mstr_sconn.sconn288_h44441004(chips)!SCONN288_H44441004_PIP-SCONN,HA!!!F153!VDD(7)!!!!
S!PVDDQ_DEF!J4A2!215!@baseboard_fab2_lib.baseboard_fab2(sch_1):page51_i167@mstr_sconn.sconn288_h44441004(chips)!SCONN288_H44441004_PIP-SCONN,HA!!!F153!VDD(8)!!!!
S!PVDDQ_DEF!J4A2!212!@baseboard_fab2_lib.baseboard_fab2(sch_1):page51_i167@mstr_sconn.sconn288_h44441004(chips)!SCONN288_H44441004_PIP-SCONN,HA!!!F153!VDD(9)!!!!
S!PVPP_DEF!J4A2!287!@baseboard_fab2_lib.baseboard_fab2(sch_1):page51_i167@mstr_sconn.sconn288_h44441004(chips)!SCONN288_H44441004_PIP-SCONN,HA!!!F153!VPP(0)!!!!
S!PVPP_DEF!J4A2!286!@baseboard_fab2_lib.baseboard_fab2(sch_1):page51_i167@mstr_sconn.sconn288_h44441004(chips)!SCONN288_H44441004_PIP-SCONN,HA!!!F153!VPP(1)!!!!
S!PVPP_DEF!J4A2!288!@baseboard_fab2_lib.baseboard_fab2(sch_1):page51_i167@mstr_sconn.sconn288_h44441004(chips)!SCONN288_H44441004_PIP-SCONN,HA!!!F153!VPP(2)!!!!
S!PVPP_DEF!J4A2!143!@baseboard_fab2_lib.baseboard_fab2(sch_1):page51_i167@mstr_sconn.sconn288_h44441004(chips)!SCONN288_H44441004_PIP-SCONN,HA!!!F153!VPP(3)!!!!
S!PVPP_DEF!J4A2!142!@baseboard_fab2_lib.baseboard_fab2(sch_1):page51_i167@mstr_sconn.sconn288_h44441004(chips)!SCONN288_H44441004_PIP-SCONN,HA!!!F153!VPP(4)!!!!
S!PVTT_DEF!J4A2!221!@baseboard_fab2_lib.baseboard_fab2(sch_1):page51_i167@mstr_sconn.sconn288_h44441004(chips)!SCONN288_H44441004_PIP-SCONN,HA!!!F153!VTT(0)!!!!
S!PVTT_DEF!J4A2!77!@baseboard_fab2_lib.baseboard_fab2(sch_1):page51_i167@mstr_sconn.sconn288_h44441004(chips)!SCONN288_H44441004_PIP-SCONN,HA!!!F153!VTT(1)!!!!
S!M_F_MA<0>!J4A1!79!@baseboard_fab2_lib.baseboard_fab2(sch_1):page53_i111@mstr_sconn.sconn288_h44441004(chips)!SCONN288_H44441004_PIP-SCONN,HA!!!F160!A0!!!!
S!M_F_MA<1>!J4A1!72!@baseboard_fab2_lib.baseboard_fab2(sch_1):page53_i111@mstr_sconn.sconn288_h44441004(chips)!SCONN288_H44441004_PIP-SCONN,HA!!!F160!A1!!!!
S!M_F_MA<10>!J4A1!225!@baseboard_fab2_lib.baseboard_fab2(sch_1):page53_i111@mstr_sconn.sconn288_h44441004(chips)!SCONN288_H44441004_PIP-SCONN,HA!!!F160!A10!!!!
S!M_F_MA<11>!J4A1!210!@baseboard_fab2_lib.baseboard_fab2(sch_1):page53_i111@mstr_sconn.sconn288_h44441004(chips)!SCONN288_H44441004_PIP-SCONN,HA!!!F160!A11!!!!
S!M_F_MA<12>!J4A1!65!@baseboard_fab2_lib.baseboard_fab2(sch_1):page53_i111@mstr_sconn.sconn288_h44441004(chips)!SCONN288_H44441004_PIP-SCONN,HA!!!F160!A12!!!!
S!M_F_MA<13>!J4A1!232!@baseboard_fab2_lib.baseboard_fab2(sch_1):page53_i111@mstr_sconn.sconn288_h44441004(chips)!SCONN288_H44441004_PIP-SCONN,HA!!!F160!A13!!!!
S!M_F_MA<14>!J4A1!228!@baseboard_fab2_lib.baseboard_fab2(sch_1):page53_i111@mstr_sconn.sconn288_h44441004(chips)!SCONN288_H44441004_PIP-SCONN,HA!!!F160!A14_WE_N!!!!
S!M_F_MA<15>!J4A1!86!@baseboard_fab2_lib.baseboard_fab2(sch_1):page53_i111@mstr_sconn.sconn288_h44441004(chips)!SCONN288_H44441004_PIP-SCONN,HA!!!F160!A15_CAS_N!!!!
S!M_F_MA<16>!J4A1!82!@baseboard_fab2_lib.baseboard_fab2(sch_1):page53_i111@mstr_sconn.sconn288_h44441004(chips)!SCONN288_H44441004_PIP-SCONN,HA!!!F160!A16_RAS_N!!!!
S!M_F_MA<17>!J4A1!234!@baseboard_fab2_lib.baseboard_fab2(sch_1):page53_i111@mstr_sconn.sconn288_h44441004(chips)!SCONN288_H44441004_PIP-SCONN,HA!!!F160!A17!!!!
S!M_F_MA<2>!J4A1!216!@baseboard_fab2_lib.baseboard_fab2(sch_1):page53_i111@mstr_sconn.sconn288_h44441004(chips)!SCONN288_H44441004_PIP-SCONN,HA!!!F160!A2!!!!
S!M_F_MA<3>!J4A1!71!@baseboard_fab2_lib.baseboard_fab2(sch_1):page53_i111@mstr_sconn.sconn288_h44441004(chips)!SCONN288_H44441004_PIP-SCONN,HA!!!F160!A3!!!!
S!M_F_MA<4>!J4A1!214!@baseboard_fab2_lib.baseboard_fab2(sch_1):page53_i111@mstr_sconn.sconn288_h44441004(chips)!SCONN288_H44441004_PIP-SCONN,HA!!!F160!A4!!!!
S!M_F_MA<5>!J4A1!213!@baseboard_fab2_lib.baseboard_fab2(sch_1):page53_i111@mstr_sconn.sconn288_h44441004(chips)!SCONN288_H44441004_PIP-SCONN,HA!!!F160!A5!!!!
S!M_F_MA<6>!J4A1!69!@baseboard_fab2_lib.baseboard_fab2(sch_1):page53_i111@mstr_sconn.sconn288_h44441004(chips)!SCONN288_H44441004_PIP-SCONN,HA!!!F160!A6!!!!
S!M_F_MA<7>!J4A1!211!@baseboard_fab2_lib.baseboard_fab2(sch_1):page53_i111@mstr_sconn.sconn288_h44441004(chips)!SCONN288_H44441004_PIP-SCONN,HA!!!F160!A7!!!!
S!M_F_MA<8>!J4A1!68!@baseboard_fab2_lib.baseboard_fab2(sch_1):page53_i111@mstr_sconn.sconn288_h44441004(chips)!SCONN288_H44441004_PIP-SCONN,HA!!!F160!A8!!!!
S!M_F_MA<9>!J4A1!66!@baseboard_fab2_lib.baseboard_fab2(sch_1):page53_i111@mstr_sconn.sconn288_h44441004(chips)!SCONN288_H44441004_PIP-SCONN,HA!!!F160!A9!!!!
S!M_F_ACT_N!J4A1!62!@baseboard_fab2_lib.baseboard_fab2(sch_1):page53_i111@mstr_sconn.sconn288_h44441004(chips)!SCONN288_H44441004_PIP-SCONN,HA!!!F160!ACT_N!!!!
S!M_F_ALERT_N!J4A1!208!@baseboard_fab2_lib.baseboard_fab2(sch_1):page53_i111@mstr_sconn.sconn288_h44441004(chips)!SCONN288_H44441004_PIP-SCONN,HA!!!F160!ALERT_N!!!!
S!M_F_BA<0>!J4A1!81!@baseboard_fab2_lib.baseboard_fab2(sch_1):page53_i111@mstr_sconn.sconn288_h44441004(chips)!SCONN288_H44441004_PIP-SCONN,HA!!!F160!BA(0)!!!!
S!M_F_BA<1>!J4A1!224!@baseboard_fab2_lib.baseboard_fab2(sch_1):page53_i111@mstr_sconn.sconn288_h44441004(chips)!SCONN288_H44441004_PIP-SCONN,HA!!!F160!BA(1)!!!!
S!M_F_BG<0>!J4A1!63!@baseboard_fab2_lib.baseboard_fab2(sch_1):page53_i111@mstr_sconn.sconn288_h44441004(chips)!SCONN288_H44441004_PIP-SCONN,HA!!!F160!BG(0)!!!!
S!M_F_BG<1>!J4A1!207!@baseboard_fab2_lib.baseboard_fab2(sch_1):page53_i111@mstr_sconn.sconn288_h44441004(chips)!SCONN288_H44441004_PIP-SCONN,HA!!!F160!BG(1)!!!!
S!M_F_C<2>!J4A1!235!@baseboard_fab2_lib.baseboard_fab2(sch_1):page53_i111@mstr_sconn.sconn288_h44441004(chips)!SCONN288_H44441004_PIP-SCONN,HA!!!F160!C(2)!!!!
S!M_F_ECC<1>!J4A1!49!@baseboard_fab2_lib.baseboard_fab2(sch_1):page53_i111@mstr_sconn.sconn288_h44441004(chips)!SCONN288_H44441004_PIP-SCONN,HA!!!F160!CB(0)!!!!
S!M_F_ECC<0>!J4A1!194!@baseboard_fab2_lib.baseboard_fab2(sch_1):page53_i111@mstr_sconn.sconn288_h44441004(chips)!SCONN288_H44441004_PIP-SCONN,HA!!!F160!CB(1)!!!!
S!M_F_ECC<3>!J4A1!56!@baseboard_fab2_lib.baseboard_fab2(sch_1):page53_i111@mstr_sconn.sconn288_h44441004(chips)!SCONN288_H44441004_PIP-SCONN,HA!!!F160!CB(2)!!!!
S!M_F_ECC<2>!J4A1!201!@baseboard_fab2_lib.baseboard_fab2(sch_1):page53_i111@mstr_sconn.sconn288_h44441004(chips)!SCONN288_H44441004_PIP-SCONN,HA!!!F160!CB(3)!!!!
S!M_F_ECC<5>!J4A1!47!@baseboard_fab2_lib.baseboard_fab2(sch_1):page53_i111@mstr_sconn.sconn288_h44441004(chips)!SCONN288_H44441004_PIP-SCONN,HA!!!F160!CB(4)!!!!
S!M_F_ECC<4>!J4A1!192!@baseboard_fab2_lib.baseboard_fab2(sch_1):page53_i111@mstr_sconn.sconn288_h44441004(chips)!SCONN288_H44441004_PIP-SCONN,HA!!!F160!CB(5)!!!!
S!M_F_ECC<7>!J4A1!54!@baseboard_fab2_lib.baseboard_fab2(sch_1):page53_i111@mstr_sconn.sconn288_h44441004(chips)!SCONN288_H44441004_PIP-SCONN,HA!!!F160!CB(6)!!!!
S!M_F_ECC<6>!J4A1!199!@baseboard_fab2_lib.baseboard_fab2(sch_1):page53_i111@mstr_sconn.sconn288_h44441004(chips)!SCONN288_H44441004_PIP-SCONN,HA!!!F160!CB(7)!!!!
S!M_F_CLK_DN<0>!J4A1!75!@baseboard_fab2_lib.baseboard_fab2(sch_1):page53_i111@mstr_sconn.sconn288_h44441004(chips)!SCONN288_H44441004_PIP-SCONN,HA!!!F160!CK0N!!!!
S!M_F_CLK_DP<0>!J4A1!74!@baseboard_fab2_lib.baseboard_fab2(sch_1):page53_i111@mstr_sconn.sconn288_h44441004(chips)!SCONN288_H44441004_PIP-SCONN,HA!!!F160!CK0P!!!!
S!M_F_CLK_DN<1>!J4A1!219!@baseboard_fab2_lib.baseboard_fab2(sch_1):page53_i111@mstr_sconn.sconn288_h44441004(chips)!SCONN288_H44441004_PIP-SCONN,HA!!!F160!CK1N!!!!
S!M_F_CLK_DP<1>!J4A1!218!@baseboard_fab2_lib.baseboard_fab2(sch_1):page53_i111@mstr_sconn.sconn288_h44441004(chips)!SCONN288_H44441004_PIP-SCONN,HA!!!F160!CK1P!!!!
S!M_F_CKE<0>!J4A1!60!@baseboard_fab2_lib.baseboard_fab2(sch_1):page53_i111@mstr_sconn.sconn288_h44441004(chips)!SCONN288_H44441004_PIP-SCONN,HA!!!F160!CKE(0)!!!!
S!M_F_CKE<1>!J4A1!203!@baseboard_fab2_lib.baseboard_fab2(sch_1):page53_i111@mstr_sconn.sconn288_h44441004(chips)!SCONN288_H44441004_PIP-SCONN,HA!!!F160!CKE(1)!!!!
S!M_F_DQ<1>!J4A1!5!@baseboard_fab2_lib.baseboard_fab2(sch_1):page53_i111@mstr_sconn.sconn288_h44441004(chips)!SCONN288_H44441004_PIP-SCONN,HA!!!F160!DQ(0)!!!!
S!M_F_DQ<11>!J4A1!23!@baseboard_fab2_lib.baseboard_fab2(sch_1):page53_i111@mstr_sconn.sconn288_h44441004(chips)!SCONN288_H44441004_PIP-SCONN,HA!!!F160!DQ(10)!!!!
S!M_F_DQ<10>!J4A1!168!@baseboard_fab2_lib.baseboard_fab2(sch_1):page53_i111@mstr_sconn.sconn288_h44441004(chips)!SCONN288_H44441004_PIP-SCONN,HA!!!F160!DQ(11)!!!!
S!M_F_DQ<13>!J4A1!14!@baseboard_fab2_lib.baseboard_fab2(sch_1):page53_i111@mstr_sconn.sconn288_h44441004(chips)!SCONN288_H44441004_PIP-SCONN,HA!!!F160!DQ(12)!!!!
S!M_F_DQ<12>!J4A1!159!@baseboard_fab2_lib.baseboard_fab2(sch_1):page53_i111@mstr_sconn.sconn288_h44441004(chips)!SCONN288_H44441004_PIP-SCONN,HA!!!F160!DQ(13)!!!!
S!M_F_DQ<15>!J4A1!21!@baseboard_fab2_lib.baseboard_fab2(sch_1):page53_i111@mstr_sconn.sconn288_h44441004(chips)!SCONN288_H44441004_PIP-SCONN,HA!!!F160!DQ(14)!!!!
S!M_F_DQ<14>!J4A1!166!@baseboard_fab2_lib.baseboard_fab2(sch_1):page53_i111@mstr_sconn.sconn288_h44441004(chips)!SCONN288_H44441004_PIP-SCONN,HA!!!F160!DQ(15)!!!!
S!M_F_DQ<17>!J4A1!27!@baseboard_fab2_lib.baseboard_fab2(sch_1):page53_i111@mstr_sconn.sconn288_h44441004(chips)!SCONN288_H44441004_PIP-SCONN,HA!!!F160!DQ(16)!!!!
S!M_F_DQ<16>!J4A1!172!@baseboard_fab2_lib.baseboard_fab2(sch_1):page53_i111@mstr_sconn.sconn288_h44441004(chips)!SCONN288_H44441004_PIP-SCONN,HA!!!F160!DQ(17)!!!!
S!M_F_DQ<19>!J4A1!34!@baseboard_fab2_lib.baseboard_fab2(sch_1):page53_i111@mstr_sconn.sconn288_h44441004(chips)!SCONN288_H44441004_PIP-SCONN,HA!!!F160!DQ(18)!!!!
S!M_F_DQ<18>!J4A1!179!@baseboard_fab2_lib.baseboard_fab2(sch_1):page53_i111@mstr_sconn.sconn288_h44441004(chips)!SCONN288_H44441004_PIP-SCONN,HA!!!F160!DQ(19)!!!!
S!M_F_DQ<0>!J4A1!150!@baseboard_fab2_lib.baseboard_fab2(sch_1):page53_i111@mstr_sconn.sconn288_h44441004(chips)!SCONN288_H44441004_PIP-SCONN,HA!!!F160!DQ(1)!!!!
S!M_F_DQ<21>!J4A1!25!@baseboard_fab2_lib.baseboard_fab2(sch_1):page53_i111@mstr_sconn.sconn288_h44441004(chips)!SCONN288_H44441004_PIP-SCONN,HA!!!F160!DQ(20)!!!!
S!M_F_DQ<20>!J4A1!170!@baseboard_fab2_lib.baseboard_fab2(sch_1):page53_i111@mstr_sconn.sconn288_h44441004(chips)!SCONN288_H44441004_PIP-SCONN,HA!!!F160!DQ(21)!!!!
S!M_F_DQ<23>!J4A1!32!@baseboard_fab2_lib.baseboard_fab2(sch_1):page53_i111@mstr_sconn.sconn288_h44441004(chips)!SCONN288_H44441004_PIP-SCONN,HA!!!F160!DQ(22)!!!!
S!M_F_DQ<22>!J4A1!177!@baseboard_fab2_lib.baseboard_fab2(sch_1):page53_i111@mstr_sconn.sconn288_h44441004(chips)!SCONN288_H44441004_PIP-SCONN,HA!!!F160!DQ(23)!!!!
S!M_F_DQ<25>!J4A1!38!@baseboard_fab2_lib.baseboard_fab2(sch_1):page53_i111@mstr_sconn.sconn288_h44441004(chips)!SCONN288_H44441004_PIP-SCONN,HA!!!F160!DQ(24)!!!!
S!M_F_DQ<24>!J4A1!183!@baseboard_fab2_lib.baseboard_fab2(sch_1):page53_i111@mstr_sconn.sconn288_h44441004(chips)!SCONN288_H44441004_PIP-SCONN,HA!!!F160!DQ(25)!!!!
S!M_F_DQ<27>!J4A1!45!@baseboard_fab2_lib.baseboard_fab2(sch_1):page53_i111@mstr_sconn.sconn288_h44441004(chips)!SCONN288_H44441004_PIP-SCONN,HA!!!F160!DQ(26)!!!!
S!M_F_DQ<26>!J4A1!190!@baseboard_fab2_lib.baseboard_fab2(sch_1):page53_i111@mstr_sconn.sconn288_h44441004(chips)!SCONN288_H44441004_PIP-SCONN,HA!!!F160!DQ(27)!!!!
S!M_F_DQ<29>!J4A1!36!@baseboard_fab2_lib.baseboard_fab2(sch_1):page53_i111@mstr_sconn.sconn288_h44441004(chips)!SCONN288_H44441004_PIP-SCONN,HA!!!F160!DQ(28)!!!!
S!M_F_DQ<28>!J4A1!181!@baseboard_fab2_lib.baseboard_fab2(sch_1):page53_i111@mstr_sconn.sconn288_h44441004(chips)!SCONN288_H44441004_PIP-SCONN,HA!!!F160!DQ(29)!!!!
S!M_F_DQ<3>!J4A1!12!@baseboard_fab2_lib.baseboard_fab2(sch_1):page53_i111@mstr_sconn.sconn288_h44441004(chips)!SCONN288_H44441004_PIP-SCONN,HA!!!F160!DQ(2)!!!!
S!M_F_DQ<31>!J4A1!43!@baseboard_fab2_lib.baseboard_fab2(sch_1):page53_i111@mstr_sconn.sconn288_h44441004(chips)!SCONN288_H44441004_PIP-SCONN,HA!!!F160!DQ(30)!!!!
S!M_F_DQ<30>!J4A1!188!@baseboard_fab2_lib.baseboard_fab2(sch_1):page53_i111@mstr_sconn.sconn288_h44441004(chips)!SCONN288_H44441004_PIP-SCONN,HA!!!F160!DQ(31)!!!!
S!M_F_DQ<33>!J4A1!97!@baseboard_fab2_lib.baseboard_fab2(sch_1):page53_i111@mstr_sconn.sconn288_h44441004(chips)!SCONN288_H44441004_PIP-SCONN,HA!!!F160!DQ(32)!!!!
S!M_F_DQ<32>!J4A1!242!@baseboard_fab2_lib.baseboard_fab2(sch_1):page53_i111@mstr_sconn.sconn288_h44441004(chips)!SCONN288_H44441004_PIP-SCONN,HA!!!F160!DQ(33)!!!!
S!M_F_DQ<35>!J4A1!104!@baseboard_fab2_lib.baseboard_fab2(sch_1):page53_i111@mstr_sconn.sconn288_h44441004(chips)!SCONN288_H44441004_PIP-SCONN,HA!!!F160!DQ(34)!!!!
S!M_F_DQ<34>!J4A1!249!@baseboard_fab2_lib.baseboard_fab2(sch_1):page53_i111@mstr_sconn.sconn288_h44441004(chips)!SCONN288_H44441004_PIP-SCONN,HA!!!F160!DQ(35)!!!!
S!M_F_DQ<37>!J4A1!95!@baseboard_fab2_lib.baseboard_fab2(sch_1):page53_i111@mstr_sconn.sconn288_h44441004(chips)!SCONN288_H44441004_PIP-SCONN,HA!!!F160!DQ(36)!!!!
S!M_F_DQ<36>!J4A1!240!@baseboard_fab2_lib.baseboard_fab2(sch_1):page53_i111@mstr_sconn.sconn288_h44441004(chips)!SCONN288_H44441004_PIP-SCONN,HA!!!F160!DQ(37)!!!!
S!M_F_DQ<39>!J4A1!102!@baseboard_fab2_lib.baseboard_fab2(sch_1):page53_i111@mstr_sconn.sconn288_h44441004(chips)!SCONN288_H44441004_PIP-SCONN,HA!!!F160!DQ(38)!!!!
S!M_F_DQ<38>!J4A1!247!@baseboard_fab2_lib.baseboard_fab2(sch_1):page53_i111@mstr_sconn.sconn288_h44441004(chips)!SCONN288_H44441004_PIP-SCONN,HA!!!F160!DQ(39)!!!!
S!M_F_DQ<2>!J4A1!157!@baseboard_fab2_lib.baseboard_fab2(sch_1):page53_i111@mstr_sconn.sconn288_h44441004(chips)!SCONN288_H44441004_PIP-SCONN,HA!!!F160!DQ(3)!!!!
S!M_F_DQ<41>!J4A1!108!@baseboard_fab2_lib.baseboard_fab2(sch_1):page53_i111@mstr_sconn.sconn288_h44441004(chips)!SCONN288_H44441004_PIP-SCONN,HA!!!F160!DQ(40)!!!!
S!M_F_DQ<40>!J4A1!253!@baseboard_fab2_lib.baseboard_fab2(sch_1):page53_i111@mstr_sconn.sconn288_h44441004(chips)!SCONN288_H44441004_PIP-SCONN,HA!!!F160!DQ(41)!!!!
S!M_F_DQ<43>!J4A1!115!@baseboard_fab2_lib.baseboard_fab2(sch_1):page53_i111@mstr_sconn.sconn288_h44441004(chips)!SCONN288_H44441004_PIP-SCONN,HA!!!F160!DQ(42)!!!!
S!M_F_DQ<42>!J4A1!260!@baseboard_fab2_lib.baseboard_fab2(sch_1):page53_i111@mstr_sconn.sconn288_h44441004(chips)!SCONN288_H44441004_PIP-SCONN,HA!!!F160!DQ(43)!!!!
S!M_F_DQ<45>!J4A1!106!@baseboard_fab2_lib.baseboard_fab2(sch_1):page53_i111@mstr_sconn.sconn288_h44441004(chips)!SCONN288_H44441004_PIP-SCONN,HA!!!F160!DQ(44)!!!!
S!M_F_DQ<44>!J4A1!251!@baseboard_fab2_lib.baseboard_fab2(sch_1):page53_i111@mstr_sconn.sconn288_h44441004(chips)!SCONN288_H44441004_PIP-SCONN,HA!!!F160!DQ(45)!!!!
S!M_F_DQ<47>!J4A1!113!@baseboard_fab2_lib.baseboard_fab2(sch_1):page53_i111@mstr_sconn.sconn288_h44441004(chips)!SCONN288_H44441004_PIP-SCONN,HA!!!F160!DQ(46)!!!!
S!M_F_DQ<46>!J4A1!258!@baseboard_fab2_lib.baseboard_fab2(sch_1):page53_i111@mstr_sconn.sconn288_h44441004(chips)!SCONN288_H44441004_PIP-SCONN,HA!!!F160!DQ(47)!!!!
S!M_F_DQ<49>!J4A1!119!@baseboard_fab2_lib.baseboard_fab2(sch_1):page53_i111@mstr_sconn.sconn288_h44441004(chips)!SCONN288_H44441004_PIP-SCONN,HA!!!F160!DQ(48)!!!!
S!M_F_DQ<48>!J4A1!264!@baseboard_fab2_lib.baseboard_fab2(sch_1):page53_i111@mstr_sconn.sconn288_h44441004(chips)!SCONN288_H44441004_PIP-SCONN,HA!!!F160!DQ(49)!!!!
S!M_F_DQ<5>!J4A1!3!@baseboard_fab2_lib.baseboard_fab2(sch_1):page53_i111@mstr_sconn.sconn288_h44441004(chips)!SCONN288_H44441004_PIP-SCONN,HA!!!F160!DQ(4)!!!!
S!M_F_DQ<51>!J4A1!126!@baseboard_fab2_lib.baseboard_fab2(sch_1):page53_i111@mstr_sconn.sconn288_h44441004(chips)!SCONN288_H44441004_PIP-SCONN,HA!!!F160!DQ(50)!!!!
S!M_F_DQ<50>!J4A1!271!@baseboard_fab2_lib.baseboard_fab2(sch_1):page53_i111@mstr_sconn.sconn288_h44441004(chips)!SCONN288_H44441004_PIP-SCONN,HA!!!F160!DQ(51)!!!!
S!M_F_DQ<53>!J4A1!117!@baseboard_fab2_lib.baseboard_fab2(sch_1):page53_i111@mstr_sconn.sconn288_h44441004(chips)!SCONN288_H44441004_PIP-SCONN,HA!!!F160!DQ(52)!!!!
S!M_F_DQ<52>!J4A1!262!@baseboard_fab2_lib.baseboard_fab2(sch_1):page53_i111@mstr_sconn.sconn288_h44441004(chips)!SCONN288_H44441004_PIP-SCONN,HA!!!F160!DQ(53)!!!!
S!M_F_DQ<55>!J4A1!124!@baseboard_fab2_lib.baseboard_fab2(sch_1):page53_i111@mstr_sconn.sconn288_h44441004(chips)!SCONN288_H44441004_PIP-SCONN,HA!!!F160!DQ(54)!!!!
S!M_F_DQ<54>!J4A1!269!@baseboard_fab2_lib.baseboard_fab2(sch_1):page53_i111@mstr_sconn.sconn288_h44441004(chips)!SCONN288_H44441004_PIP-SCONN,HA!!!F160!DQ(55)!!!!
S!M_F_DQ<57>!J4A1!130!@baseboard_fab2_lib.baseboard_fab2(sch_1):page53_i111@mstr_sconn.sconn288_h44441004(chips)!SCONN288_H44441004_PIP-SCONN,HA!!!F160!DQ(56)!!!!
S!M_F_DQ<56>!J4A1!275!@baseboard_fab2_lib.baseboard_fab2(sch_1):page53_i111@mstr_sconn.sconn288_h44441004(chips)!SCONN288_H44441004_PIP-SCONN,HA!!!F160!DQ(57)!!!!
S!M_F_DQ<59>!J4A1!137!@baseboard_fab2_lib.baseboard_fab2(sch_1):page53_i111@mstr_sconn.sconn288_h44441004(chips)!SCONN288_H44441004_PIP-SCONN,HA!!!F160!DQ(58)!!!!
S!M_F_DQ<58>!J4A1!282!@baseboard_fab2_lib.baseboard_fab2(sch_1):page53_i111@mstr_sconn.sconn288_h44441004(chips)!SCONN288_H44441004_PIP-SCONN,HA!!!F160!DQ(59)!!!!
S!M_F_DQ<4>!J4A1!148!@baseboard_fab2_lib.baseboard_fab2(sch_1):page53_i111@mstr_sconn.sconn288_h44441004(chips)!SCONN288_H44441004_PIP-SCONN,HA!!!F160!DQ(5)!!!!
S!M_F_DQ<61>!J4A1!128!@baseboard_fab2_lib.baseboard_fab2(sch_1):page53_i111@mstr_sconn.sconn288_h44441004(chips)!SCONN288_H44441004_PIP-SCONN,HA!!!F160!DQ(60)!!!!
S!M_F_DQ<60>!J4A1!273!@baseboard_fab2_lib.baseboard_fab2(sch_1):page53_i111@mstr_sconn.sconn288_h44441004(chips)!SCONN288_H44441004_PIP-SCONN,HA!!!F160!DQ(61)!!!!
S!M_F_DQ<63>!J4A1!135!@baseboard_fab2_lib.baseboard_fab2(sch_1):page53_i111@mstr_sconn.sconn288_h44441004(chips)!SCONN288_H44441004_PIP-SCONN,HA!!!F160!DQ(62)!!!!
S!M_F_DQ<62>!J4A1!280!@baseboard_fab2_lib.baseboard_fab2(sch_1):page53_i111@mstr_sconn.sconn288_h44441004(chips)!SCONN288_H44441004_PIP-SCONN,HA!!!F160!DQ(63)!!!!
S!M_F_DQ<7>!J4A1!10!@baseboard_fab2_lib.baseboard_fab2(sch_1):page53_i111@mstr_sconn.sconn288_h44441004(chips)!SCONN288_H44441004_PIP-SCONN,HA!!!F160!DQ(6)!!!!
S!M_F_DQ<6>!J4A1!155!@baseboard_fab2_lib.baseboard_fab2(sch_1):page53_i111@mstr_sconn.sconn288_h44441004(chips)!SCONN288_H44441004_PIP-SCONN,HA!!!F160!DQ(7)!!!!
S!M_F_DQ<9>!J4A1!16!@baseboard_fab2_lib.baseboard_fab2(sch_1):page53_i111@mstr_sconn.sconn288_h44441004(chips)!SCONN288_H44441004_PIP-SCONN,HA!!!F160!DQ(8)!!!!
S!M_F_DQ<8>!J4A1!161!@baseboard_fab2_lib.baseboard_fab2(sch_1):page53_i111@mstr_sconn.sconn288_h44441004(chips)!SCONN288_H44441004_PIP-SCONN,HA!!!F160!DQ(9)!!!!
S!FM_DIMM_EVENT_COD_N!J4A1!78!@baseboard_fab2_lib.baseboard_fab2(sch_1):page53_i111@mstr_sconn.sconn288_h44441004(chips)!SCONN288_H44441004_PIP-SCONN,HA!!!F160!EVENT_N!!!!
S!M_F_ODT<0>!J4A1!87!@baseboard_fab2_lib.baseboard_fab2(sch_1):page53_i111@mstr_sconn.sconn288_h44441004(chips)!SCONN288_H44441004_PIP-SCONN,HA!!!F160!ODT(0)!!!!
S!M_F_ODT<1>!J4A1!91!@baseboard_fab2_lib.baseboard_fab2(sch_1):page53_i111@mstr_sconn.sconn288_h44441004(chips)!SCONN288_H44441004_PIP-SCONN,HA!!!F160!ODT(1)!!!!
S!M_F_PAR!J4A1!222!@baseboard_fab2_lib.baseboard_fab2(sch_1):page53_i111@mstr_sconn.sconn288_h44441004(chips)!SCONN288_H44441004_PIP-SCONN,HA!!!F160!PAR!!!!
S!M_DEF_RST_N!J4A1!58!@baseboard_fab2_lib.baseboard_fab2(sch_1):page53_i111@mstr_sconn.sconn288_h44441004(chips)!SCONN288_H44441004_PIP-SCONN,HA!!!F160!RESET_N!!!!
S!TP_CH_F_DIMM_F0_RFU_0!J4A1!205!@baseboard_fab2_lib.baseboard_fab2(sch_1):page53_i111@mstr_sconn.sconn288_h44441004(chips)!SCONN288_H44441004_PIP-SCONN,HA!!!F160!RFU(0)!!!!
S!TP_CH_F_DIMM_F0_RFU_1!J4A1!227!@baseboard_fab2_lib.baseboard_fab2(sch_1):page53_i111@mstr_sconn.sconn288_h44441004(chips)!SCONN288_H44441004_PIP-SCONN,HA!!!F160!RFU(1)!!!!
S!TP_CH_F_DIMM_F0_RFU_2!J4A1!144!@baseboard_fab2_lib.baseboard_fab2(sch_1):page53_i111@mstr_sconn.sconn288_h44441004(chips)!SCONN288_H44441004_PIP-SCONN,HA!!!F160!RFU(2)!!!!
S!M_F_CS_N<0>!J4A1!84!@baseboard_fab2_lib.baseboard_fab2(sch_1):page53_i111@mstr_sconn.sconn288_h44441004(chips)!SCONN288_H44441004_PIP-SCONN,HA!!!F160!S0_N!!!!
S!M_F_CS_N<1>!J4A1!89!@baseboard_fab2_lib.baseboard_fab2(sch_1):page53_i111@mstr_sconn.sconn288_h44441004(chips)!SCONN288_H44441004_PIP-SCONN,HA!!!F160!S1_N!!!!
S!M_F_CS_N<2>!J4A1!93!@baseboard_fab2_lib.baseboard_fab2(sch_1):page53_i111@mstr_sconn.sconn288_h44441004(chips)!SCONN288_H44441004_PIP-SCONN,HA!!!F160!S2_N_C(0)!!!!
S!M_F_CS_N<3>!J4A1!237!@baseboard_fab2_lib.baseboard_fab2(sch_1):page53_i111@mstr_sconn.sconn288_h44441004(chips)!SCONN288_H44441004_PIP-SCONN,HA!!!F160!S3_N_C(1)!!!!
S!GND!J4A1!139!@baseboard_fab2_lib.baseboard_fab2(sch_1):page53_i111@mstr_sconn.sconn288_h44441004(chips)!SCONN288_H44441004_PIP-SCONN,HA!!!F160!SA(0)!!!!
S!GND!J4A1!140!@baseboard_fab2_lib.baseboard_fab2(sch_1):page53_i111@mstr_sconn.sconn288_h44441004(chips)!SCONN288_H44441004_PIP-SCONN,HA!!!F160!SA(1)!!!!
S!PVPP_DEF!J4A1!238!@baseboard_fab2_lib.baseboard_fab2(sch_1):page53_i111@mstr_sconn.sconn288_h44441004(chips)!SCONN288_H44441004_PIP-SCONN,HA!!!F160!SA(2)!!!!
S!FM_ADR_COMPLETE_DEF_N!J4A1!230!@baseboard_fab2_lib.baseboard_fab2(sch_1):page53_i111@mstr_sconn.sconn288_h44441004(chips)!SCONN288_H44441004_PIP-SCONN,HA!!!F160!SAVE_N_NC!!!!
S!SMB_DDR_DEF_VPP_SCL!J4A1!141!@baseboard_fab2_lib.baseboard_fab2(sch_1):page53_i111@mstr_sconn.sconn288_h44441004(chips)!SCONN288_H44441004_PIP-SCONN,HA!!!F160!SCL!!!!
S!SMB_DDR_DEF_VPP_SDA!J4A1!285!@baseboard_fab2_lib.baseboard_fab2(sch_1):page53_i111@mstr_sconn.sconn288_h44441004(chips)!SCONN288_H44441004_PIP-SCONN,HA!!!F160!SDA!!!!
S!PVPP_DEF!J4A1!284!@baseboard_fab2_lib.baseboard_fab2(sch_1):page53_i111@mstr_sconn.sconn288_h44441004(chips)!SCONN288_H44441004_PIP-SCONN,HA!!!F160!VDDSPD!!!!
S!M_F_VREF!J4A1!146!@baseboard_fab2_lib.baseboard_fab2(sch_1):page53_i111@mstr_sconn.sconn288_h44441004(chips)!SCONN288_H44441004_PIP-SCONN,HA!!!F160!VREFCA!!!!
S!M_F_DQS_DN<0>!J4A1!152!@baseboard_fab2_lib.baseboard_fab2(sch_1):page53_i66@mstr_sconn.sconn288_h44441004(chips)!SCONN288_H44441004_PIP-SCONN,HA!!!F159!DQS0N!!!!
S!M_F_DQS_DP<0>!J4A1!153!@baseboard_fab2_lib.baseboard_fab2(sch_1):page53_i66@mstr_sconn.sconn288_h44441004(chips)!SCONN288_H44441004_PIP-SCONN,HA!!!F159!DQS0P!!!!
S!M_F_DQS_DN<10>!J4A1!19!@baseboard_fab2_lib.baseboard_fab2(sch_1):page53_i66@mstr_sconn.sconn288_h44441004(chips)!SCONN288_H44441004_PIP-SCONN,HA!!!F159!DQS10N!!!!
S!M_F_DQS_DP<10>!J4A1!18!@baseboard_fab2_lib.baseboard_fab2(sch_1):page53_i66@mstr_sconn.sconn288_h44441004(chips)!SCONN288_H44441004_PIP-SCONN,HA!!!F159!DQS10P!!!!
S!M_F_DQS_DN<11>!J4A1!30!@baseboard_fab2_lib.baseboard_fab2(sch_1):page53_i66@mstr_sconn.sconn288_h44441004(chips)!SCONN288_H44441004_PIP-SCONN,HA!!!F159!DQS11N!!!!
S!M_F_DQS_DP<11>!J4A1!29!@baseboard_fab2_lib.baseboard_fab2(sch_1):page53_i66@mstr_sconn.sconn288_h44441004(chips)!SCONN288_H44441004_PIP-SCONN,HA!!!F159!DQS11P!!!!
S!M_F_DQS_DN<12>!J4A1!41!@baseboard_fab2_lib.baseboard_fab2(sch_1):page53_i66@mstr_sconn.sconn288_h44441004(chips)!SCONN288_H44441004_PIP-SCONN,HA!!!F159!DQS12N!!!!
S!M_F_DQS_DP<12>!J4A1!40!@baseboard_fab2_lib.baseboard_fab2(sch_1):page53_i66@mstr_sconn.sconn288_h44441004(chips)!SCONN288_H44441004_PIP-SCONN,HA!!!F159!DQS12P!!!!
S!M_F_DQS_DN<13>!J4A1!100!@baseboard_fab2_lib.baseboard_fab2(sch_1):page53_i66@mstr_sconn.sconn288_h44441004(chips)!SCONN288_H44441004_PIP-SCONN,HA!!!F159!DQS13N!!!!
S!M_F_DQS_DP<13>!J4A1!99!@baseboard_fab2_lib.baseboard_fab2(sch_1):page53_i66@mstr_sconn.sconn288_h44441004(chips)!SCONN288_H44441004_PIP-SCONN,HA!!!F159!DQS13P!!!!
S!M_F_DQS_DN<14>!J4A1!111!@baseboard_fab2_lib.baseboard_fab2(sch_1):page53_i66@mstr_sconn.sconn288_h44441004(chips)!SCONN288_H44441004_PIP-SCONN,HA!!!F159!DQS14N!!!!
S!M_F_DQS_DP<14>!J4A1!110!@baseboard_fab2_lib.baseboard_fab2(sch_1):page53_i66@mstr_sconn.sconn288_h44441004(chips)!SCONN288_H44441004_PIP-SCONN,HA!!!F159!DQS14P!!!!
S!M_F_DQS_DN<15>!J4A1!122!@baseboard_fab2_lib.baseboard_fab2(sch_1):page53_i66@mstr_sconn.sconn288_h44441004(chips)!SCONN288_H44441004_PIP-SCONN,HA!!!F159!DQS15N!!!!
S!M_F_DQS_DP<15>!J4A1!121!@baseboard_fab2_lib.baseboard_fab2(sch_1):page53_i66@mstr_sconn.sconn288_h44441004(chips)!SCONN288_H44441004_PIP-SCONN,HA!!!F159!DQS15P!!!!
S!M_F_DQS_DN<16>!J4A1!133!@baseboard_fab2_lib.baseboard_fab2(sch_1):page53_i66@mstr_sconn.sconn288_h44441004(chips)!SCONN288_H44441004_PIP-SCONN,HA!!!F159!DQS16N!!!!
S!M_F_DQS_DP<16>!J4A1!132!@baseboard_fab2_lib.baseboard_fab2(sch_1):page53_i66@mstr_sconn.sconn288_h44441004(chips)!SCONN288_H44441004_PIP-SCONN,HA!!!F159!DQS16P!!!!
S!M_F_DQS_DN<17>!J4A1!52!@baseboard_fab2_lib.baseboard_fab2(sch_1):page53_i66@mstr_sconn.sconn288_h44441004(chips)!SCONN288_H44441004_PIP-SCONN,HA!!!F159!DQS17N!!!!
S!M_F_DQS_DP<17>!J4A1!51!@baseboard_fab2_lib.baseboard_fab2(sch_1):page53_i66@mstr_sconn.sconn288_h44441004(chips)!SCONN288_H44441004_PIP-SCONN,HA!!!F159!DQS17P!!!!
S!M_F_DQS_DN<1>!J4A1!163!@baseboard_fab2_lib.baseboard_fab2(sch_1):page53_i66@mstr_sconn.sconn288_h44441004(chips)!SCONN288_H44441004_PIP-SCONN,HA!!!F159!DQS1N!!!!
S!M_F_DQS_DP<1>!J4A1!164!@baseboard_fab2_lib.baseboard_fab2(sch_1):page53_i66@mstr_sconn.sconn288_h44441004(chips)!SCONN288_H44441004_PIP-SCONN,HA!!!F159!DQS1P!!!!
S!M_F_DQS_DN<2>!J4A1!174!@baseboard_fab2_lib.baseboard_fab2(sch_1):page53_i66@mstr_sconn.sconn288_h44441004(chips)!SCONN288_H44441004_PIP-SCONN,HA!!!F159!DQS2N!!!!
S!M_F_DQS_DP<2>!J4A1!175!@baseboard_fab2_lib.baseboard_fab2(sch_1):page53_i66@mstr_sconn.sconn288_h44441004(chips)!SCONN288_H44441004_PIP-SCONN,HA!!!F159!DQS2P!!!!
S!M_F_DQS_DN<3>!J4A1!185!@baseboard_fab2_lib.baseboard_fab2(sch_1):page53_i66@mstr_sconn.sconn288_h44441004(chips)!SCONN288_H44441004_PIP-SCONN,HA!!!F159!DQS3N!!!!
S!M_F_DQS_DP<3>!J4A1!186!@baseboard_fab2_lib.baseboard_fab2(sch_1):page53_i66@mstr_sconn.sconn288_h44441004(chips)!SCONN288_H44441004_PIP-SCONN,HA!!!F159!DQS3P!!!!
S!M_F_DQS_DN<4>!J4A1!244!@baseboard_fab2_lib.baseboard_fab2(sch_1):page53_i66@mstr_sconn.sconn288_h44441004(chips)!SCONN288_H44441004_PIP-SCONN,HA!!!F159!DQS4N!!!!
S!M_F_DQS_DP<4>!J4A1!245!@baseboard_fab2_lib.baseboard_fab2(sch_1):page53_i66@mstr_sconn.sconn288_h44441004(chips)!SCONN288_H44441004_PIP-SCONN,HA!!!F159!DQS4P!!!!
S!M_F_DQS_DN<5>!J4A1!255!@baseboard_fab2_lib.baseboard_fab2(sch_1):page53_i66@mstr_sconn.sconn288_h44441004(chips)!SCONN288_H44441004_PIP-SCONN,HA!!!F159!DQS5N!!!!
S!M_F_DQS_DP<5>!J4A1!256!@baseboard_fab2_lib.baseboard_fab2(sch_1):page53_i66@mstr_sconn.sconn288_h44441004(chips)!SCONN288_H44441004_PIP-SCONN,HA!!!F159!DQS5P!!!!
S!M_F_DQS_DN<6>!J4A1!266!@baseboard_fab2_lib.baseboard_fab2(sch_1):page53_i66@mstr_sconn.sconn288_h44441004(chips)!SCONN288_H44441004_PIP-SCONN,HA!!!F159!DQS6N!!!!
S!M_F_DQS_DP<6>!J4A1!267!@baseboard_fab2_lib.baseboard_fab2(sch_1):page53_i66@mstr_sconn.sconn288_h44441004(chips)!SCONN288_H44441004_PIP-SCONN,HA!!!F159!DQS6P!!!!
S!M_F_DQS_DN<7>!J4A1!277!@baseboard_fab2_lib.baseboard_fab2(sch_1):page53_i66@mstr_sconn.sconn288_h44441004(chips)!SCONN288_H44441004_PIP-SCONN,HA!!!F159!DQS7N!!!!
S!M_F_DQS_DP<7>!J4A1!278!@baseboard_fab2_lib.baseboard_fab2(sch_1):page53_i66@mstr_sconn.sconn288_h44441004(chips)!SCONN288_H44441004_PIP-SCONN,HA!!!F159!DQS7P!!!!
S!M_F_DQS_DN<8>!J4A1!196!@baseboard_fab2_lib.baseboard_fab2(sch_1):page53_i66@mstr_sconn.sconn288_h44441004(chips)!SCONN288_H44441004_PIP-SCONN,HA!!!F159!DQS8N!!!!
S!M_F_DQS_DP<8>!J4A1!197!@baseboard_fab2_lib.baseboard_fab2(sch_1):page53_i66@mstr_sconn.sconn288_h44441004(chips)!SCONN288_H44441004_PIP-SCONN,HA!!!F159!DQS8P!!!!
S!M_F_DQS_DN<9>!J4A1!8!@baseboard_fab2_lib.baseboard_fab2(sch_1):page53_i66@mstr_sconn.sconn288_h44441004(chips)!SCONN288_H44441004_PIP-SCONN,HA!!!F159!DQS9N!!!!
S!M_F_DQS_DP<9>!J4A1!7!@baseboard_fab2_lib.baseboard_fab2(sch_1):page53_i66@mstr_sconn.sconn288_h44441004(chips)!SCONN288_H44441004_PIP-SCONN,HA!!!F159!DQS9P!!!!
S!GND!J4A1!283!@baseboard_fab2_lib.baseboard_fab2(sch_1):page53_i43@mstr_sconn.sconn288_h44441004(chips)!SCONN288_H44441004_PIP-SCONN,HA!!!F158!VSS(0)!!!!
S!GND!J4A1!261!@baseboard_fab2_lib.baseboard_fab2(sch_1):page53_i43@mstr_sconn.sconn288_h44441004(chips)!SCONN288_H44441004_PIP-SCONN,HA!!!F158!VSS(10)!!!!
S!GND!J4A1!259!@baseboard_fab2_lib.baseboard_fab2(sch_1):page53_i43@mstr_sconn.sconn288_h44441004(chips)!SCONN288_H44441004_PIP-SCONN,HA!!!F158!VSS(11)!!!!
S!GND!J4A1!257!@baseboard_fab2_lib.baseboard_fab2(sch_1):page53_i43@mstr_sconn.sconn288_h44441004(chips)!SCONN288_H44441004_PIP-SCONN,HA!!!F158!VSS(12)!!!!
S!GND!J4A1!254!@baseboard_fab2_lib.baseboard_fab2(sch_1):page53_i43@mstr_sconn.sconn288_h44441004(chips)!SCONN288_H44441004_PIP-SCONN,HA!!!F158!VSS(13)!!!!
S!GND!J4A1!252!@baseboard_fab2_lib.baseboard_fab2(sch_1):page53_i43@mstr_sconn.sconn288_h44441004(chips)!SCONN288_H44441004_PIP-SCONN,HA!!!F158!VSS(14)!!!!
S!GND!J4A1!250!@baseboard_fab2_lib.baseboard_fab2(sch_1):page53_i43@mstr_sconn.sconn288_h44441004(chips)!SCONN288_H44441004_PIP-SCONN,HA!!!F158!VSS(15)!!!!
S!GND!J4A1!248!@baseboard_fab2_lib.baseboard_fab2(sch_1):page53_i43@mstr_sconn.sconn288_h44441004(chips)!SCONN288_H44441004_PIP-SCONN,HA!!!F158!VSS(16)!!!!
S!GND!J4A1!246!@baseboard_fab2_lib.baseboard_fab2(sch_1):page53_i43@mstr_sconn.sconn288_h44441004(chips)!SCONN288_H44441004_PIP-SCONN,HA!!!F158!VSS(17)!!!!
S!GND!J4A1!243!@baseboard_fab2_lib.baseboard_fab2(sch_1):page53_i43@mstr_sconn.sconn288_h44441004(chips)!SCONN288_H44441004_PIP-SCONN,HA!!!F158!VSS(18)!!!!
S!GND!J4A1!241!@baseboard_fab2_lib.baseboard_fab2(sch_1):page53_i43@mstr_sconn.sconn288_h44441004(chips)!SCONN288_H44441004_PIP-SCONN,HA!!!F158!VSS(19)!!!!
S!GND!J4A1!281!@baseboard_fab2_lib.baseboard_fab2(sch_1):page53_i43@mstr_sconn.sconn288_h44441004(chips)!SCONN288_H44441004_PIP-SCONN,HA!!!F158!VSS(1)!!!!
S!GND!J4A1!239!@baseboard_fab2_lib.baseboard_fab2(sch_1):page53_i43@mstr_sconn.sconn288_h44441004(chips)!SCONN288_H44441004_PIP-SCONN,HA!!!F158!VSS(20)!!!!
S!GND!J4A1!202!@baseboard_fab2_lib.baseboard_fab2(sch_1):page53_i43@mstr_sconn.sconn288_h44441004(chips)!SCONN288_H44441004_PIP-SCONN,HA!!!F158!VSS(21)!!!!
S!GND!J4A1!200!@baseboard_fab2_lib.baseboard_fab2(sch_1):page53_i43@mstr_sconn.sconn288_h44441004(chips)!SCONN288_H44441004_PIP-SCONN,HA!!!F158!VSS(22)!!!!
S!GND!J4A1!198!@baseboard_fab2_lib.baseboard_fab2(sch_1):page53_i43@mstr_sconn.sconn288_h44441004(chips)!SCONN288_H44441004_PIP-SCONN,HA!!!F158!VSS(23)!!!!
S!GND!J4A1!195!@baseboard_fab2_lib.baseboard_fab2(sch_1):page53_i43@mstr_sconn.sconn288_h44441004(chips)!SCONN288_H44441004_PIP-SCONN,HA!!!F158!VSS(24)!!!!
S!GND!J4A1!193!@baseboard_fab2_lib.baseboard_fab2(sch_1):page53_i43@mstr_sconn.sconn288_h44441004(chips)!SCONN288_H44441004_PIP-SCONN,HA!!!F158!VSS(25)!!!!
S!GND!J4A1!191!@baseboard_fab2_lib.baseboard_fab2(sch_1):page53_i43@mstr_sconn.sconn288_h44441004(chips)!SCONN288_H44441004_PIP-SCONN,HA!!!F158!VSS(26)!!!!
S!GND!J4A1!189!@baseboard_fab2_lib.baseboard_fab2(sch_1):page53_i43@mstr_sconn.sconn288_h44441004(chips)!SCONN288_H44441004_PIP-SCONN,HA!!!F158!VSS(27)!!!!
S!GND!J4A1!187!@baseboard_fab2_lib.baseboard_fab2(sch_1):page53_i43@mstr_sconn.sconn288_h44441004(chips)!SCONN288_H44441004_PIP-SCONN,HA!!!F158!VSS(28)!!!!
S!GND!J4A1!184!@baseboard_fab2_lib.baseboard_fab2(sch_1):page53_i43@mstr_sconn.sconn288_h44441004(chips)!SCONN288_H44441004_PIP-SCONN,HA!!!F158!VSS(29)!!!!
S!GND!J4A1!279!@baseboard_fab2_lib.baseboard_fab2(sch_1):page53_i43@mstr_sconn.sconn288_h44441004(chips)!SCONN288_H44441004_PIP-SCONN,HA!!!F158!VSS(2)!!!!
S!GND!J4A1!182!@baseboard_fab2_lib.baseboard_fab2(sch_1):page53_i43@mstr_sconn.sconn288_h44441004(chips)!SCONN288_H44441004_PIP-SCONN,HA!!!F158!VSS(30)!!!!
S!GND!J4A1!180!@baseboard_fab2_lib.baseboard_fab2(sch_1):page53_i43@mstr_sconn.sconn288_h44441004(chips)!SCONN288_H44441004_PIP-SCONN,HA!!!F158!VSS(31)!!!!
S!GND!J4A1!178!@baseboard_fab2_lib.baseboard_fab2(sch_1):page53_i43@mstr_sconn.sconn288_h44441004(chips)!SCONN288_H44441004_PIP-SCONN,HA!!!F158!VSS(32)!!!!
S!GND!J4A1!176!@baseboard_fab2_lib.baseboard_fab2(sch_1):page53_i43@mstr_sconn.sconn288_h44441004(chips)!SCONN288_H44441004_PIP-SCONN,HA!!!F158!VSS(33)!!!!
S!GND!J4A1!173!@baseboard_fab2_lib.baseboard_fab2(sch_1):page53_i43@mstr_sconn.sconn288_h44441004(chips)!SCONN288_H44441004_PIP-SCONN,HA!!!F158!VSS(34)!!!!
S!GND!J4A1!171!@baseboard_fab2_lib.baseboard_fab2(sch_1):page53_i43@mstr_sconn.sconn288_h44441004(chips)!SCONN288_H44441004_PIP-SCONN,HA!!!F158!VSS(35)!!!!
S!GND!J4A1!169!@baseboard_fab2_lib.baseboard_fab2(sch_1):page53_i43@mstr_sconn.sconn288_h44441004(chips)!SCONN288_H44441004_PIP-SCONN,HA!!!F158!VSS(36)!!!!
S!GND!J4A1!167!@baseboard_fab2_lib.baseboard_fab2(sch_1):page53_i43@mstr_sconn.sconn288_h44441004(chips)!SCONN288_H44441004_PIP-SCONN,HA!!!F158!VSS(37)!!!!
S!GND!J4A1!165!@baseboard_fab2_lib.baseboard_fab2(sch_1):page53_i43@mstr_sconn.sconn288_h44441004(chips)!SCONN288_H44441004_PIP-SCONN,HA!!!F158!VSS(38)!!!!
S!GND!J4A1!162!@baseboard_fab2_lib.baseboard_fab2(sch_1):page53_i43@mstr_sconn.sconn288_h44441004(chips)!SCONN288_H44441004_PIP-SCONN,HA!!!F158!VSS(39)!!!!
S!GND!J4A1!276!@baseboard_fab2_lib.baseboard_fab2(sch_1):page53_i43@mstr_sconn.sconn288_h44441004(chips)!SCONN288_H44441004_PIP-SCONN,HA!!!F158!VSS(3)!!!!
S!GND!J4A1!160!@baseboard_fab2_lib.baseboard_fab2(sch_1):page53_i43@mstr_sconn.sconn288_h44441004(chips)!SCONN288_H44441004_PIP-SCONN,HA!!!F158!VSS(40)!!!!
S!GND!J4A1!158!@baseboard_fab2_lib.baseboard_fab2(sch_1):page53_i43@mstr_sconn.sconn288_h44441004(chips)!SCONN288_H44441004_PIP-SCONN,HA!!!F158!VSS(41)!!!!
S!GND!J4A1!156!@baseboard_fab2_lib.baseboard_fab2(sch_1):page53_i43@mstr_sconn.sconn288_h44441004(chips)!SCONN288_H44441004_PIP-SCONN,HA!!!F158!VSS(42)!!!!
S!GND!J4A1!154!@baseboard_fab2_lib.baseboard_fab2(sch_1):page53_i43@mstr_sconn.sconn288_h44441004(chips)!SCONN288_H44441004_PIP-SCONN,HA!!!F158!VSS(43)!!!!
S!GND!J4A1!151!@baseboard_fab2_lib.baseboard_fab2(sch_1):page53_i43@mstr_sconn.sconn288_h44441004(chips)!SCONN288_H44441004_PIP-SCONN,HA!!!F158!VSS(44)!!!!
S!GND!J4A1!149!@baseboard_fab2_lib.baseboard_fab2(sch_1):page53_i43@mstr_sconn.sconn288_h44441004(chips)!SCONN288_H44441004_PIP-SCONN,HA!!!F158!VSS(45)!!!!
S!GND!J4A1!147!@baseboard_fab2_lib.baseboard_fab2(sch_1):page53_i43@mstr_sconn.sconn288_h44441004(chips)!SCONN288_H44441004_PIP-SCONN,HA!!!F158!VSS(46)!!!!
S!GND!J4A1!138!@baseboard_fab2_lib.baseboard_fab2(sch_1):page53_i43@mstr_sconn.sconn288_h44441004(chips)!SCONN288_H44441004_PIP-SCONN,HA!!!F158!VSS(47)!!!!
S!GND!J4A1!136!@baseboard_fab2_lib.baseboard_fab2(sch_1):page53_i43@mstr_sconn.sconn288_h44441004(chips)!SCONN288_H44441004_PIP-SCONN,HA!!!F158!VSS(48)!!!!
S!GND!J4A1!134!@baseboard_fab2_lib.baseboard_fab2(sch_1):page53_i43@mstr_sconn.sconn288_h44441004(chips)!SCONN288_H44441004_PIP-SCONN,HA!!!F158!VSS(49)!!!!
S!GND!J4A1!274!@baseboard_fab2_lib.baseboard_fab2(sch_1):page53_i43@mstr_sconn.sconn288_h44441004(chips)!SCONN288_H44441004_PIP-SCONN,HA!!!F158!VSS(4)!!!!
S!GND!J4A1!131!@baseboard_fab2_lib.baseboard_fab2(sch_1):page53_i43@mstr_sconn.sconn288_h44441004(chips)!SCONN288_H44441004_PIP-SCONN,HA!!!F158!VSS(50)!!!!
S!GND!J4A1!129!@baseboard_fab2_lib.baseboard_fab2(sch_1):page53_i43@mstr_sconn.sconn288_h44441004(chips)!SCONN288_H44441004_PIP-SCONN,HA!!!F158!VSS(51)!!!!
S!GND!J4A1!127!@baseboard_fab2_lib.baseboard_fab2(sch_1):page53_i43@mstr_sconn.sconn288_h44441004(chips)!SCONN288_H44441004_PIP-SCONN,HA!!!F158!VSS(52)!!!!
S!GND!J4A1!125!@baseboard_fab2_lib.baseboard_fab2(sch_1):page53_i43@mstr_sconn.sconn288_h44441004(chips)!SCONN288_H44441004_PIP-SCONN,HA!!!F158!VSS(53)!!!!
S!GND!J4A1!123!@baseboard_fab2_lib.baseboard_fab2(sch_1):page53_i43@mstr_sconn.sconn288_h44441004(chips)!SCONN288_H44441004_PIP-SCONN,HA!!!F158!VSS(54)!!!!
S!GND!J4A1!120!@baseboard_fab2_lib.baseboard_fab2(sch_1):page53_i43@mstr_sconn.sconn288_h44441004(chips)!SCONN288_H44441004_PIP-SCONN,HA!!!F158!VSS(55)!!!!
S!GND!J4A1!118!@baseboard_fab2_lib.baseboard_fab2(sch_1):page53_i43@mstr_sconn.sconn288_h44441004(chips)!SCONN288_H44441004_PIP-SCONN,HA!!!F158!VSS(56)!!!!
S!GND!J4A1!116!@baseboard_fab2_lib.baseboard_fab2(sch_1):page53_i43@mstr_sconn.sconn288_h44441004(chips)!SCONN288_H44441004_PIP-SCONN,HA!!!F158!VSS(57)!!!!
S!GND!J4A1!114!@baseboard_fab2_lib.baseboard_fab2(sch_1):page53_i43@mstr_sconn.sconn288_h44441004(chips)!SCONN288_H44441004_PIP-SCONN,HA!!!F158!VSS(58)!!!!
S!GND!J4A1!112!@baseboard_fab2_lib.baseboard_fab2(sch_1):page53_i43@mstr_sconn.sconn288_h44441004(chips)!SCONN288_H44441004_PIP-SCONN,HA!!!F158!VSS(59)!!!!
S!GND!J4A1!272!@baseboard_fab2_lib.baseboard_fab2(sch_1):page53_i43@mstr_sconn.sconn288_h44441004(chips)!SCONN288_H44441004_PIP-SCONN,HA!!!F158!VSS(5)!!!!
S!GND!J4A1!109!@baseboard_fab2_lib.baseboard_fab2(sch_1):page53_i43@mstr_sconn.sconn288_h44441004(chips)!SCONN288_H44441004_PIP-SCONN,HA!!!F158!VSS(60)!!!!
S!GND!J4A1!107!@baseboard_fab2_lib.baseboard_fab2(sch_1):page53_i43@mstr_sconn.sconn288_h44441004(chips)!SCONN288_H44441004_PIP-SCONN,HA!!!F158!VSS(61)!!!!
S!GND!J4A1!105!@baseboard_fab2_lib.baseboard_fab2(sch_1):page53_i43@mstr_sconn.sconn288_h44441004(chips)!SCONN288_H44441004_PIP-SCONN,HA!!!F158!VSS(62)!!!!
S!GND!J4A1!103!@baseboard_fab2_lib.baseboard_fab2(sch_1):page53_i43@mstr_sconn.sconn288_h44441004(chips)!SCONN288_H44441004_PIP-SCONN,HA!!!F158!VSS(63)!!!!
S!GND!J4A1!101!@baseboard_fab2_lib.baseboard_fab2(sch_1):page53_i43@mstr_sconn.sconn288_h44441004(chips)!SCONN288_H44441004_PIP-SCONN,HA!!!F158!VSS(64)!!!!
S!GND!J4A1!98!@baseboard_fab2_lib.baseboard_fab2(sch_1):page53_i43@mstr_sconn.sconn288_h44441004(chips)!SCONN288_H44441004_PIP-SCONN,HA!!!F158!VSS(65)!!!!
S!GND!J4A1!96!@baseboard_fab2_lib.baseboard_fab2(sch_1):page53_i43@mstr_sconn.sconn288_h44441004(chips)!SCONN288_H44441004_PIP-SCONN,HA!!!F158!VSS(66)!!!!
S!GND!J4A1!94!@baseboard_fab2_lib.baseboard_fab2(sch_1):page53_i43@mstr_sconn.sconn288_h44441004(chips)!SCONN288_H44441004_PIP-SCONN,HA!!!F158!VSS(67)!!!!
S!GND!J4A1!57!@baseboard_fab2_lib.baseboard_fab2(sch_1):page53_i43@mstr_sconn.sconn288_h44441004(chips)!SCONN288_H44441004_PIP-SCONN,HA!!!F158!VSS(68)!!!!
S!GND!J4A1!55!@baseboard_fab2_lib.baseboard_fab2(sch_1):page53_i43@mstr_sconn.sconn288_h44441004(chips)!SCONN288_H44441004_PIP-SCONN,HA!!!F158!VSS(69)!!!!
S!GND!J4A1!270!@baseboard_fab2_lib.baseboard_fab2(sch_1):page53_i43@mstr_sconn.sconn288_h44441004(chips)!SCONN288_H44441004_PIP-SCONN,HA!!!F158!VSS(6)!!!!
S!GND!J4A1!53!@baseboard_fab2_lib.baseboard_fab2(sch_1):page53_i43@mstr_sconn.sconn288_h44441004(chips)!SCONN288_H44441004_PIP-SCONN,HA!!!F158!VSS(70)!!!!
S!GND!J4A1!50!@baseboard_fab2_lib.baseboard_fab2(sch_1):page53_i43@mstr_sconn.sconn288_h44441004(chips)!SCONN288_H44441004_PIP-SCONN,HA!!!F158!VSS(71)!!!!
S!GND!J4A1!48!@baseboard_fab2_lib.baseboard_fab2(sch_1):page53_i43@mstr_sconn.sconn288_h44441004(chips)!SCONN288_H44441004_PIP-SCONN,HA!!!F158!VSS(72)!!!!
S!GND!J4A1!46!@baseboard_fab2_lib.baseboard_fab2(sch_1):page53_i43@mstr_sconn.sconn288_h44441004(chips)!SCONN288_H44441004_PIP-SCONN,HA!!!F158!VSS(73)!!!!
S!GND!J4A1!44!@baseboard_fab2_lib.baseboard_fab2(sch_1):page53_i43@mstr_sconn.sconn288_h44441004(chips)!SCONN288_H44441004_PIP-SCONN,HA!!!F158!VSS(74)!!!!
S!GND!J4A1!42!@baseboard_fab2_lib.baseboard_fab2(sch_1):page53_i43@mstr_sconn.sconn288_h44441004(chips)!SCONN288_H44441004_PIP-SCONN,HA!!!F158!VSS(75)!!!!
S!GND!J4A1!39!@baseboard_fab2_lib.baseboard_fab2(sch_1):page53_i43@mstr_sconn.sconn288_h44441004(chips)!SCONN288_H44441004_PIP-SCONN,HA!!!F158!VSS(76)!!!!
S!GND!J4A1!37!@baseboard_fab2_lib.baseboard_fab2(sch_1):page53_i43@mstr_sconn.sconn288_h44441004(chips)!SCONN288_H44441004_PIP-SCONN,HA!!!F158!VSS(77)!!!!
S!GND!J4A1!35!@baseboard_fab2_lib.baseboard_fab2(sch_1):page53_i43@mstr_sconn.sconn288_h44441004(chips)!SCONN288_H44441004_PIP-SCONN,HA!!!F158!VSS(78)!!!!
S!GND!J4A1!33!@baseboard_fab2_lib.baseboard_fab2(sch_1):page53_i43@mstr_sconn.sconn288_h44441004(chips)!SCONN288_H44441004_PIP-SCONN,HA!!!F158!VSS(79)!!!!
S!GND!J4A1!268!@baseboard_fab2_lib.baseboard_fab2(sch_1):page53_i43@mstr_sconn.sconn288_h44441004(chips)!SCONN288_H44441004_PIP-SCONN,HA!!!F158!VSS(7)!!!!
S!GND!J4A1!31!@baseboard_fab2_lib.baseboard_fab2(sch_1):page53_i43@mstr_sconn.sconn288_h44441004(chips)!SCONN288_H44441004_PIP-SCONN,HA!!!F158!VSS(80)!!!!
S!GND!J4A1!28!@baseboard_fab2_lib.baseboard_fab2(sch_1):page53_i43@mstr_sconn.sconn288_h44441004(chips)!SCONN288_H44441004_PIP-SCONN,HA!!!F158!VSS(81)!!!!
S!GND!J4A1!26!@baseboard_fab2_lib.baseboard_fab2(sch_1):page53_i43@mstr_sconn.sconn288_h44441004(chips)!SCONN288_H44441004_PIP-SCONN,HA!!!F158!VSS(82)!!!!
S!GND!J4A1!24!@baseboard_fab2_lib.baseboard_fab2(sch_1):page53_i43@mstr_sconn.sconn288_h44441004(chips)!SCONN288_H44441004_PIP-SCONN,HA!!!F158!VSS(83)!!!!
S!GND!J4A1!22!@baseboard_fab2_lib.baseboard_fab2(sch_1):page53_i43@mstr_sconn.sconn288_h44441004(chips)!SCONN288_H44441004_PIP-SCONN,HA!!!F158!VSS(84)!!!!
S!GND!J4A1!20!@baseboard_fab2_lib.baseboard_fab2(sch_1):page53_i43@mstr_sconn.sconn288_h44441004(chips)!SCONN288_H44441004_PIP-SCONN,HA!!!F158!VSS(85)!!!!
S!GND!J4A1!17!@baseboard_fab2_lib.baseboard_fab2(sch_1):page53_i43@mstr_sconn.sconn288_h44441004(chips)!SCONN288_H44441004_PIP-SCONN,HA!!!F158!VSS(86)!!!!
S!GND!J4A1!15!@baseboard_fab2_lib.baseboard_fab2(sch_1):page53_i43@mstr_sconn.sconn288_h44441004(chips)!SCONN288_H44441004_PIP-SCONN,HA!!!F158!VSS(87)!!!!
S!GND!J4A1!13!@baseboard_fab2_lib.baseboard_fab2(sch_1):page53_i43@mstr_sconn.sconn288_h44441004(chips)!SCONN288_H44441004_PIP-SCONN,HA!!!F158!VSS(88)!!!!
S!GND!J4A1!11!@baseboard_fab2_lib.baseboard_fab2(sch_1):page53_i43@mstr_sconn.sconn288_h44441004(chips)!SCONN288_H44441004_PIP-SCONN,HA!!!F158!VSS(89)!!!!
S!GND!J4A1!265!@baseboard_fab2_lib.baseboard_fab2(sch_1):page53_i43@mstr_sconn.sconn288_h44441004(chips)!SCONN288_H44441004_PIP-SCONN,HA!!!F158!VSS(8)!!!!
S!GND!J4A1!9!@baseboard_fab2_lib.baseboard_fab2(sch_1):page53_i43@mstr_sconn.sconn288_h44441004(chips)!SCONN288_H44441004_PIP-SCONN,HA!!!F158!VSS(90)!!!!
S!GND!J4A1!6!@baseboard_fab2_lib.baseboard_fab2(sch_1):page53_i43@mstr_sconn.sconn288_h44441004(chips)!SCONN288_H44441004_PIP-SCONN,HA!!!F158!VSS(91)!!!!
S!GND!J4A1!4!@baseboard_fab2_lib.baseboard_fab2(sch_1):page53_i43@mstr_sconn.sconn288_h44441004(chips)!SCONN288_H44441004_PIP-SCONN,HA!!!F158!VSS(92)!!!!
S!GND!J4A1!2!@baseboard_fab2_lib.baseboard_fab2(sch_1):page53_i43@mstr_sconn.sconn288_h44441004(chips)!SCONN288_H44441004_PIP-SCONN,HA!!!F158!VSS(93)!!!!
S!GND!J4A1!263!@baseboard_fab2_lib.baseboard_fab2(sch_1):page53_i43@mstr_sconn.sconn288_h44441004(chips)!SCONN288_H44441004_PIP-SCONN,HA!!!F158!VSS(9)!!!!
S!P12V_NVDIMM_DEF!J4A1!145!@baseboard_fab2_lib.baseboard_fab2(sch_1):page53_i171@mstr_sconn.sconn288_h44441004(chips)!SCONN288_H44441004_PIP-SCONN,HA!!!F157!\12v\(0)!!!!
S!P12V_NVDIMM_DEF!J4A1!1!@baseboard_fab2_lib.baseboard_fab2(sch_1):page53_i171@mstr_sconn.sconn288_h44441004(chips)!SCONN288_H44441004_PIP-SCONN,HA!!!F157!\12v\(1)!!!!
S!PVDDQ_DEF!J4A1!236!@baseboard_fab2_lib.baseboard_fab2(sch_1):page53_i171@mstr_sconn.sconn288_h44441004(chips)!SCONN288_H44441004_PIP-SCONN,HA!!!F157!VDD(0)!!!!
S!PVDDQ_DEF!J4A1!209!@baseboard_fab2_lib.baseboard_fab2(sch_1):page53_i171@mstr_sconn.sconn288_h44441004(chips)!SCONN288_H44441004_PIP-SCONN,HA!!!F157!VDD(10)!!!!
S!PVDDQ_DEF!J4A1!206!@baseboard_fab2_lib.baseboard_fab2(sch_1):page53_i171@mstr_sconn.sconn288_h44441004(chips)!SCONN288_H44441004_PIP-SCONN,HA!!!F157!VDD(11)!!!!
S!PVDDQ_DEF!J4A1!204!@baseboard_fab2_lib.baseboard_fab2(sch_1):page53_i171@mstr_sconn.sconn288_h44441004(chips)!SCONN288_H44441004_PIP-SCONN,HA!!!F157!VDD(12)!!!!
S!PVDDQ_DEF!J4A1!92!@baseboard_fab2_lib.baseboard_fab2(sch_1):page53_i171@mstr_sconn.sconn288_h44441004(chips)!SCONN288_H44441004_PIP-SCONN,HA!!!F157!VDD(13)!!!!
S!PVDDQ_DEF!J4A1!90!@baseboard_fab2_lib.baseboard_fab2(sch_1):page53_i171@mstr_sconn.sconn288_h44441004(chips)!SCONN288_H44441004_PIP-SCONN,HA!!!F157!VDD(14)!!!!
S!PVDDQ_DEF!J4A1!88!@baseboard_fab2_lib.baseboard_fab2(sch_1):page53_i171@mstr_sconn.sconn288_h44441004(chips)!SCONN288_H44441004_PIP-SCONN,HA!!!F157!VDD(15)!!!!
S!PVDDQ_DEF!J4A1!85!@baseboard_fab2_lib.baseboard_fab2(sch_1):page53_i171@mstr_sconn.sconn288_h44441004(chips)!SCONN288_H44441004_PIP-SCONN,HA!!!F157!VDD(16)!!!!
S!PVDDQ_DEF!J4A1!83!@baseboard_fab2_lib.baseboard_fab2(sch_1):page53_i171@mstr_sconn.sconn288_h44441004(chips)!SCONN288_H44441004_PIP-SCONN,HA!!!F157!VDD(17)!!!!
S!PVDDQ_DEF!J4A1!80!@baseboard_fab2_lib.baseboard_fab2(sch_1):page53_i171@mstr_sconn.sconn288_h44441004(chips)!SCONN288_H44441004_PIP-SCONN,HA!!!F157!VDD(18)!!!!
S!PVDDQ_DEF!J4A1!76!@baseboard_fab2_lib.baseboard_fab2(sch_1):page53_i171@mstr_sconn.sconn288_h44441004(chips)!SCONN288_H44441004_PIP-SCONN,HA!!!F157!VDD(19)!!!!
S!PVDDQ_DEF!J4A1!233!@baseboard_fab2_lib.baseboard_fab2(sch_1):page53_i171@mstr_sconn.sconn288_h44441004(chips)!SCONN288_H44441004_PIP-SCONN,HA!!!F157!VDD(1)!!!!
S!PVDDQ_DEF!J4A1!73!@baseboard_fab2_lib.baseboard_fab2(sch_1):page53_i171@mstr_sconn.sconn288_h44441004(chips)!SCONN288_H44441004_PIP-SCONN,HA!!!F157!VDD(20)!!!!
S!PVDDQ_DEF!J4A1!70!@baseboard_fab2_lib.baseboard_fab2(sch_1):page53_i171@mstr_sconn.sconn288_h44441004(chips)!SCONN288_H44441004_PIP-SCONN,HA!!!F157!VDD(21)!!!!
S!PVDDQ_DEF!J4A1!67!@baseboard_fab2_lib.baseboard_fab2(sch_1):page53_i171@mstr_sconn.sconn288_h44441004(chips)!SCONN288_H44441004_PIP-SCONN,HA!!!F157!VDD(22)!!!!
S!PVDDQ_DEF!J4A1!64!@baseboard_fab2_lib.baseboard_fab2(sch_1):page53_i171@mstr_sconn.sconn288_h44441004(chips)!SCONN288_H44441004_PIP-SCONN,HA!!!F157!VDD(23)!!!!
S!PVDDQ_DEF!J4A1!61!@baseboard_fab2_lib.baseboard_fab2(sch_1):page53_i171@mstr_sconn.sconn288_h44441004(chips)!SCONN288_H44441004_PIP-SCONN,HA!!!F157!VDD(24)!!!!
S!PVDDQ_DEF!J4A1!59!@baseboard_fab2_lib.baseboard_fab2(sch_1):page53_i171@mstr_sconn.sconn288_h44441004(chips)!SCONN288_H44441004_PIP-SCONN,HA!!!F157!VDD(25)!!!!
S!PVDDQ_DEF!J4A1!231!@baseboard_fab2_lib.baseboard_fab2(sch_1):page53_i171@mstr_sconn.sconn288_h44441004(chips)!SCONN288_H44441004_PIP-SCONN,HA!!!F157!VDD(2)!!!!
S!PVDDQ_DEF!J4A1!229!@baseboard_fab2_lib.baseboard_fab2(sch_1):page53_i171@mstr_sconn.sconn288_h44441004(chips)!SCONN288_H44441004_PIP-SCONN,HA!!!F157!VDD(3)!!!!
S!PVDDQ_DEF!J4A1!226!@baseboard_fab2_lib.baseboard_fab2(sch_1):page53_i171@mstr_sconn.sconn288_h44441004(chips)!SCONN288_H44441004_PIP-SCONN,HA!!!F157!VDD(4)!!!!
S!PVDDQ_DEF!J4A1!223!@baseboard_fab2_lib.baseboard_fab2(sch_1):page53_i171@mstr_sconn.sconn288_h44441004(chips)!SCONN288_H44441004_PIP-SCONN,HA!!!F157!VDD(5)!!!!
S!PVDDQ_DEF!J4A1!220!@baseboard_fab2_lib.baseboard_fab2(sch_1):page53_i171@mstr_sconn.sconn288_h44441004(chips)!SCONN288_H44441004_PIP-SCONN,HA!!!F157!VDD(6)!!!!
S!PVDDQ_DEF!J4A1!217!@baseboard_fab2_lib.baseboard_fab2(sch_1):page53_i171@mstr_sconn.sconn288_h44441004(chips)!SCONN288_H44441004_PIP-SCONN,HA!!!F157!VDD(7)!!!!
S!PVDDQ_DEF!J4A1!215!@baseboard_fab2_lib.baseboard_fab2(sch_1):page53_i171@mstr_sconn.sconn288_h44441004(chips)!SCONN288_H44441004_PIP-SCONN,HA!!!F157!VDD(8)!!!!
S!PVDDQ_DEF!J4A1!212!@baseboard_fab2_lib.baseboard_fab2(sch_1):page53_i171@mstr_sconn.sconn288_h44441004(chips)!SCONN288_H44441004_PIP-SCONN,HA!!!F157!VDD(9)!!!!
S!PVPP_DEF!J4A1!287!@baseboard_fab2_lib.baseboard_fab2(sch_1):page53_i171@mstr_sconn.sconn288_h44441004(chips)!SCONN288_H44441004_PIP-SCONN,HA!!!F157!VPP(0)!!!!
S!PVPP_DEF!J4A1!286!@baseboard_fab2_lib.baseboard_fab2(sch_1):page53_i171@mstr_sconn.sconn288_h44441004(chips)!SCONN288_H44441004_PIP-SCONN,HA!!!F157!VPP(1)!!!!
S!PVPP_DEF!J4A1!288!@baseboard_fab2_lib.baseboard_fab2(sch_1):page53_i171@mstr_sconn.sconn288_h44441004(chips)!SCONN288_H44441004_PIP-SCONN,HA!!!F157!VPP(2)!!!!
S!PVPP_DEF!J4A1!143!@baseboard_fab2_lib.baseboard_fab2(sch_1):page53_i171@mstr_sconn.sconn288_h44441004(chips)!SCONN288_H44441004_PIP-SCONN,HA!!!F157!VPP(3)!!!!
S!PVPP_DEF!J4A1!142!@baseboard_fab2_lib.baseboard_fab2(sch_1):page53_i171@mstr_sconn.sconn288_h44441004(chips)!SCONN288_H44441004_PIP-SCONN,HA!!!F157!VPP(4)!!!!
S!PVTT_DEF!J4A1!221!@baseboard_fab2_lib.baseboard_fab2(sch_1):page53_i171@mstr_sconn.sconn288_h44441004(chips)!SCONN288_H44441004_PIP-SCONN,HA!!!F157!VTT(0)!!!!
S!PVTT_DEF!J4A1!77!@baseboard_fab2_lib.baseboard_fab2(sch_1):page53_i171@mstr_sconn.sconn288_h44441004(chips)!SCONN288_H44441004_PIP-SCONN,HA!!!F157!VTT(1)!!!!
S!M_G_MA<0>!J1G1!79!@baseboard_fab2_lib.baseboard_fab2(sch_1):page77_i111@mstr_sconn.sconn288_h44441004(chips)!SCONN288_H44441004_PIP-SCONN,HA!!!F172!A0!!!!
S!M_G_MA<1>!J1G1!72!@baseboard_fab2_lib.baseboard_fab2(sch_1):page77_i111@mstr_sconn.sconn288_h44441004(chips)!SCONN288_H44441004_PIP-SCONN,HA!!!F172!A1!!!!
S!M_G_MA<10>!J1G1!225!@baseboard_fab2_lib.baseboard_fab2(sch_1):page77_i111@mstr_sconn.sconn288_h44441004(chips)!SCONN288_H44441004_PIP-SCONN,HA!!!F172!A10!!!!
S!M_G_MA<11>!J1G1!210!@baseboard_fab2_lib.baseboard_fab2(sch_1):page77_i111@mstr_sconn.sconn288_h44441004(chips)!SCONN288_H44441004_PIP-SCONN,HA!!!F172!A11!!!!
S!M_G_MA<12>!J1G1!65!@baseboard_fab2_lib.baseboard_fab2(sch_1):page77_i111@mstr_sconn.sconn288_h44441004(chips)!SCONN288_H44441004_PIP-SCONN,HA!!!F172!A12!!!!
S!M_G_MA<13>!J1G1!232!@baseboard_fab2_lib.baseboard_fab2(sch_1):page77_i111@mstr_sconn.sconn288_h44441004(chips)!SCONN288_H44441004_PIP-SCONN,HA!!!F172!A13!!!!
S!M_G_MA<14>!J1G1!228!@baseboard_fab2_lib.baseboard_fab2(sch_1):page77_i111@mstr_sconn.sconn288_h44441004(chips)!SCONN288_H44441004_PIP-SCONN,HA!!!F172!A14_WE_N!!!!
S!M_G_MA<15>!J1G1!86!@baseboard_fab2_lib.baseboard_fab2(sch_1):page77_i111@mstr_sconn.sconn288_h44441004(chips)!SCONN288_H44441004_PIP-SCONN,HA!!!F172!A15_CAS_N!!!!
S!M_G_MA<16>!J1G1!82!@baseboard_fab2_lib.baseboard_fab2(sch_1):page77_i111@mstr_sconn.sconn288_h44441004(chips)!SCONN288_H44441004_PIP-SCONN,HA!!!F172!A16_RAS_N!!!!
S!M_G_MA<17>!J1G1!234!@baseboard_fab2_lib.baseboard_fab2(sch_1):page77_i111@mstr_sconn.sconn288_h44441004(chips)!SCONN288_H44441004_PIP-SCONN,HA!!!F172!A17!!!!
S!M_G_MA<2>!J1G1!216!@baseboard_fab2_lib.baseboard_fab2(sch_1):page77_i111@mstr_sconn.sconn288_h44441004(chips)!SCONN288_H44441004_PIP-SCONN,HA!!!F172!A2!!!!
S!M_G_MA<3>!J1G1!71!@baseboard_fab2_lib.baseboard_fab2(sch_1):page77_i111@mstr_sconn.sconn288_h44441004(chips)!SCONN288_H44441004_PIP-SCONN,HA!!!F172!A3!!!!
S!M_G_MA<4>!J1G1!214!@baseboard_fab2_lib.baseboard_fab2(sch_1):page77_i111@mstr_sconn.sconn288_h44441004(chips)!SCONN288_H44441004_PIP-SCONN,HA!!!F172!A4!!!!
S!M_G_MA<5>!J1G1!213!@baseboard_fab2_lib.baseboard_fab2(sch_1):page77_i111@mstr_sconn.sconn288_h44441004(chips)!SCONN288_H44441004_PIP-SCONN,HA!!!F172!A5!!!!
S!M_G_MA<6>!J1G1!69!@baseboard_fab2_lib.baseboard_fab2(sch_1):page77_i111@mstr_sconn.sconn288_h44441004(chips)!SCONN288_H44441004_PIP-SCONN,HA!!!F172!A6!!!!
S!M_G_MA<7>!J1G1!211!@baseboard_fab2_lib.baseboard_fab2(sch_1):page77_i111@mstr_sconn.sconn288_h44441004(chips)!SCONN288_H44441004_PIP-SCONN,HA!!!F172!A7!!!!
S!M_G_MA<8>!J1G1!68!@baseboard_fab2_lib.baseboard_fab2(sch_1):page77_i111@mstr_sconn.sconn288_h44441004(chips)!SCONN288_H44441004_PIP-SCONN,HA!!!F172!A8!!!!
S!M_G_MA<9>!J1G1!66!@baseboard_fab2_lib.baseboard_fab2(sch_1):page77_i111@mstr_sconn.sconn288_h44441004(chips)!SCONN288_H44441004_PIP-SCONN,HA!!!F172!A9!!!!
S!M_G_ACT_N!J1G1!62!@baseboard_fab2_lib.baseboard_fab2(sch_1):page77_i111@mstr_sconn.sconn288_h44441004(chips)!SCONN288_H44441004_PIP-SCONN,HA!!!F172!ACT_N!!!!
S!M_G_ALERT_N!J1G1!208!@baseboard_fab2_lib.baseboard_fab2(sch_1):page77_i111@mstr_sconn.sconn288_h44441004(chips)!SCONN288_H44441004_PIP-SCONN,HA!!!F172!ALERT_N!!!!
S!M_G_BA<0>!J1G1!81!@baseboard_fab2_lib.baseboard_fab2(sch_1):page77_i111@mstr_sconn.sconn288_h44441004(chips)!SCONN288_H44441004_PIP-SCONN,HA!!!F172!BA(0)!!!!
S!M_G_BA<1>!J1G1!224!@baseboard_fab2_lib.baseboard_fab2(sch_1):page77_i111@mstr_sconn.sconn288_h44441004(chips)!SCONN288_H44441004_PIP-SCONN,HA!!!F172!BA(1)!!!!
S!M_G_BG<0>!J1G1!63!@baseboard_fab2_lib.baseboard_fab2(sch_1):page77_i111@mstr_sconn.sconn288_h44441004(chips)!SCONN288_H44441004_PIP-SCONN,HA!!!F172!BG(0)!!!!
S!M_G_BG<1>!J1G1!207!@baseboard_fab2_lib.baseboard_fab2(sch_1):page77_i111@mstr_sconn.sconn288_h44441004(chips)!SCONN288_H44441004_PIP-SCONN,HA!!!F172!BG(1)!!!!
S!M_G_C<2>!J1G1!235!@baseboard_fab2_lib.baseboard_fab2(sch_1):page77_i111@mstr_sconn.sconn288_h44441004(chips)!SCONN288_H44441004_PIP-SCONN,HA!!!F172!C(2)!!!!
S!M_G_ECC<1>!J1G1!49!@baseboard_fab2_lib.baseboard_fab2(sch_1):page77_i111@mstr_sconn.sconn288_h44441004(chips)!SCONN288_H44441004_PIP-SCONN,HA!!!F172!CB(0)!!!!
S!M_G_ECC<0>!J1G1!194!@baseboard_fab2_lib.baseboard_fab2(sch_1):page77_i111@mstr_sconn.sconn288_h44441004(chips)!SCONN288_H44441004_PIP-SCONN,HA!!!F172!CB(1)!!!!
S!M_G_ECC<3>!J1G1!56!@baseboard_fab2_lib.baseboard_fab2(sch_1):page77_i111@mstr_sconn.sconn288_h44441004(chips)!SCONN288_H44441004_PIP-SCONN,HA!!!F172!CB(2)!!!!
S!M_G_ECC<2>!J1G1!201!@baseboard_fab2_lib.baseboard_fab2(sch_1):page77_i111@mstr_sconn.sconn288_h44441004(chips)!SCONN288_H44441004_PIP-SCONN,HA!!!F172!CB(3)!!!!
S!M_G_ECC<5>!J1G1!47!@baseboard_fab2_lib.baseboard_fab2(sch_1):page77_i111@mstr_sconn.sconn288_h44441004(chips)!SCONN288_H44441004_PIP-SCONN,HA!!!F172!CB(4)!!!!
S!M_G_ECC<4>!J1G1!192!@baseboard_fab2_lib.baseboard_fab2(sch_1):page77_i111@mstr_sconn.sconn288_h44441004(chips)!SCONN288_H44441004_PIP-SCONN,HA!!!F172!CB(5)!!!!
S!M_G_ECC<7>!J1G1!54!@baseboard_fab2_lib.baseboard_fab2(sch_1):page77_i111@mstr_sconn.sconn288_h44441004(chips)!SCONN288_H44441004_PIP-SCONN,HA!!!F172!CB(6)!!!!
S!M_G_ECC<6>!J1G1!199!@baseboard_fab2_lib.baseboard_fab2(sch_1):page77_i111@mstr_sconn.sconn288_h44441004(chips)!SCONN288_H44441004_PIP-SCONN,HA!!!F172!CB(7)!!!!
S!M_G_CLK_DN<0>!J1G1!75!@baseboard_fab2_lib.baseboard_fab2(sch_1):page77_i111@mstr_sconn.sconn288_h44441004(chips)!SCONN288_H44441004_PIP-SCONN,HA!!!F172!CK0N!!!!
S!M_G_CLK_DP<0>!J1G1!74!@baseboard_fab2_lib.baseboard_fab2(sch_1):page77_i111@mstr_sconn.sconn288_h44441004(chips)!SCONN288_H44441004_PIP-SCONN,HA!!!F172!CK0P!!!!
S!M_G_CLK_DN<1>!J1G1!219!@baseboard_fab2_lib.baseboard_fab2(sch_1):page77_i111@mstr_sconn.sconn288_h44441004(chips)!SCONN288_H44441004_PIP-SCONN,HA!!!F172!CK1N!!!!
S!M_G_CLK_DP<1>!J1G1!218!@baseboard_fab2_lib.baseboard_fab2(sch_1):page77_i111@mstr_sconn.sconn288_h44441004(chips)!SCONN288_H44441004_PIP-SCONN,HA!!!F172!CK1P!!!!
S!M_G_CKE<0>!J1G1!60!@baseboard_fab2_lib.baseboard_fab2(sch_1):page77_i111@mstr_sconn.sconn288_h44441004(chips)!SCONN288_H44441004_PIP-SCONN,HA!!!F172!CKE(0)!!!!
S!M_G_CKE<1>!J1G1!203!@baseboard_fab2_lib.baseboard_fab2(sch_1):page77_i111@mstr_sconn.sconn288_h44441004(chips)!SCONN288_H44441004_PIP-SCONN,HA!!!F172!CKE(1)!!!!
S!M_G_DQ<1>!J1G1!5!@baseboard_fab2_lib.baseboard_fab2(sch_1):page77_i111@mstr_sconn.sconn288_h44441004(chips)!SCONN288_H44441004_PIP-SCONN,HA!!!F172!DQ(0)!!!!
S!M_G_DQ<11>!J1G1!23!@baseboard_fab2_lib.baseboard_fab2(sch_1):page77_i111@mstr_sconn.sconn288_h44441004(chips)!SCONN288_H44441004_PIP-SCONN,HA!!!F172!DQ(10)!!!!
S!M_G_DQ<10>!J1G1!168!@baseboard_fab2_lib.baseboard_fab2(sch_1):page77_i111@mstr_sconn.sconn288_h44441004(chips)!SCONN288_H44441004_PIP-SCONN,HA!!!F172!DQ(11)!!!!
S!M_G_DQ<13>!J1G1!14!@baseboard_fab2_lib.baseboard_fab2(sch_1):page77_i111@mstr_sconn.sconn288_h44441004(chips)!SCONN288_H44441004_PIP-SCONN,HA!!!F172!DQ(12)!!!!
S!M_G_DQ<12>!J1G1!159!@baseboard_fab2_lib.baseboard_fab2(sch_1):page77_i111@mstr_sconn.sconn288_h44441004(chips)!SCONN288_H44441004_PIP-SCONN,HA!!!F172!DQ(13)!!!!
S!M_G_DQ<15>!J1G1!21!@baseboard_fab2_lib.baseboard_fab2(sch_1):page77_i111@mstr_sconn.sconn288_h44441004(chips)!SCONN288_H44441004_PIP-SCONN,HA!!!F172!DQ(14)!!!!
S!M_G_DQ<14>!J1G1!166!@baseboard_fab2_lib.baseboard_fab2(sch_1):page77_i111@mstr_sconn.sconn288_h44441004(chips)!SCONN288_H44441004_PIP-SCONN,HA!!!F172!DQ(15)!!!!
S!M_G_DQ<17>!J1G1!27!@baseboard_fab2_lib.baseboard_fab2(sch_1):page77_i111@mstr_sconn.sconn288_h44441004(chips)!SCONN288_H44441004_PIP-SCONN,HA!!!F172!DQ(16)!!!!
S!M_G_DQ<16>!J1G1!172!@baseboard_fab2_lib.baseboard_fab2(sch_1):page77_i111@mstr_sconn.sconn288_h44441004(chips)!SCONN288_H44441004_PIP-SCONN,HA!!!F172!DQ(17)!!!!
S!M_G_DQ<19>!J1G1!34!@baseboard_fab2_lib.baseboard_fab2(sch_1):page77_i111@mstr_sconn.sconn288_h44441004(chips)!SCONN288_H44441004_PIP-SCONN,HA!!!F172!DQ(18)!!!!
S!M_G_DQ<18>!J1G1!179!@baseboard_fab2_lib.baseboard_fab2(sch_1):page77_i111@mstr_sconn.sconn288_h44441004(chips)!SCONN288_H44441004_PIP-SCONN,HA!!!F172!DQ(19)!!!!
S!M_G_DQ<0>!J1G1!150!@baseboard_fab2_lib.baseboard_fab2(sch_1):page77_i111@mstr_sconn.sconn288_h44441004(chips)!SCONN288_H44441004_PIP-SCONN,HA!!!F172!DQ(1)!!!!
S!M_G_DQ<21>!J1G1!25!@baseboard_fab2_lib.baseboard_fab2(sch_1):page77_i111@mstr_sconn.sconn288_h44441004(chips)!SCONN288_H44441004_PIP-SCONN,HA!!!F172!DQ(20)!!!!
S!M_G_DQ<20>!J1G1!170!@baseboard_fab2_lib.baseboard_fab2(sch_1):page77_i111@mstr_sconn.sconn288_h44441004(chips)!SCONN288_H44441004_PIP-SCONN,HA!!!F172!DQ(21)!!!!
S!M_G_DQ<23>!J1G1!32!@baseboard_fab2_lib.baseboard_fab2(sch_1):page77_i111@mstr_sconn.sconn288_h44441004(chips)!SCONN288_H44441004_PIP-SCONN,HA!!!F172!DQ(22)!!!!
S!M_G_DQ<22>!J1G1!177!@baseboard_fab2_lib.baseboard_fab2(sch_1):page77_i111@mstr_sconn.sconn288_h44441004(chips)!SCONN288_H44441004_PIP-SCONN,HA!!!F172!DQ(23)!!!!
S!M_G_DQ<25>!J1G1!38!@baseboard_fab2_lib.baseboard_fab2(sch_1):page77_i111@mstr_sconn.sconn288_h44441004(chips)!SCONN288_H44441004_PIP-SCONN,HA!!!F172!DQ(24)!!!!
S!M_G_DQ<24>!J1G1!183!@baseboard_fab2_lib.baseboard_fab2(sch_1):page77_i111@mstr_sconn.sconn288_h44441004(chips)!SCONN288_H44441004_PIP-SCONN,HA!!!F172!DQ(25)!!!!
S!M_G_DQ<27>!J1G1!45!@baseboard_fab2_lib.baseboard_fab2(sch_1):page77_i111@mstr_sconn.sconn288_h44441004(chips)!SCONN288_H44441004_PIP-SCONN,HA!!!F172!DQ(26)!!!!
S!M_G_DQ<26>!J1G1!190!@baseboard_fab2_lib.baseboard_fab2(sch_1):page77_i111@mstr_sconn.sconn288_h44441004(chips)!SCONN288_H44441004_PIP-SCONN,HA!!!F172!DQ(27)!!!!
S!M_G_DQ<29>!J1G1!36!@baseboard_fab2_lib.baseboard_fab2(sch_1):page77_i111@mstr_sconn.sconn288_h44441004(chips)!SCONN288_H44441004_PIP-SCONN,HA!!!F172!DQ(28)!!!!
S!M_G_DQ<28>!J1G1!181!@baseboard_fab2_lib.baseboard_fab2(sch_1):page77_i111@mstr_sconn.sconn288_h44441004(chips)!SCONN288_H44441004_PIP-SCONN,HA!!!F172!DQ(29)!!!!
S!M_G_DQ<3>!J1G1!12!@baseboard_fab2_lib.baseboard_fab2(sch_1):page77_i111@mstr_sconn.sconn288_h44441004(chips)!SCONN288_H44441004_PIP-SCONN,HA!!!F172!DQ(2)!!!!
S!M_G_DQ<31>!J1G1!43!@baseboard_fab2_lib.baseboard_fab2(sch_1):page77_i111@mstr_sconn.sconn288_h44441004(chips)!SCONN288_H44441004_PIP-SCONN,HA!!!F172!DQ(30)!!!!
S!M_G_DQ<30>!J1G1!188!@baseboard_fab2_lib.baseboard_fab2(sch_1):page77_i111@mstr_sconn.sconn288_h44441004(chips)!SCONN288_H44441004_PIP-SCONN,HA!!!F172!DQ(31)!!!!
S!M_G_DQ<33>!J1G1!97!@baseboard_fab2_lib.baseboard_fab2(sch_1):page77_i111@mstr_sconn.sconn288_h44441004(chips)!SCONN288_H44441004_PIP-SCONN,HA!!!F172!DQ(32)!!!!
S!M_G_DQ<32>!J1G1!242!@baseboard_fab2_lib.baseboard_fab2(sch_1):page77_i111@mstr_sconn.sconn288_h44441004(chips)!SCONN288_H44441004_PIP-SCONN,HA!!!F172!DQ(33)!!!!
S!M_G_DQ<35>!J1G1!104!@baseboard_fab2_lib.baseboard_fab2(sch_1):page77_i111@mstr_sconn.sconn288_h44441004(chips)!SCONN288_H44441004_PIP-SCONN,HA!!!F172!DQ(34)!!!!
S!M_G_DQ<34>!J1G1!249!@baseboard_fab2_lib.baseboard_fab2(sch_1):page77_i111@mstr_sconn.sconn288_h44441004(chips)!SCONN288_H44441004_PIP-SCONN,HA!!!F172!DQ(35)!!!!
S!M_G_DQ<37>!J1G1!95!@baseboard_fab2_lib.baseboard_fab2(sch_1):page77_i111@mstr_sconn.sconn288_h44441004(chips)!SCONN288_H44441004_PIP-SCONN,HA!!!F172!DQ(36)!!!!
S!M_G_DQ<36>!J1G1!240!@baseboard_fab2_lib.baseboard_fab2(sch_1):page77_i111@mstr_sconn.sconn288_h44441004(chips)!SCONN288_H44441004_PIP-SCONN,HA!!!F172!DQ(37)!!!!
S!M_G_DQ<39>!J1G1!102!@baseboard_fab2_lib.baseboard_fab2(sch_1):page77_i111@mstr_sconn.sconn288_h44441004(chips)!SCONN288_H44441004_PIP-SCONN,HA!!!F172!DQ(38)!!!!
S!M_G_DQ<38>!J1G1!247!@baseboard_fab2_lib.baseboard_fab2(sch_1):page77_i111@mstr_sconn.sconn288_h44441004(chips)!SCONN288_H44441004_PIP-SCONN,HA!!!F172!DQ(39)!!!!
S!M_G_DQ<2>!J1G1!157!@baseboard_fab2_lib.baseboard_fab2(sch_1):page77_i111@mstr_sconn.sconn288_h44441004(chips)!SCONN288_H44441004_PIP-SCONN,HA!!!F172!DQ(3)!!!!
S!M_G_DQ<41>!J1G1!108!@baseboard_fab2_lib.baseboard_fab2(sch_1):page77_i111@mstr_sconn.sconn288_h44441004(chips)!SCONN288_H44441004_PIP-SCONN,HA!!!F172!DQ(40)!!!!
S!M_G_DQ<40>!J1G1!253!@baseboard_fab2_lib.baseboard_fab2(sch_1):page77_i111@mstr_sconn.sconn288_h44441004(chips)!SCONN288_H44441004_PIP-SCONN,HA!!!F172!DQ(41)!!!!
S!M_G_DQ<43>!J1G1!115!@baseboard_fab2_lib.baseboard_fab2(sch_1):page77_i111@mstr_sconn.sconn288_h44441004(chips)!SCONN288_H44441004_PIP-SCONN,HA!!!F172!DQ(42)!!!!
S!M_G_DQ<42>!J1G1!260!@baseboard_fab2_lib.baseboard_fab2(sch_1):page77_i111@mstr_sconn.sconn288_h44441004(chips)!SCONN288_H44441004_PIP-SCONN,HA!!!F172!DQ(43)!!!!
S!M_G_DQ<45>!J1G1!106!@baseboard_fab2_lib.baseboard_fab2(sch_1):page77_i111@mstr_sconn.sconn288_h44441004(chips)!SCONN288_H44441004_PIP-SCONN,HA!!!F172!DQ(44)!!!!
S!M_G_DQ<44>!J1G1!251!@baseboard_fab2_lib.baseboard_fab2(sch_1):page77_i111@mstr_sconn.sconn288_h44441004(chips)!SCONN288_H44441004_PIP-SCONN,HA!!!F172!DQ(45)!!!!
S!M_G_DQ<47>!J1G1!113!@baseboard_fab2_lib.baseboard_fab2(sch_1):page77_i111@mstr_sconn.sconn288_h44441004(chips)!SCONN288_H44441004_PIP-SCONN,HA!!!F172!DQ(46)!!!!
S!M_G_DQ<46>!J1G1!258!@baseboard_fab2_lib.baseboard_fab2(sch_1):page77_i111@mstr_sconn.sconn288_h44441004(chips)!SCONN288_H44441004_PIP-SCONN,HA!!!F172!DQ(47)!!!!
S!M_G_DQ<49>!J1G1!119!@baseboard_fab2_lib.baseboard_fab2(sch_1):page77_i111@mstr_sconn.sconn288_h44441004(chips)!SCONN288_H44441004_PIP-SCONN,HA!!!F172!DQ(48)!!!!
S!M_G_DQ<48>!J1G1!264!@baseboard_fab2_lib.baseboard_fab2(sch_1):page77_i111@mstr_sconn.sconn288_h44441004(chips)!SCONN288_H44441004_PIP-SCONN,HA!!!F172!DQ(49)!!!!
S!M_G_DQ<5>!J1G1!3!@baseboard_fab2_lib.baseboard_fab2(sch_1):page77_i111@mstr_sconn.sconn288_h44441004(chips)!SCONN288_H44441004_PIP-SCONN,HA!!!F172!DQ(4)!!!!
S!M_G_DQ<51>!J1G1!126!@baseboard_fab2_lib.baseboard_fab2(sch_1):page77_i111@mstr_sconn.sconn288_h44441004(chips)!SCONN288_H44441004_PIP-SCONN,HA!!!F172!DQ(50)!!!!
S!M_G_DQ<50>!J1G1!271!@baseboard_fab2_lib.baseboard_fab2(sch_1):page77_i111@mstr_sconn.sconn288_h44441004(chips)!SCONN288_H44441004_PIP-SCONN,HA!!!F172!DQ(51)!!!!
S!M_G_DQ<53>!J1G1!117!@baseboard_fab2_lib.baseboard_fab2(sch_1):page77_i111@mstr_sconn.sconn288_h44441004(chips)!SCONN288_H44441004_PIP-SCONN,HA!!!F172!DQ(52)!!!!
S!M_G_DQ<52>!J1G1!262!@baseboard_fab2_lib.baseboard_fab2(sch_1):page77_i111@mstr_sconn.sconn288_h44441004(chips)!SCONN288_H44441004_PIP-SCONN,HA!!!F172!DQ(53)!!!!
S!M_G_DQ<55>!J1G1!124!@baseboard_fab2_lib.baseboard_fab2(sch_1):page77_i111@mstr_sconn.sconn288_h44441004(chips)!SCONN288_H44441004_PIP-SCONN,HA!!!F172!DQ(54)!!!!
S!M_G_DQ<54>!J1G1!269!@baseboard_fab2_lib.baseboard_fab2(sch_1):page77_i111@mstr_sconn.sconn288_h44441004(chips)!SCONN288_H44441004_PIP-SCONN,HA!!!F172!DQ(55)!!!!
S!M_G_DQ<57>!J1G1!130!@baseboard_fab2_lib.baseboard_fab2(sch_1):page77_i111@mstr_sconn.sconn288_h44441004(chips)!SCONN288_H44441004_PIP-SCONN,HA!!!F172!DQ(56)!!!!
S!M_G_DQ<56>!J1G1!275!@baseboard_fab2_lib.baseboard_fab2(sch_1):page77_i111@mstr_sconn.sconn288_h44441004(chips)!SCONN288_H44441004_PIP-SCONN,HA!!!F172!DQ(57)!!!!
S!M_G_DQ<59>!J1G1!137!@baseboard_fab2_lib.baseboard_fab2(sch_1):page77_i111@mstr_sconn.sconn288_h44441004(chips)!SCONN288_H44441004_PIP-SCONN,HA!!!F172!DQ(58)!!!!
S!M_G_DQ<58>!J1G1!282!@baseboard_fab2_lib.baseboard_fab2(sch_1):page77_i111@mstr_sconn.sconn288_h44441004(chips)!SCONN288_H44441004_PIP-SCONN,HA!!!F172!DQ(59)!!!!
S!M_G_DQ<4>!J1G1!148!@baseboard_fab2_lib.baseboard_fab2(sch_1):page77_i111@mstr_sconn.sconn288_h44441004(chips)!SCONN288_H44441004_PIP-SCONN,HA!!!F172!DQ(5)!!!!
S!M_G_DQ<61>!J1G1!128!@baseboard_fab2_lib.baseboard_fab2(sch_1):page77_i111@mstr_sconn.sconn288_h44441004(chips)!SCONN288_H44441004_PIP-SCONN,HA!!!F172!DQ(60)!!!!
S!M_G_DQ<60>!J1G1!273!@baseboard_fab2_lib.baseboard_fab2(sch_1):page77_i111@mstr_sconn.sconn288_h44441004(chips)!SCONN288_H44441004_PIP-SCONN,HA!!!F172!DQ(61)!!!!
S!M_G_DQ<63>!J1G1!135!@baseboard_fab2_lib.baseboard_fab2(sch_1):page77_i111@mstr_sconn.sconn288_h44441004(chips)!SCONN288_H44441004_PIP-SCONN,HA!!!F172!DQ(62)!!!!
S!M_G_DQ<62>!J1G1!280!@baseboard_fab2_lib.baseboard_fab2(sch_1):page77_i111@mstr_sconn.sconn288_h44441004(chips)!SCONN288_H44441004_PIP-SCONN,HA!!!F172!DQ(63)!!!!
S!M_G_DQ<7>!J1G1!10!@baseboard_fab2_lib.baseboard_fab2(sch_1):page77_i111@mstr_sconn.sconn288_h44441004(chips)!SCONN288_H44441004_PIP-SCONN,HA!!!F172!DQ(6)!!!!
S!M_G_DQ<6>!J1G1!155!@baseboard_fab2_lib.baseboard_fab2(sch_1):page77_i111@mstr_sconn.sconn288_h44441004(chips)!SCONN288_H44441004_PIP-SCONN,HA!!!F172!DQ(7)!!!!
S!M_G_DQ<9>!J1G1!16!@baseboard_fab2_lib.baseboard_fab2(sch_1):page77_i111@mstr_sconn.sconn288_h44441004(chips)!SCONN288_H44441004_PIP-SCONN,HA!!!F172!DQ(8)!!!!
S!M_G_DQ<8>!J1G1!161!@baseboard_fab2_lib.baseboard_fab2(sch_1):page77_i111@mstr_sconn.sconn288_h44441004(chips)!SCONN288_H44441004_PIP-SCONN,HA!!!F172!DQ(9)!!!!
S!FM_DIMM_EVENT_COD_N!J1G1!78!@baseboard_fab2_lib.baseboard_fab2(sch_1):page77_i111@mstr_sconn.sconn288_h44441004(chips)!SCONN288_H44441004_PIP-SCONN,HA!!!F172!EVENT_N!!!!
S!M_G_ODT<0>!J1G1!87!@baseboard_fab2_lib.baseboard_fab2(sch_1):page77_i111@mstr_sconn.sconn288_h44441004(chips)!SCONN288_H44441004_PIP-SCONN,HA!!!F172!ODT(0)!!!!
S!M_G_ODT<1>!J1G1!91!@baseboard_fab2_lib.baseboard_fab2(sch_1):page77_i111@mstr_sconn.sconn288_h44441004(chips)!SCONN288_H44441004_PIP-SCONN,HA!!!F172!ODT(1)!!!!
S!M_G_PAR!J1G1!222!@baseboard_fab2_lib.baseboard_fab2(sch_1):page77_i111@mstr_sconn.sconn288_h44441004(chips)!SCONN288_H44441004_PIP-SCONN,HA!!!F172!PAR!!!!
S!M_GHJ_RST_N!J1G1!58!@baseboard_fab2_lib.baseboard_fab2(sch_1):page77_i111@mstr_sconn.sconn288_h44441004(chips)!SCONN288_H44441004_PIP-SCONN,HA!!!F172!RESET_N!!!!
S!TP_CH_G_DIMM_G0_RFU_0!J1G1!205!@baseboard_fab2_lib.baseboard_fab2(sch_1):page77_i111@mstr_sconn.sconn288_h44441004(chips)!SCONN288_H44441004_PIP-SCONN,HA!!!F172!RFU(0)!!!!
S!TP_CH_G_DIMM_G0_RFU_1!J1G1!227!@baseboard_fab2_lib.baseboard_fab2(sch_1):page77_i111@mstr_sconn.sconn288_h44441004(chips)!SCONN288_H44441004_PIP-SCONN,HA!!!F172!RFU(1)!!!!
S!TP_CH_G_DIMM_G0_RFU_2!J1G1!144!@baseboard_fab2_lib.baseboard_fab2(sch_1):page77_i111@mstr_sconn.sconn288_h44441004(chips)!SCONN288_H44441004_PIP-SCONN,HA!!!F172!RFU(2)!!!!
S!M_G_CS_N<0>!J1G1!84!@baseboard_fab2_lib.baseboard_fab2(sch_1):page77_i111@mstr_sconn.sconn288_h44441004(chips)!SCONN288_H44441004_PIP-SCONN,HA!!!F172!S0_N!!!!
S!M_G_CS_N<1>!J1G1!89!@baseboard_fab2_lib.baseboard_fab2(sch_1):page77_i111@mstr_sconn.sconn288_h44441004(chips)!SCONN288_H44441004_PIP-SCONN,HA!!!F172!S1_N!!!!
S!M_G_CS_N<2>!J1G1!93!@baseboard_fab2_lib.baseboard_fab2(sch_1):page77_i111@mstr_sconn.sconn288_h44441004(chips)!SCONN288_H44441004_PIP-SCONN,HA!!!F172!S2_N_C(0)!!!!
S!M_G_CS_N<3>!J1G1!237!@baseboard_fab2_lib.baseboard_fab2(sch_1):page77_i111@mstr_sconn.sconn288_h44441004(chips)!SCONN288_H44441004_PIP-SCONN,HA!!!F172!S3_N_C(1)!!!!
S!GND!J1G1!139!@baseboard_fab2_lib.baseboard_fab2(sch_1):page77_i111@mstr_sconn.sconn288_h44441004(chips)!SCONN288_H44441004_PIP-SCONN,HA!!!F172!SA(0)!!!!
S!GND!J1G1!140!@baseboard_fab2_lib.baseboard_fab2(sch_1):page77_i111@mstr_sconn.sconn288_h44441004(chips)!SCONN288_H44441004_PIP-SCONN,HA!!!F172!SA(1)!!!!
S!GND!J1G1!238!@baseboard_fab2_lib.baseboard_fab2(sch_1):page77_i111@mstr_sconn.sconn288_h44441004(chips)!SCONN288_H44441004_PIP-SCONN,HA!!!F172!SA(2)!!!!
S!FM_ADR_COMPLETE_GHJ_N!J1G1!230!@baseboard_fab2_lib.baseboard_fab2(sch_1):page77_i111@mstr_sconn.sconn288_h44441004(chips)!SCONN288_H44441004_PIP-SCONN,HA!!!F172!SAVE_N_NC!!!!
S!SMB_DDR_GHJ_VPP_SCL!J1G1!141!@baseboard_fab2_lib.baseboard_fab2(sch_1):page77_i111@mstr_sconn.sconn288_h44441004(chips)!SCONN288_H44441004_PIP-SCONN,HA!!!F172!SCL!!!!
S!SMB_DDR_GHJ_VPP_SDA!J1G1!285!@baseboard_fab2_lib.baseboard_fab2(sch_1):page77_i111@mstr_sconn.sconn288_h44441004(chips)!SCONN288_H44441004_PIP-SCONN,HA!!!F172!SDA!!!!
S!PVPP_GHJ!J1G1!284!@baseboard_fab2_lib.baseboard_fab2(sch_1):page77_i111@mstr_sconn.sconn288_h44441004(chips)!SCONN288_H44441004_PIP-SCONN,HA!!!F172!VDDSPD!!!!
S!M_G_VREF!J1G1!146!@baseboard_fab2_lib.baseboard_fab2(sch_1):page77_i111@mstr_sconn.sconn288_h44441004(chips)!SCONN288_H44441004_PIP-SCONN,HA!!!F172!VREFCA!!!!
S!M_G_DQS_DN<0>!J1G1!152!@baseboard_fab2_lib.baseboard_fab2(sch_1):page77_i66@mstr_sconn.sconn288_h44441004(chips)!SCONN288_H44441004_PIP-SCONN,HA!!!F171!DQS0N!!!!
S!M_G_DQS_DP<0>!J1G1!153!@baseboard_fab2_lib.baseboard_fab2(sch_1):page77_i66@mstr_sconn.sconn288_h44441004(chips)!SCONN288_H44441004_PIP-SCONN,HA!!!F171!DQS0P!!!!
S!M_G_DQS_DN<10>!J1G1!19!@baseboard_fab2_lib.baseboard_fab2(sch_1):page77_i66@mstr_sconn.sconn288_h44441004(chips)!SCONN288_H44441004_PIP-SCONN,HA!!!F171!DQS10N!!!!
S!M_G_DQS_DP<10>!J1G1!18!@baseboard_fab2_lib.baseboard_fab2(sch_1):page77_i66@mstr_sconn.sconn288_h44441004(chips)!SCONN288_H44441004_PIP-SCONN,HA!!!F171!DQS10P!!!!
S!M_G_DQS_DN<11>!J1G1!30!@baseboard_fab2_lib.baseboard_fab2(sch_1):page77_i66@mstr_sconn.sconn288_h44441004(chips)!SCONN288_H44441004_PIP-SCONN,HA!!!F171!DQS11N!!!!
S!M_G_DQS_DP<11>!J1G1!29!@baseboard_fab2_lib.baseboard_fab2(sch_1):page77_i66@mstr_sconn.sconn288_h44441004(chips)!SCONN288_H44441004_PIP-SCONN,HA!!!F171!DQS11P!!!!
S!M_G_DQS_DN<12>!J1G1!41!@baseboard_fab2_lib.baseboard_fab2(sch_1):page77_i66@mstr_sconn.sconn288_h44441004(chips)!SCONN288_H44441004_PIP-SCONN,HA!!!F171!DQS12N!!!!
S!M_G_DQS_DP<12>!J1G1!40!@baseboard_fab2_lib.baseboard_fab2(sch_1):page77_i66@mstr_sconn.sconn288_h44441004(chips)!SCONN288_H44441004_PIP-SCONN,HA!!!F171!DQS12P!!!!
S!M_G_DQS_DN<13>!J1G1!100!@baseboard_fab2_lib.baseboard_fab2(sch_1):page77_i66@mstr_sconn.sconn288_h44441004(chips)!SCONN288_H44441004_PIP-SCONN,HA!!!F171!DQS13N!!!!
S!M_G_DQS_DP<13>!J1G1!99!@baseboard_fab2_lib.baseboard_fab2(sch_1):page77_i66@mstr_sconn.sconn288_h44441004(chips)!SCONN288_H44441004_PIP-SCONN,HA!!!F171!DQS13P!!!!
S!M_G_DQS_DN<14>!J1G1!111!@baseboard_fab2_lib.baseboard_fab2(sch_1):page77_i66@mstr_sconn.sconn288_h44441004(chips)!SCONN288_H44441004_PIP-SCONN,HA!!!F171!DQS14N!!!!
S!M_G_DQS_DP<14>!J1G1!110!@baseboard_fab2_lib.baseboard_fab2(sch_1):page77_i66@mstr_sconn.sconn288_h44441004(chips)!SCONN288_H44441004_PIP-SCONN,HA!!!F171!DQS14P!!!!
S!M_G_DQS_DN<15>!J1G1!122!@baseboard_fab2_lib.baseboard_fab2(sch_1):page77_i66@mstr_sconn.sconn288_h44441004(chips)!SCONN288_H44441004_PIP-SCONN,HA!!!F171!DQS15N!!!!
S!M_G_DQS_DP<15>!J1G1!121!@baseboard_fab2_lib.baseboard_fab2(sch_1):page77_i66@mstr_sconn.sconn288_h44441004(chips)!SCONN288_H44441004_PIP-SCONN,HA!!!F171!DQS15P!!!!
S!M_G_DQS_DN<16>!J1G1!133!@baseboard_fab2_lib.baseboard_fab2(sch_1):page77_i66@mstr_sconn.sconn288_h44441004(chips)!SCONN288_H44441004_PIP-SCONN,HA!!!F171!DQS16N!!!!
S!M_G_DQS_DP<16>!J1G1!132!@baseboard_fab2_lib.baseboard_fab2(sch_1):page77_i66@mstr_sconn.sconn288_h44441004(chips)!SCONN288_H44441004_PIP-SCONN,HA!!!F171!DQS16P!!!!
S!M_G_DQS_DN<17>!J1G1!52!@baseboard_fab2_lib.baseboard_fab2(sch_1):page77_i66@mstr_sconn.sconn288_h44441004(chips)!SCONN288_H44441004_PIP-SCONN,HA!!!F171!DQS17N!!!!
S!M_G_DQS_DP<17>!J1G1!51!@baseboard_fab2_lib.baseboard_fab2(sch_1):page77_i66@mstr_sconn.sconn288_h44441004(chips)!SCONN288_H44441004_PIP-SCONN,HA!!!F171!DQS17P!!!!
S!M_G_DQS_DN<1>!J1G1!163!@baseboard_fab2_lib.baseboard_fab2(sch_1):page77_i66@mstr_sconn.sconn288_h44441004(chips)!SCONN288_H44441004_PIP-SCONN,HA!!!F171!DQS1N!!!!
S!M_G_DQS_DP<1>!J1G1!164!@baseboard_fab2_lib.baseboard_fab2(sch_1):page77_i66@mstr_sconn.sconn288_h44441004(chips)!SCONN288_H44441004_PIP-SCONN,HA!!!F171!DQS1P!!!!
S!M_G_DQS_DN<2>!J1G1!174!@baseboard_fab2_lib.baseboard_fab2(sch_1):page77_i66@mstr_sconn.sconn288_h44441004(chips)!SCONN288_H44441004_PIP-SCONN,HA!!!F171!DQS2N!!!!
S!M_G_DQS_DP<2>!J1G1!175!@baseboard_fab2_lib.baseboard_fab2(sch_1):page77_i66@mstr_sconn.sconn288_h44441004(chips)!SCONN288_H44441004_PIP-SCONN,HA!!!F171!DQS2P!!!!
S!M_G_DQS_DN<3>!J1G1!185!@baseboard_fab2_lib.baseboard_fab2(sch_1):page77_i66@mstr_sconn.sconn288_h44441004(chips)!SCONN288_H44441004_PIP-SCONN,HA!!!F171!DQS3N!!!!
S!M_G_DQS_DP<3>!J1G1!186!@baseboard_fab2_lib.baseboard_fab2(sch_1):page77_i66@mstr_sconn.sconn288_h44441004(chips)!SCONN288_H44441004_PIP-SCONN,HA!!!F171!DQS3P!!!!
S!M_G_DQS_DN<4>!J1G1!244!@baseboard_fab2_lib.baseboard_fab2(sch_1):page77_i66@mstr_sconn.sconn288_h44441004(chips)!SCONN288_H44441004_PIP-SCONN,HA!!!F171!DQS4N!!!!
S!M_G_DQS_DP<4>!J1G1!245!@baseboard_fab2_lib.baseboard_fab2(sch_1):page77_i66@mstr_sconn.sconn288_h44441004(chips)!SCONN288_H44441004_PIP-SCONN,HA!!!F171!DQS4P!!!!
S!M_G_DQS_DN<5>!J1G1!255!@baseboard_fab2_lib.baseboard_fab2(sch_1):page77_i66@mstr_sconn.sconn288_h44441004(chips)!SCONN288_H44441004_PIP-SCONN,HA!!!F171!DQS5N!!!!
S!M_G_DQS_DP<5>!J1G1!256!@baseboard_fab2_lib.baseboard_fab2(sch_1):page77_i66@mstr_sconn.sconn288_h44441004(chips)!SCONN288_H44441004_PIP-SCONN,HA!!!F171!DQS5P!!!!
S!M_G_DQS_DN<6>!J1G1!266!@baseboard_fab2_lib.baseboard_fab2(sch_1):page77_i66@mstr_sconn.sconn288_h44441004(chips)!SCONN288_H44441004_PIP-SCONN,HA!!!F171!DQS6N!!!!
S!M_G_DQS_DP<6>!J1G1!267!@baseboard_fab2_lib.baseboard_fab2(sch_1):page77_i66@mstr_sconn.sconn288_h44441004(chips)!SCONN288_H44441004_PIP-SCONN,HA!!!F171!DQS6P!!!!
S!M_G_DQS_DN<7>!J1G1!277!@baseboard_fab2_lib.baseboard_fab2(sch_1):page77_i66@mstr_sconn.sconn288_h44441004(chips)!SCONN288_H44441004_PIP-SCONN,HA!!!F171!DQS7N!!!!
S!M_G_DQS_DP<7>!J1G1!278!@baseboard_fab2_lib.baseboard_fab2(sch_1):page77_i66@mstr_sconn.sconn288_h44441004(chips)!SCONN288_H44441004_PIP-SCONN,HA!!!F171!DQS7P!!!!
S!M_G_DQS_DN<8>!J1G1!196!@baseboard_fab2_lib.baseboard_fab2(sch_1):page77_i66@mstr_sconn.sconn288_h44441004(chips)!SCONN288_H44441004_PIP-SCONN,HA!!!F171!DQS8N!!!!
S!M_G_DQS_DP<8>!J1G1!197!@baseboard_fab2_lib.baseboard_fab2(sch_1):page77_i66@mstr_sconn.sconn288_h44441004(chips)!SCONN288_H44441004_PIP-SCONN,HA!!!F171!DQS8P!!!!
S!M_G_DQS_DN<9>!J1G1!8!@baseboard_fab2_lib.baseboard_fab2(sch_1):page77_i66@mstr_sconn.sconn288_h44441004(chips)!SCONN288_H44441004_PIP-SCONN,HA!!!F171!DQS9N!!!!
S!M_G_DQS_DP<9>!J1G1!7!@baseboard_fab2_lib.baseboard_fab2(sch_1):page77_i66@mstr_sconn.sconn288_h44441004(chips)!SCONN288_H44441004_PIP-SCONN,HA!!!F171!DQS9P!!!!
S!GND!J1G1!283!@baseboard_fab2_lib.baseboard_fab2(sch_1):page77_i43@mstr_sconn.sconn288_h44441004(chips)!SCONN288_H44441004_PIP-SCONN,HA!!!F170!VSS(0)!!!!
S!GND!J1G1!261!@baseboard_fab2_lib.baseboard_fab2(sch_1):page77_i43@mstr_sconn.sconn288_h44441004(chips)!SCONN288_H44441004_PIP-SCONN,HA!!!F170!VSS(10)!!!!
S!GND!J1G1!259!@baseboard_fab2_lib.baseboard_fab2(sch_1):page77_i43@mstr_sconn.sconn288_h44441004(chips)!SCONN288_H44441004_PIP-SCONN,HA!!!F170!VSS(11)!!!!
S!GND!J1G1!257!@baseboard_fab2_lib.baseboard_fab2(sch_1):page77_i43@mstr_sconn.sconn288_h44441004(chips)!SCONN288_H44441004_PIP-SCONN,HA!!!F170!VSS(12)!!!!
S!GND!J1G1!254!@baseboard_fab2_lib.baseboard_fab2(sch_1):page77_i43@mstr_sconn.sconn288_h44441004(chips)!SCONN288_H44441004_PIP-SCONN,HA!!!F170!VSS(13)!!!!
S!GND!J1G1!252!@baseboard_fab2_lib.baseboard_fab2(sch_1):page77_i43@mstr_sconn.sconn288_h44441004(chips)!SCONN288_H44441004_PIP-SCONN,HA!!!F170!VSS(14)!!!!
S!GND!J1G1!250!@baseboard_fab2_lib.baseboard_fab2(sch_1):page77_i43@mstr_sconn.sconn288_h44441004(chips)!SCONN288_H44441004_PIP-SCONN,HA!!!F170!VSS(15)!!!!
S!GND!J1G1!248!@baseboard_fab2_lib.baseboard_fab2(sch_1):page77_i43@mstr_sconn.sconn288_h44441004(chips)!SCONN288_H44441004_PIP-SCONN,HA!!!F170!VSS(16)!!!!
S!GND!J1G1!246!@baseboard_fab2_lib.baseboard_fab2(sch_1):page77_i43@mstr_sconn.sconn288_h44441004(chips)!SCONN288_H44441004_PIP-SCONN,HA!!!F170!VSS(17)!!!!
S!GND!J1G1!243!@baseboard_fab2_lib.baseboard_fab2(sch_1):page77_i43@mstr_sconn.sconn288_h44441004(chips)!SCONN288_H44441004_PIP-SCONN,HA!!!F170!VSS(18)!!!!
S!GND!J1G1!241!@baseboard_fab2_lib.baseboard_fab2(sch_1):page77_i43@mstr_sconn.sconn288_h44441004(chips)!SCONN288_H44441004_PIP-SCONN,HA!!!F170!VSS(19)!!!!
S!GND!J1G1!281!@baseboard_fab2_lib.baseboard_fab2(sch_1):page77_i43@mstr_sconn.sconn288_h44441004(chips)!SCONN288_H44441004_PIP-SCONN,HA!!!F170!VSS(1)!!!!
S!GND!J1G1!239!@baseboard_fab2_lib.baseboard_fab2(sch_1):page77_i43@mstr_sconn.sconn288_h44441004(chips)!SCONN288_H44441004_PIP-SCONN,HA!!!F170!VSS(20)!!!!
S!GND!J1G1!202!@baseboard_fab2_lib.baseboard_fab2(sch_1):page77_i43@mstr_sconn.sconn288_h44441004(chips)!SCONN288_H44441004_PIP-SCONN,HA!!!F170!VSS(21)!!!!
S!GND!J1G1!200!@baseboard_fab2_lib.baseboard_fab2(sch_1):page77_i43@mstr_sconn.sconn288_h44441004(chips)!SCONN288_H44441004_PIP-SCONN,HA!!!F170!VSS(22)!!!!
S!GND!J1G1!198!@baseboard_fab2_lib.baseboard_fab2(sch_1):page77_i43@mstr_sconn.sconn288_h44441004(chips)!SCONN288_H44441004_PIP-SCONN,HA!!!F170!VSS(23)!!!!
S!GND!J1G1!195!@baseboard_fab2_lib.baseboard_fab2(sch_1):page77_i43@mstr_sconn.sconn288_h44441004(chips)!SCONN288_H44441004_PIP-SCONN,HA!!!F170!VSS(24)!!!!
S!GND!J1G1!193!@baseboard_fab2_lib.baseboard_fab2(sch_1):page77_i43@mstr_sconn.sconn288_h44441004(chips)!SCONN288_H44441004_PIP-SCONN,HA!!!F170!VSS(25)!!!!
S!GND!J1G1!191!@baseboard_fab2_lib.baseboard_fab2(sch_1):page77_i43@mstr_sconn.sconn288_h44441004(chips)!SCONN288_H44441004_PIP-SCONN,HA!!!F170!VSS(26)!!!!
S!GND!J1G1!189!@baseboard_fab2_lib.baseboard_fab2(sch_1):page77_i43@mstr_sconn.sconn288_h44441004(chips)!SCONN288_H44441004_PIP-SCONN,HA!!!F170!VSS(27)!!!!
S!GND!J1G1!187!@baseboard_fab2_lib.baseboard_fab2(sch_1):page77_i43@mstr_sconn.sconn288_h44441004(chips)!SCONN288_H44441004_PIP-SCONN,HA!!!F170!VSS(28)!!!!
S!GND!J1G1!184!@baseboard_fab2_lib.baseboard_fab2(sch_1):page77_i43@mstr_sconn.sconn288_h44441004(chips)!SCONN288_H44441004_PIP-SCONN,HA!!!F170!VSS(29)!!!!
S!GND!J1G1!279!@baseboard_fab2_lib.baseboard_fab2(sch_1):page77_i43@mstr_sconn.sconn288_h44441004(chips)!SCONN288_H44441004_PIP-SCONN,HA!!!F170!VSS(2)!!!!
S!GND!J1G1!182!@baseboard_fab2_lib.baseboard_fab2(sch_1):page77_i43@mstr_sconn.sconn288_h44441004(chips)!SCONN288_H44441004_PIP-SCONN,HA!!!F170!VSS(30)!!!!
S!GND!J1G1!180!@baseboard_fab2_lib.baseboard_fab2(sch_1):page77_i43@mstr_sconn.sconn288_h44441004(chips)!SCONN288_H44441004_PIP-SCONN,HA!!!F170!VSS(31)!!!!
S!GND!J1G1!178!@baseboard_fab2_lib.baseboard_fab2(sch_1):page77_i43@mstr_sconn.sconn288_h44441004(chips)!SCONN288_H44441004_PIP-SCONN,HA!!!F170!VSS(32)!!!!
S!GND!J1G1!176!@baseboard_fab2_lib.baseboard_fab2(sch_1):page77_i43@mstr_sconn.sconn288_h44441004(chips)!SCONN288_H44441004_PIP-SCONN,HA!!!F170!VSS(33)!!!!
S!GND!J1G1!173!@baseboard_fab2_lib.baseboard_fab2(sch_1):page77_i43@mstr_sconn.sconn288_h44441004(chips)!SCONN288_H44441004_PIP-SCONN,HA!!!F170!VSS(34)!!!!
S!GND!J1G1!171!@baseboard_fab2_lib.baseboard_fab2(sch_1):page77_i43@mstr_sconn.sconn288_h44441004(chips)!SCONN288_H44441004_PIP-SCONN,HA!!!F170!VSS(35)!!!!
S!GND!J1G1!169!@baseboard_fab2_lib.baseboard_fab2(sch_1):page77_i43@mstr_sconn.sconn288_h44441004(chips)!SCONN288_H44441004_PIP-SCONN,HA!!!F170!VSS(36)!!!!
S!GND!J1G1!167!@baseboard_fab2_lib.baseboard_fab2(sch_1):page77_i43@mstr_sconn.sconn288_h44441004(chips)!SCONN288_H44441004_PIP-SCONN,HA!!!F170!VSS(37)!!!!
S!GND!J1G1!165!@baseboard_fab2_lib.baseboard_fab2(sch_1):page77_i43@mstr_sconn.sconn288_h44441004(chips)!SCONN288_H44441004_PIP-SCONN,HA!!!F170!VSS(38)!!!!
S!GND!J1G1!162!@baseboard_fab2_lib.baseboard_fab2(sch_1):page77_i43@mstr_sconn.sconn288_h44441004(chips)!SCONN288_H44441004_PIP-SCONN,HA!!!F170!VSS(39)!!!!
S!GND!J1G1!276!@baseboard_fab2_lib.baseboard_fab2(sch_1):page77_i43@mstr_sconn.sconn288_h44441004(chips)!SCONN288_H44441004_PIP-SCONN,HA!!!F170!VSS(3)!!!!
S!GND!J1G1!160!@baseboard_fab2_lib.baseboard_fab2(sch_1):page77_i43@mstr_sconn.sconn288_h44441004(chips)!SCONN288_H44441004_PIP-SCONN,HA!!!F170!VSS(40)!!!!
S!GND!J1G1!158!@baseboard_fab2_lib.baseboard_fab2(sch_1):page77_i43@mstr_sconn.sconn288_h44441004(chips)!SCONN288_H44441004_PIP-SCONN,HA!!!F170!VSS(41)!!!!
S!GND!J1G1!156!@baseboard_fab2_lib.baseboard_fab2(sch_1):page77_i43@mstr_sconn.sconn288_h44441004(chips)!SCONN288_H44441004_PIP-SCONN,HA!!!F170!VSS(42)!!!!
S!GND!J1G1!154!@baseboard_fab2_lib.baseboard_fab2(sch_1):page77_i43@mstr_sconn.sconn288_h44441004(chips)!SCONN288_H44441004_PIP-SCONN,HA!!!F170!VSS(43)!!!!
S!GND!J1G1!151!@baseboard_fab2_lib.baseboard_fab2(sch_1):page77_i43@mstr_sconn.sconn288_h44441004(chips)!SCONN288_H44441004_PIP-SCONN,HA!!!F170!VSS(44)!!!!
S!GND!J1G1!149!@baseboard_fab2_lib.baseboard_fab2(sch_1):page77_i43@mstr_sconn.sconn288_h44441004(chips)!SCONN288_H44441004_PIP-SCONN,HA!!!F170!VSS(45)!!!!
S!GND!J1G1!147!@baseboard_fab2_lib.baseboard_fab2(sch_1):page77_i43@mstr_sconn.sconn288_h44441004(chips)!SCONN288_H44441004_PIP-SCONN,HA!!!F170!VSS(46)!!!!
S!GND!J1G1!138!@baseboard_fab2_lib.baseboard_fab2(sch_1):page77_i43@mstr_sconn.sconn288_h44441004(chips)!SCONN288_H44441004_PIP-SCONN,HA!!!F170!VSS(47)!!!!
S!GND!J1G1!136!@baseboard_fab2_lib.baseboard_fab2(sch_1):page77_i43@mstr_sconn.sconn288_h44441004(chips)!SCONN288_H44441004_PIP-SCONN,HA!!!F170!VSS(48)!!!!
S!GND!J1G1!134!@baseboard_fab2_lib.baseboard_fab2(sch_1):page77_i43@mstr_sconn.sconn288_h44441004(chips)!SCONN288_H44441004_PIP-SCONN,HA!!!F170!VSS(49)!!!!
S!GND!J1G1!274!@baseboard_fab2_lib.baseboard_fab2(sch_1):page77_i43@mstr_sconn.sconn288_h44441004(chips)!SCONN288_H44441004_PIP-SCONN,HA!!!F170!VSS(4)!!!!
S!GND!J1G1!131!@baseboard_fab2_lib.baseboard_fab2(sch_1):page77_i43@mstr_sconn.sconn288_h44441004(chips)!SCONN288_H44441004_PIP-SCONN,HA!!!F170!VSS(50)!!!!
S!GND!J1G1!129!@baseboard_fab2_lib.baseboard_fab2(sch_1):page77_i43@mstr_sconn.sconn288_h44441004(chips)!SCONN288_H44441004_PIP-SCONN,HA!!!F170!VSS(51)!!!!
S!GND!J1G1!127!@baseboard_fab2_lib.baseboard_fab2(sch_1):page77_i43@mstr_sconn.sconn288_h44441004(chips)!SCONN288_H44441004_PIP-SCONN,HA!!!F170!VSS(52)!!!!
S!GND!J1G1!125!@baseboard_fab2_lib.baseboard_fab2(sch_1):page77_i43@mstr_sconn.sconn288_h44441004(chips)!SCONN288_H44441004_PIP-SCONN,HA!!!F170!VSS(53)!!!!
S!GND!J1G1!123!@baseboard_fab2_lib.baseboard_fab2(sch_1):page77_i43@mstr_sconn.sconn288_h44441004(chips)!SCONN288_H44441004_PIP-SCONN,HA!!!F170!VSS(54)!!!!
S!GND!J1G1!120!@baseboard_fab2_lib.baseboard_fab2(sch_1):page77_i43@mstr_sconn.sconn288_h44441004(chips)!SCONN288_H44441004_PIP-SCONN,HA!!!F170!VSS(55)!!!!
S!GND!J1G1!118!@baseboard_fab2_lib.baseboard_fab2(sch_1):page77_i43@mstr_sconn.sconn288_h44441004(chips)!SCONN288_H44441004_PIP-SCONN,HA!!!F170!VSS(56)!!!!
S!GND!J1G1!116!@baseboard_fab2_lib.baseboard_fab2(sch_1):page77_i43@mstr_sconn.sconn288_h44441004(chips)!SCONN288_H44441004_PIP-SCONN,HA!!!F170!VSS(57)!!!!
S!GND!J1G1!114!@baseboard_fab2_lib.baseboard_fab2(sch_1):page77_i43@mstr_sconn.sconn288_h44441004(chips)!SCONN288_H44441004_PIP-SCONN,HA!!!F170!VSS(58)!!!!
S!GND!J1G1!112!@baseboard_fab2_lib.baseboard_fab2(sch_1):page77_i43@mstr_sconn.sconn288_h44441004(chips)!SCONN288_H44441004_PIP-SCONN,HA!!!F170!VSS(59)!!!!
S!GND!J1G1!272!@baseboard_fab2_lib.baseboard_fab2(sch_1):page77_i43@mstr_sconn.sconn288_h44441004(chips)!SCONN288_H44441004_PIP-SCONN,HA!!!F170!VSS(5)!!!!
S!GND!J1G1!109!@baseboard_fab2_lib.baseboard_fab2(sch_1):page77_i43@mstr_sconn.sconn288_h44441004(chips)!SCONN288_H44441004_PIP-SCONN,HA!!!F170!VSS(60)!!!!
S!GND!J1G1!107!@baseboard_fab2_lib.baseboard_fab2(sch_1):page77_i43@mstr_sconn.sconn288_h44441004(chips)!SCONN288_H44441004_PIP-SCONN,HA!!!F170!VSS(61)!!!!
S!GND!J1G1!105!@baseboard_fab2_lib.baseboard_fab2(sch_1):page77_i43@mstr_sconn.sconn288_h44441004(chips)!SCONN288_H44441004_PIP-SCONN,HA!!!F170!VSS(62)!!!!
S!GND!J1G1!103!@baseboard_fab2_lib.baseboard_fab2(sch_1):page77_i43@mstr_sconn.sconn288_h44441004(chips)!SCONN288_H44441004_PIP-SCONN,HA!!!F170!VSS(63)!!!!
S!GND!J1G1!101!@baseboard_fab2_lib.baseboard_fab2(sch_1):page77_i43@mstr_sconn.sconn288_h44441004(chips)!SCONN288_H44441004_PIP-SCONN,HA!!!F170!VSS(64)!!!!
S!GND!J1G1!98!@baseboard_fab2_lib.baseboard_fab2(sch_1):page77_i43@mstr_sconn.sconn288_h44441004(chips)!SCONN288_H44441004_PIP-SCONN,HA!!!F170!VSS(65)!!!!
S!GND!J1G1!96!@baseboard_fab2_lib.baseboard_fab2(sch_1):page77_i43@mstr_sconn.sconn288_h44441004(chips)!SCONN288_H44441004_PIP-SCONN,HA!!!F170!VSS(66)!!!!
S!GND!J1G1!94!@baseboard_fab2_lib.baseboard_fab2(sch_1):page77_i43@mstr_sconn.sconn288_h44441004(chips)!SCONN288_H44441004_PIP-SCONN,HA!!!F170!VSS(67)!!!!
S!GND!J1G1!57!@baseboard_fab2_lib.baseboard_fab2(sch_1):page77_i43@mstr_sconn.sconn288_h44441004(chips)!SCONN288_H44441004_PIP-SCONN,HA!!!F170!VSS(68)!!!!
S!GND!J1G1!55!@baseboard_fab2_lib.baseboard_fab2(sch_1):page77_i43@mstr_sconn.sconn288_h44441004(chips)!SCONN288_H44441004_PIP-SCONN,HA!!!F170!VSS(69)!!!!
S!GND!J1G1!270!@baseboard_fab2_lib.baseboard_fab2(sch_1):page77_i43@mstr_sconn.sconn288_h44441004(chips)!SCONN288_H44441004_PIP-SCONN,HA!!!F170!VSS(6)!!!!
S!GND!J1G1!53!@baseboard_fab2_lib.baseboard_fab2(sch_1):page77_i43@mstr_sconn.sconn288_h44441004(chips)!SCONN288_H44441004_PIP-SCONN,HA!!!F170!VSS(70)!!!!
S!GND!J1G1!50!@baseboard_fab2_lib.baseboard_fab2(sch_1):page77_i43@mstr_sconn.sconn288_h44441004(chips)!SCONN288_H44441004_PIP-SCONN,HA!!!F170!VSS(71)!!!!
S!GND!J1G1!48!@baseboard_fab2_lib.baseboard_fab2(sch_1):page77_i43@mstr_sconn.sconn288_h44441004(chips)!SCONN288_H44441004_PIP-SCONN,HA!!!F170!VSS(72)!!!!
S!GND!J1G1!46!@baseboard_fab2_lib.baseboard_fab2(sch_1):page77_i43@mstr_sconn.sconn288_h44441004(chips)!SCONN288_H44441004_PIP-SCONN,HA!!!F170!VSS(73)!!!!
S!GND!J1G1!44!@baseboard_fab2_lib.baseboard_fab2(sch_1):page77_i43@mstr_sconn.sconn288_h44441004(chips)!SCONN288_H44441004_PIP-SCONN,HA!!!F170!VSS(74)!!!!
S!GND!J1G1!42!@baseboard_fab2_lib.baseboard_fab2(sch_1):page77_i43@mstr_sconn.sconn288_h44441004(chips)!SCONN288_H44441004_PIP-SCONN,HA!!!F170!VSS(75)!!!!
S!GND!J1G1!39!@baseboard_fab2_lib.baseboard_fab2(sch_1):page77_i43@mstr_sconn.sconn288_h44441004(chips)!SCONN288_H44441004_PIP-SCONN,HA!!!F170!VSS(76)!!!!
S!GND!J1G1!37!@baseboard_fab2_lib.baseboard_fab2(sch_1):page77_i43@mstr_sconn.sconn288_h44441004(chips)!SCONN288_H44441004_PIP-SCONN,HA!!!F170!VSS(77)!!!!
S!GND!J1G1!35!@baseboard_fab2_lib.baseboard_fab2(sch_1):page77_i43@mstr_sconn.sconn288_h44441004(chips)!SCONN288_H44441004_PIP-SCONN,HA!!!F170!VSS(78)!!!!
S!GND!J1G1!33!@baseboard_fab2_lib.baseboard_fab2(sch_1):page77_i43@mstr_sconn.sconn288_h44441004(chips)!SCONN288_H44441004_PIP-SCONN,HA!!!F170!VSS(79)!!!!
S!GND!J1G1!268!@baseboard_fab2_lib.baseboard_fab2(sch_1):page77_i43@mstr_sconn.sconn288_h44441004(chips)!SCONN288_H44441004_PIP-SCONN,HA!!!F170!VSS(7)!!!!
S!GND!J1G1!31!@baseboard_fab2_lib.baseboard_fab2(sch_1):page77_i43@mstr_sconn.sconn288_h44441004(chips)!SCONN288_H44441004_PIP-SCONN,HA!!!F170!VSS(80)!!!!
S!GND!J1G1!28!@baseboard_fab2_lib.baseboard_fab2(sch_1):page77_i43@mstr_sconn.sconn288_h44441004(chips)!SCONN288_H44441004_PIP-SCONN,HA!!!F170!VSS(81)!!!!
S!GND!J1G1!26!@baseboard_fab2_lib.baseboard_fab2(sch_1):page77_i43@mstr_sconn.sconn288_h44441004(chips)!SCONN288_H44441004_PIP-SCONN,HA!!!F170!VSS(82)!!!!
S!GND!J1G1!24!@baseboard_fab2_lib.baseboard_fab2(sch_1):page77_i43@mstr_sconn.sconn288_h44441004(chips)!SCONN288_H44441004_PIP-SCONN,HA!!!F170!VSS(83)!!!!
S!GND!J1G1!22!@baseboard_fab2_lib.baseboard_fab2(sch_1):page77_i43@mstr_sconn.sconn288_h44441004(chips)!SCONN288_H44441004_PIP-SCONN,HA!!!F170!VSS(84)!!!!
S!GND!J1G1!20!@baseboard_fab2_lib.baseboard_fab2(sch_1):page77_i43@mstr_sconn.sconn288_h44441004(chips)!SCONN288_H44441004_PIP-SCONN,HA!!!F170!VSS(85)!!!!
S!GND!J1G1!17!@baseboard_fab2_lib.baseboard_fab2(sch_1):page77_i43@mstr_sconn.sconn288_h44441004(chips)!SCONN288_H44441004_PIP-SCONN,HA!!!F170!VSS(86)!!!!
S!GND!J1G1!15!@baseboard_fab2_lib.baseboard_fab2(sch_1):page77_i43@mstr_sconn.sconn288_h44441004(chips)!SCONN288_H44441004_PIP-SCONN,HA!!!F170!VSS(87)!!!!
S!GND!J1G1!13!@baseboard_fab2_lib.baseboard_fab2(sch_1):page77_i43@mstr_sconn.sconn288_h44441004(chips)!SCONN288_H44441004_PIP-SCONN,HA!!!F170!VSS(88)!!!!
S!GND!J1G1!11!@baseboard_fab2_lib.baseboard_fab2(sch_1):page77_i43@mstr_sconn.sconn288_h44441004(chips)!SCONN288_H44441004_PIP-SCONN,HA!!!F170!VSS(89)!!!!
S!GND!J1G1!265!@baseboard_fab2_lib.baseboard_fab2(sch_1):page77_i43@mstr_sconn.sconn288_h44441004(chips)!SCONN288_H44441004_PIP-SCONN,HA!!!F170!VSS(8)!!!!
S!GND!J1G1!9!@baseboard_fab2_lib.baseboard_fab2(sch_1):page77_i43@mstr_sconn.sconn288_h44441004(chips)!SCONN288_H44441004_PIP-SCONN,HA!!!F170!VSS(90)!!!!
S!GND!J1G1!6!@baseboard_fab2_lib.baseboard_fab2(sch_1):page77_i43@mstr_sconn.sconn288_h44441004(chips)!SCONN288_H44441004_PIP-SCONN,HA!!!F170!VSS(91)!!!!
S!GND!J1G1!4!@baseboard_fab2_lib.baseboard_fab2(sch_1):page77_i43@mstr_sconn.sconn288_h44441004(chips)!SCONN288_H44441004_PIP-SCONN,HA!!!F170!VSS(92)!!!!
S!GND!J1G1!2!@baseboard_fab2_lib.baseboard_fab2(sch_1):page77_i43@mstr_sconn.sconn288_h44441004(chips)!SCONN288_H44441004_PIP-SCONN,HA!!!F170!VSS(93)!!!!
S!GND!J1G1!263!@baseboard_fab2_lib.baseboard_fab2(sch_1):page77_i43@mstr_sconn.sconn288_h44441004(chips)!SCONN288_H44441004_PIP-SCONN,HA!!!F170!VSS(9)!!!!
S!P12V_NVDIMM_GHJ!J1G1!145!@baseboard_fab2_lib.baseboard_fab2(sch_1):page77_i171@mstr_sconn.sconn288_h44441004(chips)!SCONN288_H44441004_PIP-SCONN,HA!!!F169!\12v\(0)!!!!
S!P12V_NVDIMM_GHJ!J1G1!1!@baseboard_fab2_lib.baseboard_fab2(sch_1):page77_i171@mstr_sconn.sconn288_h44441004(chips)!SCONN288_H44441004_PIP-SCONN,HA!!!F169!\12v\(1)!!!!
S!PVDDQ_GHJ!J1G1!236!@baseboard_fab2_lib.baseboard_fab2(sch_1):page77_i171@mstr_sconn.sconn288_h44441004(chips)!SCONN288_H44441004_PIP-SCONN,HA!!!F169!VDD(0)!!!!
S!PVDDQ_GHJ!J1G1!209!@baseboard_fab2_lib.baseboard_fab2(sch_1):page77_i171@mstr_sconn.sconn288_h44441004(chips)!SCONN288_H44441004_PIP-SCONN,HA!!!F169!VDD(10)!!!!
S!PVDDQ_GHJ!J1G1!206!@baseboard_fab2_lib.baseboard_fab2(sch_1):page77_i171@mstr_sconn.sconn288_h44441004(chips)!SCONN288_H44441004_PIP-SCONN,HA!!!F169!VDD(11)!!!!
S!PVDDQ_GHJ!J1G1!204!@baseboard_fab2_lib.baseboard_fab2(sch_1):page77_i171@mstr_sconn.sconn288_h44441004(chips)!SCONN288_H44441004_PIP-SCONN,HA!!!F169!VDD(12)!!!!
S!PVDDQ_GHJ!J1G1!92!@baseboard_fab2_lib.baseboard_fab2(sch_1):page77_i171@mstr_sconn.sconn288_h44441004(chips)!SCONN288_H44441004_PIP-SCONN,HA!!!F169!VDD(13)!!!!
S!PVDDQ_GHJ!J1G1!90!@baseboard_fab2_lib.baseboard_fab2(sch_1):page77_i171@mstr_sconn.sconn288_h44441004(chips)!SCONN288_H44441004_PIP-SCONN,HA!!!F169!VDD(14)!!!!
S!PVDDQ_GHJ!J1G1!88!@baseboard_fab2_lib.baseboard_fab2(sch_1):page77_i171@mstr_sconn.sconn288_h44441004(chips)!SCONN288_H44441004_PIP-SCONN,HA!!!F169!VDD(15)!!!!
S!PVDDQ_GHJ!J1G1!85!@baseboard_fab2_lib.baseboard_fab2(sch_1):page77_i171@mstr_sconn.sconn288_h44441004(chips)!SCONN288_H44441004_PIP-SCONN,HA!!!F169!VDD(16)!!!!
S!PVDDQ_GHJ!J1G1!83!@baseboard_fab2_lib.baseboard_fab2(sch_1):page77_i171@mstr_sconn.sconn288_h44441004(chips)!SCONN288_H44441004_PIP-SCONN,HA!!!F169!VDD(17)!!!!
S!PVDDQ_GHJ!J1G1!80!@baseboard_fab2_lib.baseboard_fab2(sch_1):page77_i171@mstr_sconn.sconn288_h44441004(chips)!SCONN288_H44441004_PIP-SCONN,HA!!!F169!VDD(18)!!!!
S!PVDDQ_GHJ!J1G1!76!@baseboard_fab2_lib.baseboard_fab2(sch_1):page77_i171@mstr_sconn.sconn288_h44441004(chips)!SCONN288_H44441004_PIP-SCONN,HA!!!F169!VDD(19)!!!!
S!PVDDQ_GHJ!J1G1!233!@baseboard_fab2_lib.baseboard_fab2(sch_1):page77_i171@mstr_sconn.sconn288_h44441004(chips)!SCONN288_H44441004_PIP-SCONN,HA!!!F169!VDD(1)!!!!
S!PVDDQ_GHJ!J1G1!73!@baseboard_fab2_lib.baseboard_fab2(sch_1):page77_i171@mstr_sconn.sconn288_h44441004(chips)!SCONN288_H44441004_PIP-SCONN,HA!!!F169!VDD(20)!!!!
S!PVDDQ_GHJ!J1G1!70!@baseboard_fab2_lib.baseboard_fab2(sch_1):page77_i171@mstr_sconn.sconn288_h44441004(chips)!SCONN288_H44441004_PIP-SCONN,HA!!!F169!VDD(21)!!!!
S!PVDDQ_GHJ!J1G1!67!@baseboard_fab2_lib.baseboard_fab2(sch_1):page77_i171@mstr_sconn.sconn288_h44441004(chips)!SCONN288_H44441004_PIP-SCONN,HA!!!F169!VDD(22)!!!!
S!PVDDQ_GHJ!J1G1!64!@baseboard_fab2_lib.baseboard_fab2(sch_1):page77_i171@mstr_sconn.sconn288_h44441004(chips)!SCONN288_H44441004_PIP-SCONN,HA!!!F169!VDD(23)!!!!
S!PVDDQ_GHJ!J1G1!61!@baseboard_fab2_lib.baseboard_fab2(sch_1):page77_i171@mstr_sconn.sconn288_h44441004(chips)!SCONN288_H44441004_PIP-SCONN,HA!!!F169!VDD(24)!!!!
S!PVDDQ_GHJ!J1G1!59!@baseboard_fab2_lib.baseboard_fab2(sch_1):page77_i171@mstr_sconn.sconn288_h44441004(chips)!SCONN288_H44441004_PIP-SCONN,HA!!!F169!VDD(25)!!!!
S!PVDDQ_GHJ!J1G1!231!@baseboard_fab2_lib.baseboard_fab2(sch_1):page77_i171@mstr_sconn.sconn288_h44441004(chips)!SCONN288_H44441004_PIP-SCONN,HA!!!F169!VDD(2)!!!!
S!PVDDQ_GHJ!J1G1!229!@baseboard_fab2_lib.baseboard_fab2(sch_1):page77_i171@mstr_sconn.sconn288_h44441004(chips)!SCONN288_H44441004_PIP-SCONN,HA!!!F169!VDD(3)!!!!
S!PVDDQ_GHJ!J1G1!226!@baseboard_fab2_lib.baseboard_fab2(sch_1):page77_i171@mstr_sconn.sconn288_h44441004(chips)!SCONN288_H44441004_PIP-SCONN,HA!!!F169!VDD(4)!!!!
S!PVDDQ_GHJ!J1G1!223!@baseboard_fab2_lib.baseboard_fab2(sch_1):page77_i171@mstr_sconn.sconn288_h44441004(chips)!SCONN288_H44441004_PIP-SCONN,HA!!!F169!VDD(5)!!!!
S!PVDDQ_GHJ!J1G1!220!@baseboard_fab2_lib.baseboard_fab2(sch_1):page77_i171@mstr_sconn.sconn288_h44441004(chips)!SCONN288_H44441004_PIP-SCONN,HA!!!F169!VDD(6)!!!!
S!PVDDQ_GHJ!J1G1!217!@baseboard_fab2_lib.baseboard_fab2(sch_1):page77_i171@mstr_sconn.sconn288_h44441004(chips)!SCONN288_H44441004_PIP-SCONN,HA!!!F169!VDD(7)!!!!
S!PVDDQ_GHJ!J1G1!215!@baseboard_fab2_lib.baseboard_fab2(sch_1):page77_i171@mstr_sconn.sconn288_h44441004(chips)!SCONN288_H44441004_PIP-SCONN,HA!!!F169!VDD(8)!!!!
S!PVDDQ_GHJ!J1G1!212!@baseboard_fab2_lib.baseboard_fab2(sch_1):page77_i171@mstr_sconn.sconn288_h44441004(chips)!SCONN288_H44441004_PIP-SCONN,HA!!!F169!VDD(9)!!!!
S!PVPP_GHJ!J1G1!287!@baseboard_fab2_lib.baseboard_fab2(sch_1):page77_i171@mstr_sconn.sconn288_h44441004(chips)!SCONN288_H44441004_PIP-SCONN,HA!!!F169!VPP(0)!!!!
S!PVPP_GHJ!J1G1!286!@baseboard_fab2_lib.baseboard_fab2(sch_1):page77_i171@mstr_sconn.sconn288_h44441004(chips)!SCONN288_H44441004_PIP-SCONN,HA!!!F169!VPP(1)!!!!
S!PVPP_GHJ!J1G1!288!@baseboard_fab2_lib.baseboard_fab2(sch_1):page77_i171@mstr_sconn.sconn288_h44441004(chips)!SCONN288_H44441004_PIP-SCONN,HA!!!F169!VPP(2)!!!!
S!PVPP_GHJ!J1G1!143!@baseboard_fab2_lib.baseboard_fab2(sch_1):page77_i171@mstr_sconn.sconn288_h44441004(chips)!SCONN288_H44441004_PIP-SCONN,HA!!!F169!VPP(3)!!!!
S!PVPP_GHJ!J1G1!142!@baseboard_fab2_lib.baseboard_fab2(sch_1):page77_i171@mstr_sconn.sconn288_h44441004(chips)!SCONN288_H44441004_PIP-SCONN,HA!!!F169!VPP(4)!!!!
S!PVTT_GHJ!J1G1!221!@baseboard_fab2_lib.baseboard_fab2(sch_1):page77_i171@mstr_sconn.sconn288_h44441004(chips)!SCONN288_H44441004_PIP-SCONN,HA!!!F169!VTT(0)!!!!
S!PVTT_GHJ!J1G1!77!@baseboard_fab2_lib.baseboard_fab2(sch_1):page77_i171@mstr_sconn.sconn288_h44441004(chips)!SCONN288_H44441004_PIP-SCONN,HA!!!F169!VTT(1)!!!!
S!M_H_MA<0>!J1G2!79!@baseboard_fab2_lib.baseboard_fab2(sch_1):page79_i111@mstr_sconn.sconn288_h44441004(chips)!SCONN288_H44441004_PIP-SCONN,HA!!!F168!A0!!!!
S!M_H_MA<1>!J1G2!72!@baseboard_fab2_lib.baseboard_fab2(sch_1):page79_i111@mstr_sconn.sconn288_h44441004(chips)!SCONN288_H44441004_PIP-SCONN,HA!!!F168!A1!!!!
S!M_H_MA<10>!J1G2!225!@baseboard_fab2_lib.baseboard_fab2(sch_1):page79_i111@mstr_sconn.sconn288_h44441004(chips)!SCONN288_H44441004_PIP-SCONN,HA!!!F168!A10!!!!
S!M_H_MA<11>!J1G2!210!@baseboard_fab2_lib.baseboard_fab2(sch_1):page79_i111@mstr_sconn.sconn288_h44441004(chips)!SCONN288_H44441004_PIP-SCONN,HA!!!F168!A11!!!!
S!M_H_MA<12>!J1G2!65!@baseboard_fab2_lib.baseboard_fab2(sch_1):page79_i111@mstr_sconn.sconn288_h44441004(chips)!SCONN288_H44441004_PIP-SCONN,HA!!!F168!A12!!!!
S!M_H_MA<13>!J1G2!232!@baseboard_fab2_lib.baseboard_fab2(sch_1):page79_i111@mstr_sconn.sconn288_h44441004(chips)!SCONN288_H44441004_PIP-SCONN,HA!!!F168!A13!!!!
S!M_H_MA<14>!J1G2!228!@baseboard_fab2_lib.baseboard_fab2(sch_1):page79_i111@mstr_sconn.sconn288_h44441004(chips)!SCONN288_H44441004_PIP-SCONN,HA!!!F168!A14_WE_N!!!!
S!M_H_MA<15>!J1G2!86!@baseboard_fab2_lib.baseboard_fab2(sch_1):page79_i111@mstr_sconn.sconn288_h44441004(chips)!SCONN288_H44441004_PIP-SCONN,HA!!!F168!A15_CAS_N!!!!
S!M_H_MA<16>!J1G2!82!@baseboard_fab2_lib.baseboard_fab2(sch_1):page79_i111@mstr_sconn.sconn288_h44441004(chips)!SCONN288_H44441004_PIP-SCONN,HA!!!F168!A16_RAS_N!!!!
S!M_H_MA<17>!J1G2!234!@baseboard_fab2_lib.baseboard_fab2(sch_1):page79_i111@mstr_sconn.sconn288_h44441004(chips)!SCONN288_H44441004_PIP-SCONN,HA!!!F168!A17!!!!
S!M_H_MA<2>!J1G2!216!@baseboard_fab2_lib.baseboard_fab2(sch_1):page79_i111@mstr_sconn.sconn288_h44441004(chips)!SCONN288_H44441004_PIP-SCONN,HA!!!F168!A2!!!!
S!M_H_MA<3>!J1G2!71!@baseboard_fab2_lib.baseboard_fab2(sch_1):page79_i111@mstr_sconn.sconn288_h44441004(chips)!SCONN288_H44441004_PIP-SCONN,HA!!!F168!A3!!!!
S!M_H_MA<4>!J1G2!214!@baseboard_fab2_lib.baseboard_fab2(sch_1):page79_i111@mstr_sconn.sconn288_h44441004(chips)!SCONN288_H44441004_PIP-SCONN,HA!!!F168!A4!!!!
S!M_H_MA<5>!J1G2!213!@baseboard_fab2_lib.baseboard_fab2(sch_1):page79_i111@mstr_sconn.sconn288_h44441004(chips)!SCONN288_H44441004_PIP-SCONN,HA!!!F168!A5!!!!
S!M_H_MA<6>!J1G2!69!@baseboard_fab2_lib.baseboard_fab2(sch_1):page79_i111@mstr_sconn.sconn288_h44441004(chips)!SCONN288_H44441004_PIP-SCONN,HA!!!F168!A6!!!!
S!M_H_MA<7>!J1G2!211!@baseboard_fab2_lib.baseboard_fab2(sch_1):page79_i111@mstr_sconn.sconn288_h44441004(chips)!SCONN288_H44441004_PIP-SCONN,HA!!!F168!A7!!!!
S!M_H_MA<8>!J1G2!68!@baseboard_fab2_lib.baseboard_fab2(sch_1):page79_i111@mstr_sconn.sconn288_h44441004(chips)!SCONN288_H44441004_PIP-SCONN,HA!!!F168!A8!!!!
S!M_H_MA<9>!J1G2!66!@baseboard_fab2_lib.baseboard_fab2(sch_1):page79_i111@mstr_sconn.sconn288_h44441004(chips)!SCONN288_H44441004_PIP-SCONN,HA!!!F168!A9!!!!
S!M_H_ACT_N!J1G2!62!@baseboard_fab2_lib.baseboard_fab2(sch_1):page79_i111@mstr_sconn.sconn288_h44441004(chips)!SCONN288_H44441004_PIP-SCONN,HA!!!F168!ACT_N!!!!
S!M_H_ALERT_N!J1G2!208!@baseboard_fab2_lib.baseboard_fab2(sch_1):page79_i111@mstr_sconn.sconn288_h44441004(chips)!SCONN288_H44441004_PIP-SCONN,HA!!!F168!ALERT_N!!!!
S!M_H_BA<0>!J1G2!81!@baseboard_fab2_lib.baseboard_fab2(sch_1):page79_i111@mstr_sconn.sconn288_h44441004(chips)!SCONN288_H44441004_PIP-SCONN,HA!!!F168!BA(0)!!!!
S!M_H_BA<1>!J1G2!224!@baseboard_fab2_lib.baseboard_fab2(sch_1):page79_i111@mstr_sconn.sconn288_h44441004(chips)!SCONN288_H44441004_PIP-SCONN,HA!!!F168!BA(1)!!!!
S!M_H_BG<0>!J1G2!63!@baseboard_fab2_lib.baseboard_fab2(sch_1):page79_i111@mstr_sconn.sconn288_h44441004(chips)!SCONN288_H44441004_PIP-SCONN,HA!!!F168!BG(0)!!!!
S!M_H_BG<1>!J1G2!207!@baseboard_fab2_lib.baseboard_fab2(sch_1):page79_i111@mstr_sconn.sconn288_h44441004(chips)!SCONN288_H44441004_PIP-SCONN,HA!!!F168!BG(1)!!!!
S!M_H_C<2>!J1G2!235!@baseboard_fab2_lib.baseboard_fab2(sch_1):page79_i111@mstr_sconn.sconn288_h44441004(chips)!SCONN288_H44441004_PIP-SCONN,HA!!!F168!C(2)!!!!
S!M_H_ECC<1>!J1G2!49!@baseboard_fab2_lib.baseboard_fab2(sch_1):page79_i111@mstr_sconn.sconn288_h44441004(chips)!SCONN288_H44441004_PIP-SCONN,HA!!!F168!CB(0)!!!!
S!M_H_ECC<0>!J1G2!194!@baseboard_fab2_lib.baseboard_fab2(sch_1):page79_i111@mstr_sconn.sconn288_h44441004(chips)!SCONN288_H44441004_PIP-SCONN,HA!!!F168!CB(1)!!!!
S!M_H_ECC<3>!J1G2!56!@baseboard_fab2_lib.baseboard_fab2(sch_1):page79_i111@mstr_sconn.sconn288_h44441004(chips)!SCONN288_H44441004_PIP-SCONN,HA!!!F168!CB(2)!!!!
S!M_H_ECC<2>!J1G2!201!@baseboard_fab2_lib.baseboard_fab2(sch_1):page79_i111@mstr_sconn.sconn288_h44441004(chips)!SCONN288_H44441004_PIP-SCONN,HA!!!F168!CB(3)!!!!
S!M_H_ECC<5>!J1G2!47!@baseboard_fab2_lib.baseboard_fab2(sch_1):page79_i111@mstr_sconn.sconn288_h44441004(chips)!SCONN288_H44441004_PIP-SCONN,HA!!!F168!CB(4)!!!!
S!M_H_ECC<4>!J1G2!192!@baseboard_fab2_lib.baseboard_fab2(sch_1):page79_i111@mstr_sconn.sconn288_h44441004(chips)!SCONN288_H44441004_PIP-SCONN,HA!!!F168!CB(5)!!!!
S!M_H_ECC<7>!J1G2!54!@baseboard_fab2_lib.baseboard_fab2(sch_1):page79_i111@mstr_sconn.sconn288_h44441004(chips)!SCONN288_H44441004_PIP-SCONN,HA!!!F168!CB(6)!!!!
S!M_H_ECC<6>!J1G2!199!@baseboard_fab2_lib.baseboard_fab2(sch_1):page79_i111@mstr_sconn.sconn288_h44441004(chips)!SCONN288_H44441004_PIP-SCONN,HA!!!F168!CB(7)!!!!
S!M_H_CLK_DN<0>!J1G2!75!@baseboard_fab2_lib.baseboard_fab2(sch_1):page79_i111@mstr_sconn.sconn288_h44441004(chips)!SCONN288_H44441004_PIP-SCONN,HA!!!F168!CK0N!!!!
S!M_H_CLK_DP<0>!J1G2!74!@baseboard_fab2_lib.baseboard_fab2(sch_1):page79_i111@mstr_sconn.sconn288_h44441004(chips)!SCONN288_H44441004_PIP-SCONN,HA!!!F168!CK0P!!!!
S!M_H_CLK_DN<1>!J1G2!219!@baseboard_fab2_lib.baseboard_fab2(sch_1):page79_i111@mstr_sconn.sconn288_h44441004(chips)!SCONN288_H44441004_PIP-SCONN,HA!!!F168!CK1N!!!!
S!M_H_CLK_DP<1>!J1G2!218!@baseboard_fab2_lib.baseboard_fab2(sch_1):page79_i111@mstr_sconn.sconn288_h44441004(chips)!SCONN288_H44441004_PIP-SCONN,HA!!!F168!CK1P!!!!
S!M_H_CKE<0>!J1G2!60!@baseboard_fab2_lib.baseboard_fab2(sch_1):page79_i111@mstr_sconn.sconn288_h44441004(chips)!SCONN288_H44441004_PIP-SCONN,HA!!!F168!CKE(0)!!!!
S!M_H_CKE<1>!J1G2!203!@baseboard_fab2_lib.baseboard_fab2(sch_1):page79_i111@mstr_sconn.sconn288_h44441004(chips)!SCONN288_H44441004_PIP-SCONN,HA!!!F168!CKE(1)!!!!
S!M_H_DQ<1>!J1G2!5!@baseboard_fab2_lib.baseboard_fab2(sch_1):page79_i111@mstr_sconn.sconn288_h44441004(chips)!SCONN288_H44441004_PIP-SCONN,HA!!!F168!DQ(0)!!!!
S!M_H_DQ<11>!J1G2!23!@baseboard_fab2_lib.baseboard_fab2(sch_1):page79_i111@mstr_sconn.sconn288_h44441004(chips)!SCONN288_H44441004_PIP-SCONN,HA!!!F168!DQ(10)!!!!
S!M_H_DQ<10>!J1G2!168!@baseboard_fab2_lib.baseboard_fab2(sch_1):page79_i111@mstr_sconn.sconn288_h44441004(chips)!SCONN288_H44441004_PIP-SCONN,HA!!!F168!DQ(11)!!!!
S!M_H_DQ<13>!J1G2!14!@baseboard_fab2_lib.baseboard_fab2(sch_1):page79_i111@mstr_sconn.sconn288_h44441004(chips)!SCONN288_H44441004_PIP-SCONN,HA!!!F168!DQ(12)!!!!
S!M_H_DQ<12>!J1G2!159!@baseboard_fab2_lib.baseboard_fab2(sch_1):page79_i111@mstr_sconn.sconn288_h44441004(chips)!SCONN288_H44441004_PIP-SCONN,HA!!!F168!DQ(13)!!!!
S!M_H_DQ<15>!J1G2!21!@baseboard_fab2_lib.baseboard_fab2(sch_1):page79_i111@mstr_sconn.sconn288_h44441004(chips)!SCONN288_H44441004_PIP-SCONN,HA!!!F168!DQ(14)!!!!
S!M_H_DQ<14>!J1G2!166!@baseboard_fab2_lib.baseboard_fab2(sch_1):page79_i111@mstr_sconn.sconn288_h44441004(chips)!SCONN288_H44441004_PIP-SCONN,HA!!!F168!DQ(15)!!!!
S!M_H_DQ<17>!J1G2!27!@baseboard_fab2_lib.baseboard_fab2(sch_1):page79_i111@mstr_sconn.sconn288_h44441004(chips)!SCONN288_H44441004_PIP-SCONN,HA!!!F168!DQ(16)!!!!
S!M_H_DQ<16>!J1G2!172!@baseboard_fab2_lib.baseboard_fab2(sch_1):page79_i111@mstr_sconn.sconn288_h44441004(chips)!SCONN288_H44441004_PIP-SCONN,HA!!!F168!DQ(17)!!!!
S!M_H_DQ<19>!J1G2!34!@baseboard_fab2_lib.baseboard_fab2(sch_1):page79_i111@mstr_sconn.sconn288_h44441004(chips)!SCONN288_H44441004_PIP-SCONN,HA!!!F168!DQ(18)!!!!
S!M_H_DQ<18>!J1G2!179!@baseboard_fab2_lib.baseboard_fab2(sch_1):page79_i111@mstr_sconn.sconn288_h44441004(chips)!SCONN288_H44441004_PIP-SCONN,HA!!!F168!DQ(19)!!!!
S!M_H_DQ<0>!J1G2!150!@baseboard_fab2_lib.baseboard_fab2(sch_1):page79_i111@mstr_sconn.sconn288_h44441004(chips)!SCONN288_H44441004_PIP-SCONN,HA!!!F168!DQ(1)!!!!
S!M_H_DQ<21>!J1G2!25!@baseboard_fab2_lib.baseboard_fab2(sch_1):page79_i111@mstr_sconn.sconn288_h44441004(chips)!SCONN288_H44441004_PIP-SCONN,HA!!!F168!DQ(20)!!!!
S!M_H_DQ<20>!J1G2!170!@baseboard_fab2_lib.baseboard_fab2(sch_1):page79_i111@mstr_sconn.sconn288_h44441004(chips)!SCONN288_H44441004_PIP-SCONN,HA!!!F168!DQ(21)!!!!
S!M_H_DQ<23>!J1G2!32!@baseboard_fab2_lib.baseboard_fab2(sch_1):page79_i111@mstr_sconn.sconn288_h44441004(chips)!SCONN288_H44441004_PIP-SCONN,HA!!!F168!DQ(22)!!!!
S!M_H_DQ<22>!J1G2!177!@baseboard_fab2_lib.baseboard_fab2(sch_1):page79_i111@mstr_sconn.sconn288_h44441004(chips)!SCONN288_H44441004_PIP-SCONN,HA!!!F168!DQ(23)!!!!
S!M_H_DQ<25>!J1G2!38!@baseboard_fab2_lib.baseboard_fab2(sch_1):page79_i111@mstr_sconn.sconn288_h44441004(chips)!SCONN288_H44441004_PIP-SCONN,HA!!!F168!DQ(24)!!!!
S!M_H_DQ<24>!J1G2!183!@baseboard_fab2_lib.baseboard_fab2(sch_1):page79_i111@mstr_sconn.sconn288_h44441004(chips)!SCONN288_H44441004_PIP-SCONN,HA!!!F168!DQ(25)!!!!
S!M_H_DQ<27>!J1G2!45!@baseboard_fab2_lib.baseboard_fab2(sch_1):page79_i111@mstr_sconn.sconn288_h44441004(chips)!SCONN288_H44441004_PIP-SCONN,HA!!!F168!DQ(26)!!!!
S!M_H_DQ<26>!J1G2!190!@baseboard_fab2_lib.baseboard_fab2(sch_1):page79_i111@mstr_sconn.sconn288_h44441004(chips)!SCONN288_H44441004_PIP-SCONN,HA!!!F168!DQ(27)!!!!
S!M_H_DQ<29>!J1G2!36!@baseboard_fab2_lib.baseboard_fab2(sch_1):page79_i111@mstr_sconn.sconn288_h44441004(chips)!SCONN288_H44441004_PIP-SCONN,HA!!!F168!DQ(28)!!!!
S!M_H_DQ<28>!J1G2!181!@baseboard_fab2_lib.baseboard_fab2(sch_1):page79_i111@mstr_sconn.sconn288_h44441004(chips)!SCONN288_H44441004_PIP-SCONN,HA!!!F168!DQ(29)!!!!
S!M_H_DQ<3>!J1G2!12!@baseboard_fab2_lib.baseboard_fab2(sch_1):page79_i111@mstr_sconn.sconn288_h44441004(chips)!SCONN288_H44441004_PIP-SCONN,HA!!!F168!DQ(2)!!!!
S!M_H_DQ<31>!J1G2!43!@baseboard_fab2_lib.baseboard_fab2(sch_1):page79_i111@mstr_sconn.sconn288_h44441004(chips)!SCONN288_H44441004_PIP-SCONN,HA!!!F168!DQ(30)!!!!
S!M_H_DQ<30>!J1G2!188!@baseboard_fab2_lib.baseboard_fab2(sch_1):page79_i111@mstr_sconn.sconn288_h44441004(chips)!SCONN288_H44441004_PIP-SCONN,HA!!!F168!DQ(31)!!!!
S!M_H_DQ<33>!J1G2!97!@baseboard_fab2_lib.baseboard_fab2(sch_1):page79_i111@mstr_sconn.sconn288_h44441004(chips)!SCONN288_H44441004_PIP-SCONN,HA!!!F168!DQ(32)!!!!
S!M_H_DQ<32>!J1G2!242!@baseboard_fab2_lib.baseboard_fab2(sch_1):page79_i111@mstr_sconn.sconn288_h44441004(chips)!SCONN288_H44441004_PIP-SCONN,HA!!!F168!DQ(33)!!!!
S!M_H_DQ<35>!J1G2!104!@baseboard_fab2_lib.baseboard_fab2(sch_1):page79_i111@mstr_sconn.sconn288_h44441004(chips)!SCONN288_H44441004_PIP-SCONN,HA!!!F168!DQ(34)!!!!
S!M_H_DQ<34>!J1G2!249!@baseboard_fab2_lib.baseboard_fab2(sch_1):page79_i111@mstr_sconn.sconn288_h44441004(chips)!SCONN288_H44441004_PIP-SCONN,HA!!!F168!DQ(35)!!!!
S!M_H_DQ<37>!J1G2!95!@baseboard_fab2_lib.baseboard_fab2(sch_1):page79_i111@mstr_sconn.sconn288_h44441004(chips)!SCONN288_H44441004_PIP-SCONN,HA!!!F168!DQ(36)!!!!
S!M_H_DQ<36>!J1G2!240!@baseboard_fab2_lib.baseboard_fab2(sch_1):page79_i111@mstr_sconn.sconn288_h44441004(chips)!SCONN288_H44441004_PIP-SCONN,HA!!!F168!DQ(37)!!!!
S!M_H_DQ<39>!J1G2!102!@baseboard_fab2_lib.baseboard_fab2(sch_1):page79_i111@mstr_sconn.sconn288_h44441004(chips)!SCONN288_H44441004_PIP-SCONN,HA!!!F168!DQ(38)!!!!
S!M_H_DQ<38>!J1G2!247!@baseboard_fab2_lib.baseboard_fab2(sch_1):page79_i111@mstr_sconn.sconn288_h44441004(chips)!SCONN288_H44441004_PIP-SCONN,HA!!!F168!DQ(39)!!!!
S!M_H_DQ<2>!J1G2!157!@baseboard_fab2_lib.baseboard_fab2(sch_1):page79_i111@mstr_sconn.sconn288_h44441004(chips)!SCONN288_H44441004_PIP-SCONN,HA!!!F168!DQ(3)!!!!
S!M_H_DQ<41>!J1G2!108!@baseboard_fab2_lib.baseboard_fab2(sch_1):page79_i111@mstr_sconn.sconn288_h44441004(chips)!SCONN288_H44441004_PIP-SCONN,HA!!!F168!DQ(40)!!!!
S!M_H_DQ<40>!J1G2!253!@baseboard_fab2_lib.baseboard_fab2(sch_1):page79_i111@mstr_sconn.sconn288_h44441004(chips)!SCONN288_H44441004_PIP-SCONN,HA!!!F168!DQ(41)!!!!
S!M_H_DQ<43>!J1G2!115!@baseboard_fab2_lib.baseboard_fab2(sch_1):page79_i111@mstr_sconn.sconn288_h44441004(chips)!SCONN288_H44441004_PIP-SCONN,HA!!!F168!DQ(42)!!!!
S!M_H_DQ<42>!J1G2!260!@baseboard_fab2_lib.baseboard_fab2(sch_1):page79_i111@mstr_sconn.sconn288_h44441004(chips)!SCONN288_H44441004_PIP-SCONN,HA!!!F168!DQ(43)!!!!
S!M_H_DQ<45>!J1G2!106!@baseboard_fab2_lib.baseboard_fab2(sch_1):page79_i111@mstr_sconn.sconn288_h44441004(chips)!SCONN288_H44441004_PIP-SCONN,HA!!!F168!DQ(44)!!!!
S!M_H_DQ<44>!J1G2!251!@baseboard_fab2_lib.baseboard_fab2(sch_1):page79_i111@mstr_sconn.sconn288_h44441004(chips)!SCONN288_H44441004_PIP-SCONN,HA!!!F168!DQ(45)!!!!
S!M_H_DQ<47>!J1G2!113!@baseboard_fab2_lib.baseboard_fab2(sch_1):page79_i111@mstr_sconn.sconn288_h44441004(chips)!SCONN288_H44441004_PIP-SCONN,HA!!!F168!DQ(46)!!!!
S!M_H_DQ<46>!J1G2!258!@baseboard_fab2_lib.baseboard_fab2(sch_1):page79_i111@mstr_sconn.sconn288_h44441004(chips)!SCONN288_H44441004_PIP-SCONN,HA!!!F168!DQ(47)!!!!
S!M_H_DQ<49>!J1G2!119!@baseboard_fab2_lib.baseboard_fab2(sch_1):page79_i111@mstr_sconn.sconn288_h44441004(chips)!SCONN288_H44441004_PIP-SCONN,HA!!!F168!DQ(48)!!!!
S!M_H_DQ<48>!J1G2!264!@baseboard_fab2_lib.baseboard_fab2(sch_1):page79_i111@mstr_sconn.sconn288_h44441004(chips)!SCONN288_H44441004_PIP-SCONN,HA!!!F168!DQ(49)!!!!
S!M_H_DQ<5>!J1G2!3!@baseboard_fab2_lib.baseboard_fab2(sch_1):page79_i111@mstr_sconn.sconn288_h44441004(chips)!SCONN288_H44441004_PIP-SCONN,HA!!!F168!DQ(4)!!!!
S!M_H_DQ<51>!J1G2!126!@baseboard_fab2_lib.baseboard_fab2(sch_1):page79_i111@mstr_sconn.sconn288_h44441004(chips)!SCONN288_H44441004_PIP-SCONN,HA!!!F168!DQ(50)!!!!
S!M_H_DQ<50>!J1G2!271!@baseboard_fab2_lib.baseboard_fab2(sch_1):page79_i111@mstr_sconn.sconn288_h44441004(chips)!SCONN288_H44441004_PIP-SCONN,HA!!!F168!DQ(51)!!!!
S!M_H_DQ<53>!J1G2!117!@baseboard_fab2_lib.baseboard_fab2(sch_1):page79_i111@mstr_sconn.sconn288_h44441004(chips)!SCONN288_H44441004_PIP-SCONN,HA!!!F168!DQ(52)!!!!
S!M_H_DQ<52>!J1G2!262!@baseboard_fab2_lib.baseboard_fab2(sch_1):page79_i111@mstr_sconn.sconn288_h44441004(chips)!SCONN288_H44441004_PIP-SCONN,HA!!!F168!DQ(53)!!!!
S!M_H_DQ<55>!J1G2!124!@baseboard_fab2_lib.baseboard_fab2(sch_1):page79_i111@mstr_sconn.sconn288_h44441004(chips)!SCONN288_H44441004_PIP-SCONN,HA!!!F168!DQ(54)!!!!
S!M_H_DQ<54>!J1G2!269!@baseboard_fab2_lib.baseboard_fab2(sch_1):page79_i111@mstr_sconn.sconn288_h44441004(chips)!SCONN288_H44441004_PIP-SCONN,HA!!!F168!DQ(55)!!!!
S!M_H_DQ<57>!J1G2!130!@baseboard_fab2_lib.baseboard_fab2(sch_1):page79_i111@mstr_sconn.sconn288_h44441004(chips)!SCONN288_H44441004_PIP-SCONN,HA!!!F168!DQ(56)!!!!
S!M_H_DQ<56>!J1G2!275!@baseboard_fab2_lib.baseboard_fab2(sch_1):page79_i111@mstr_sconn.sconn288_h44441004(chips)!SCONN288_H44441004_PIP-SCONN,HA!!!F168!DQ(57)!!!!
S!M_H_DQ<59>!J1G2!137!@baseboard_fab2_lib.baseboard_fab2(sch_1):page79_i111@mstr_sconn.sconn288_h44441004(chips)!SCONN288_H44441004_PIP-SCONN,HA!!!F168!DQ(58)!!!!
S!M_H_DQ<58>!J1G2!282!@baseboard_fab2_lib.baseboard_fab2(sch_1):page79_i111@mstr_sconn.sconn288_h44441004(chips)!SCONN288_H44441004_PIP-SCONN,HA!!!F168!DQ(59)!!!!
S!M_H_DQ<4>!J1G2!148!@baseboard_fab2_lib.baseboard_fab2(sch_1):page79_i111@mstr_sconn.sconn288_h44441004(chips)!SCONN288_H44441004_PIP-SCONN,HA!!!F168!DQ(5)!!!!
S!M_H_DQ<61>!J1G2!128!@baseboard_fab2_lib.baseboard_fab2(sch_1):page79_i111@mstr_sconn.sconn288_h44441004(chips)!SCONN288_H44441004_PIP-SCONN,HA!!!F168!DQ(60)!!!!
S!M_H_DQ<60>!J1G2!273!@baseboard_fab2_lib.baseboard_fab2(sch_1):page79_i111@mstr_sconn.sconn288_h44441004(chips)!SCONN288_H44441004_PIP-SCONN,HA!!!F168!DQ(61)!!!!
S!M_H_DQ<63>!J1G2!135!@baseboard_fab2_lib.baseboard_fab2(sch_1):page79_i111@mstr_sconn.sconn288_h44441004(chips)!SCONN288_H44441004_PIP-SCONN,HA!!!F168!DQ(62)!!!!
S!M_H_DQ<62>!J1G2!280!@baseboard_fab2_lib.baseboard_fab2(sch_1):page79_i111@mstr_sconn.sconn288_h44441004(chips)!SCONN288_H44441004_PIP-SCONN,HA!!!F168!DQ(63)!!!!
S!M_H_DQ<7>!J1G2!10!@baseboard_fab2_lib.baseboard_fab2(sch_1):page79_i111@mstr_sconn.sconn288_h44441004(chips)!SCONN288_H44441004_PIP-SCONN,HA!!!F168!DQ(6)!!!!
S!M_H_DQ<6>!J1G2!155!@baseboard_fab2_lib.baseboard_fab2(sch_1):page79_i111@mstr_sconn.sconn288_h44441004(chips)!SCONN288_H44441004_PIP-SCONN,HA!!!F168!DQ(7)!!!!
S!M_H_DQ<9>!J1G2!16!@baseboard_fab2_lib.baseboard_fab2(sch_1):page79_i111@mstr_sconn.sconn288_h44441004(chips)!SCONN288_H44441004_PIP-SCONN,HA!!!F168!DQ(8)!!!!
S!M_H_DQ<8>!J1G2!161!@baseboard_fab2_lib.baseboard_fab2(sch_1):page79_i111@mstr_sconn.sconn288_h44441004(chips)!SCONN288_H44441004_PIP-SCONN,HA!!!F168!DQ(9)!!!!
S!FM_DIMM_EVENT_COD_N!J1G2!78!@baseboard_fab2_lib.baseboard_fab2(sch_1):page79_i111@mstr_sconn.sconn288_h44441004(chips)!SCONN288_H44441004_PIP-SCONN,HA!!!F168!EVENT_N!!!!
S!M_H_ODT<0>!J1G2!87!@baseboard_fab2_lib.baseboard_fab2(sch_1):page79_i111@mstr_sconn.sconn288_h44441004(chips)!SCONN288_H44441004_PIP-SCONN,HA!!!F168!ODT(0)!!!!
S!M_H_ODT<1>!J1G2!91!@baseboard_fab2_lib.baseboard_fab2(sch_1):page79_i111@mstr_sconn.sconn288_h44441004(chips)!SCONN288_H44441004_PIP-SCONN,HA!!!F168!ODT(1)!!!!
S!M_H_PAR!J1G2!222!@baseboard_fab2_lib.baseboard_fab2(sch_1):page79_i111@mstr_sconn.sconn288_h44441004(chips)!SCONN288_H44441004_PIP-SCONN,HA!!!F168!PAR!!!!
S!M_GHJ_RST_N!J1G2!58!@baseboard_fab2_lib.baseboard_fab2(sch_1):page79_i111@mstr_sconn.sconn288_h44441004(chips)!SCONN288_H44441004_PIP-SCONN,HA!!!F168!RESET_N!!!!
S!TP_CH_H_DIMM_H0_RFU_0!J1G2!205!@baseboard_fab2_lib.baseboard_fab2(sch_1):page79_i111@mstr_sconn.sconn288_h44441004(chips)!SCONN288_H44441004_PIP-SCONN,HA!!!F168!RFU(0)!!!!
S!TP_CH_H_DIMM_H0_RFU_1!J1G2!227!@baseboard_fab2_lib.baseboard_fab2(sch_1):page79_i111@mstr_sconn.sconn288_h44441004(chips)!SCONN288_H44441004_PIP-SCONN,HA!!!F168!RFU(1)!!!!
S!TP_CH_H_DIMM_H0_RFU_2!J1G2!144!@baseboard_fab2_lib.baseboard_fab2(sch_1):page79_i111@mstr_sconn.sconn288_h44441004(chips)!SCONN288_H44441004_PIP-SCONN,HA!!!F168!RFU(2)!!!!
S!M_H_CS_N<0>!J1G2!84!@baseboard_fab2_lib.baseboard_fab2(sch_1):page79_i111@mstr_sconn.sconn288_h44441004(chips)!SCONN288_H44441004_PIP-SCONN,HA!!!F168!S0_N!!!!
S!M_H_CS_N<1>!J1G2!89!@baseboard_fab2_lib.baseboard_fab2(sch_1):page79_i111@mstr_sconn.sconn288_h44441004(chips)!SCONN288_H44441004_PIP-SCONN,HA!!!F168!S1_N!!!!
S!M_H_CS_N<2>!J1G2!93!@baseboard_fab2_lib.baseboard_fab2(sch_1):page79_i111@mstr_sconn.sconn288_h44441004(chips)!SCONN288_H44441004_PIP-SCONN,HA!!!F168!S2_N_C(0)!!!!
S!M_H_CS_N<3>!J1G2!237!@baseboard_fab2_lib.baseboard_fab2(sch_1):page79_i111@mstr_sconn.sconn288_h44441004(chips)!SCONN288_H44441004_PIP-SCONN,HA!!!F168!S3_N_C(1)!!!!
S!GND!J1G2!139!@baseboard_fab2_lib.baseboard_fab2(sch_1):page79_i111@mstr_sconn.sconn288_h44441004(chips)!SCONN288_H44441004_PIP-SCONN,HA!!!F168!SA(0)!!!!
S!PVPP_GHJ!J1G2!140!@baseboard_fab2_lib.baseboard_fab2(sch_1):page79_i111@mstr_sconn.sconn288_h44441004(chips)!SCONN288_H44441004_PIP-SCONN,HA!!!F168!SA(1)!!!!
S!GND!J1G2!238!@baseboard_fab2_lib.baseboard_fab2(sch_1):page79_i111@mstr_sconn.sconn288_h44441004(chips)!SCONN288_H44441004_PIP-SCONN,HA!!!F168!SA(2)!!!!
S!FM_ADR_COMPLETE_GHJ_N!J1G2!230!@baseboard_fab2_lib.baseboard_fab2(sch_1):page79_i111@mstr_sconn.sconn288_h44441004(chips)!SCONN288_H44441004_PIP-SCONN,HA!!!F168!SAVE_N_NC!!!!
S!SMB_DDR_GHJ_VPP_SCL!J1G2!141!@baseboard_fab2_lib.baseboard_fab2(sch_1):page79_i111@mstr_sconn.sconn288_h44441004(chips)!SCONN288_H44441004_PIP-SCONN,HA!!!F168!SCL!!!!
S!SMB_DDR_GHJ_VPP_SDA!J1G2!285!@baseboard_fab2_lib.baseboard_fab2(sch_1):page79_i111@mstr_sconn.sconn288_h44441004(chips)!SCONN288_H44441004_PIP-SCONN,HA!!!F168!SDA!!!!
S!PVPP_GHJ!J1G2!284!@baseboard_fab2_lib.baseboard_fab2(sch_1):page79_i111@mstr_sconn.sconn288_h44441004(chips)!SCONN288_H44441004_PIP-SCONN,HA!!!F168!VDDSPD!!!!
S!M_H_VREF!J1G2!146!@baseboard_fab2_lib.baseboard_fab2(sch_1):page79_i111@mstr_sconn.sconn288_h44441004(chips)!SCONN288_H44441004_PIP-SCONN,HA!!!F168!VREFCA!!!!
S!M_H_DQS_DN<0>!J1G2!152!@baseboard_fab2_lib.baseboard_fab2(sch_1):page79_i64@mstr_sconn.sconn288_h44441004(chips)!SCONN288_H44441004_PIP-SCONN,HA!!!F167!DQS0N!!!!
S!M_H_DQS_DP<0>!J1G2!153!@baseboard_fab2_lib.baseboard_fab2(sch_1):page79_i64@mstr_sconn.sconn288_h44441004(chips)!SCONN288_H44441004_PIP-SCONN,HA!!!F167!DQS0P!!!!
S!M_H_DQS_DN<10>!J1G2!19!@baseboard_fab2_lib.baseboard_fab2(sch_1):page79_i64@mstr_sconn.sconn288_h44441004(chips)!SCONN288_H44441004_PIP-SCONN,HA!!!F167!DQS10N!!!!
S!M_H_DQS_DP<10>!J1G2!18!@baseboard_fab2_lib.baseboard_fab2(sch_1):page79_i64@mstr_sconn.sconn288_h44441004(chips)!SCONN288_H44441004_PIP-SCONN,HA!!!F167!DQS10P!!!!
S!M_H_DQS_DN<11>!J1G2!30!@baseboard_fab2_lib.baseboard_fab2(sch_1):page79_i64@mstr_sconn.sconn288_h44441004(chips)!SCONN288_H44441004_PIP-SCONN,HA!!!F167!DQS11N!!!!
S!M_H_DQS_DP<11>!J1G2!29!@baseboard_fab2_lib.baseboard_fab2(sch_1):page79_i64@mstr_sconn.sconn288_h44441004(chips)!SCONN288_H44441004_PIP-SCONN,HA!!!F167!DQS11P!!!!
S!M_H_DQS_DN<12>!J1G2!41!@baseboard_fab2_lib.baseboard_fab2(sch_1):page79_i64@mstr_sconn.sconn288_h44441004(chips)!SCONN288_H44441004_PIP-SCONN,HA!!!F167!DQS12N!!!!
S!M_H_DQS_DP<12>!J1G2!40!@baseboard_fab2_lib.baseboard_fab2(sch_1):page79_i64@mstr_sconn.sconn288_h44441004(chips)!SCONN288_H44441004_PIP-SCONN,HA!!!F167!DQS12P!!!!
S!M_H_DQS_DN<13>!J1G2!100!@baseboard_fab2_lib.baseboard_fab2(sch_1):page79_i64@mstr_sconn.sconn288_h44441004(chips)!SCONN288_H44441004_PIP-SCONN,HA!!!F167!DQS13N!!!!
S!M_H_DQS_DP<13>!J1G2!99!@baseboard_fab2_lib.baseboard_fab2(sch_1):page79_i64@mstr_sconn.sconn288_h44441004(chips)!SCONN288_H44441004_PIP-SCONN,HA!!!F167!DQS13P!!!!
S!M_H_DQS_DN<14>!J1G2!111!@baseboard_fab2_lib.baseboard_fab2(sch_1):page79_i64@mstr_sconn.sconn288_h44441004(chips)!SCONN288_H44441004_PIP-SCONN,HA!!!F167!DQS14N!!!!
S!M_H_DQS_DP<14>!J1G2!110!@baseboard_fab2_lib.baseboard_fab2(sch_1):page79_i64@mstr_sconn.sconn288_h44441004(chips)!SCONN288_H44441004_PIP-SCONN,HA!!!F167!DQS14P!!!!
S!M_H_DQS_DN<15>!J1G2!122!@baseboard_fab2_lib.baseboard_fab2(sch_1):page79_i64@mstr_sconn.sconn288_h44441004(chips)!SCONN288_H44441004_PIP-SCONN,HA!!!F167!DQS15N!!!!
S!M_H_DQS_DP<15>!J1G2!121!@baseboard_fab2_lib.baseboard_fab2(sch_1):page79_i64@mstr_sconn.sconn288_h44441004(chips)!SCONN288_H44441004_PIP-SCONN,HA!!!F167!DQS15P!!!!
S!M_H_DQS_DN<16>!J1G2!133!@baseboard_fab2_lib.baseboard_fab2(sch_1):page79_i64@mstr_sconn.sconn288_h44441004(chips)!SCONN288_H44441004_PIP-SCONN,HA!!!F167!DQS16N!!!!
S!M_H_DQS_DP<16>!J1G2!132!@baseboard_fab2_lib.baseboard_fab2(sch_1):page79_i64@mstr_sconn.sconn288_h44441004(chips)!SCONN288_H44441004_PIP-SCONN,HA!!!F167!DQS16P!!!!
S!M_H_DQS_DN<17>!J1G2!52!@baseboard_fab2_lib.baseboard_fab2(sch_1):page79_i64@mstr_sconn.sconn288_h44441004(chips)!SCONN288_H44441004_PIP-SCONN,HA!!!F167!DQS17N!!!!
S!M_H_DQS_DP<17>!J1G2!51!@baseboard_fab2_lib.baseboard_fab2(sch_1):page79_i64@mstr_sconn.sconn288_h44441004(chips)!SCONN288_H44441004_PIP-SCONN,HA!!!F167!DQS17P!!!!
S!M_H_DQS_DN<1>!J1G2!163!@baseboard_fab2_lib.baseboard_fab2(sch_1):page79_i64@mstr_sconn.sconn288_h44441004(chips)!SCONN288_H44441004_PIP-SCONN,HA!!!F167!DQS1N!!!!
S!M_H_DQS_DP<1>!J1G2!164!@baseboard_fab2_lib.baseboard_fab2(sch_1):page79_i64@mstr_sconn.sconn288_h44441004(chips)!SCONN288_H44441004_PIP-SCONN,HA!!!F167!DQS1P!!!!
S!M_H_DQS_DN<2>!J1G2!174!@baseboard_fab2_lib.baseboard_fab2(sch_1):page79_i64@mstr_sconn.sconn288_h44441004(chips)!SCONN288_H44441004_PIP-SCONN,HA!!!F167!DQS2N!!!!
S!M_H_DQS_DP<2>!J1G2!175!@baseboard_fab2_lib.baseboard_fab2(sch_1):page79_i64@mstr_sconn.sconn288_h44441004(chips)!SCONN288_H44441004_PIP-SCONN,HA!!!F167!DQS2P!!!!
S!M_H_DQS_DN<3>!J1G2!185!@baseboard_fab2_lib.baseboard_fab2(sch_1):page79_i64@mstr_sconn.sconn288_h44441004(chips)!SCONN288_H44441004_PIP-SCONN,HA!!!F167!DQS3N!!!!
S!M_H_DQS_DP<3>!J1G2!186!@baseboard_fab2_lib.baseboard_fab2(sch_1):page79_i64@mstr_sconn.sconn288_h44441004(chips)!SCONN288_H44441004_PIP-SCONN,HA!!!F167!DQS3P!!!!
S!M_H_DQS_DN<4>!J1G2!244!@baseboard_fab2_lib.baseboard_fab2(sch_1):page79_i64@mstr_sconn.sconn288_h44441004(chips)!SCONN288_H44441004_PIP-SCONN,HA!!!F167!DQS4N!!!!
S!M_H_DQS_DP<4>!J1G2!245!@baseboard_fab2_lib.baseboard_fab2(sch_1):page79_i64@mstr_sconn.sconn288_h44441004(chips)!SCONN288_H44441004_PIP-SCONN,HA!!!F167!DQS4P!!!!
S!M_H_DQS_DN<5>!J1G2!255!@baseboard_fab2_lib.baseboard_fab2(sch_1):page79_i64@mstr_sconn.sconn288_h44441004(chips)!SCONN288_H44441004_PIP-SCONN,HA!!!F167!DQS5N!!!!
S!M_H_DQS_DP<5>!J1G2!256!@baseboard_fab2_lib.baseboard_fab2(sch_1):page79_i64@mstr_sconn.sconn288_h44441004(chips)!SCONN288_H44441004_PIP-SCONN,HA!!!F167!DQS5P!!!!
S!M_H_DQS_DN<6>!J1G2!266!@baseboard_fab2_lib.baseboard_fab2(sch_1):page79_i64@mstr_sconn.sconn288_h44441004(chips)!SCONN288_H44441004_PIP-SCONN,HA!!!F167!DQS6N!!!!
S!M_H_DQS_DP<6>!J1G2!267!@baseboard_fab2_lib.baseboard_fab2(sch_1):page79_i64@mstr_sconn.sconn288_h44441004(chips)!SCONN288_H44441004_PIP-SCONN,HA!!!F167!DQS6P!!!!
S!M_H_DQS_DN<7>!J1G2!277!@baseboard_fab2_lib.baseboard_fab2(sch_1):page79_i64@mstr_sconn.sconn288_h44441004(chips)!SCONN288_H44441004_PIP-SCONN,HA!!!F167!DQS7N!!!!
S!M_H_DQS_DP<7>!J1G2!278!@baseboard_fab2_lib.baseboard_fab2(sch_1):page79_i64@mstr_sconn.sconn288_h44441004(chips)!SCONN288_H44441004_PIP-SCONN,HA!!!F167!DQS7P!!!!
S!M_H_DQS_DN<8>!J1G2!196!@baseboard_fab2_lib.baseboard_fab2(sch_1):page79_i64@mstr_sconn.sconn288_h44441004(chips)!SCONN288_H44441004_PIP-SCONN,HA!!!F167!DQS8N!!!!
S!M_H_DQS_DP<8>!J1G2!197!@baseboard_fab2_lib.baseboard_fab2(sch_1):page79_i64@mstr_sconn.sconn288_h44441004(chips)!SCONN288_H44441004_PIP-SCONN,HA!!!F167!DQS8P!!!!
S!M_H_DQS_DN<9>!J1G2!8!@baseboard_fab2_lib.baseboard_fab2(sch_1):page79_i64@mstr_sconn.sconn288_h44441004(chips)!SCONN288_H44441004_PIP-SCONN,HA!!!F167!DQS9N!!!!
S!M_H_DQS_DP<9>!J1G2!7!@baseboard_fab2_lib.baseboard_fab2(sch_1):page79_i64@mstr_sconn.sconn288_h44441004(chips)!SCONN288_H44441004_PIP-SCONN,HA!!!F167!DQS9P!!!!
S!GND!J1G2!283!@baseboard_fab2_lib.baseboard_fab2(sch_1):page79_i43@mstr_sconn.sconn288_h44441004(chips)!SCONN288_H44441004_PIP-SCONN,HA!!!F166!VSS(0)!!!!
S!GND!J1G2!261!@baseboard_fab2_lib.baseboard_fab2(sch_1):page79_i43@mstr_sconn.sconn288_h44441004(chips)!SCONN288_H44441004_PIP-SCONN,HA!!!F166!VSS(10)!!!!
S!GND!J1G2!259!@baseboard_fab2_lib.baseboard_fab2(sch_1):page79_i43@mstr_sconn.sconn288_h44441004(chips)!SCONN288_H44441004_PIP-SCONN,HA!!!F166!VSS(11)!!!!
S!GND!J1G2!257!@baseboard_fab2_lib.baseboard_fab2(sch_1):page79_i43@mstr_sconn.sconn288_h44441004(chips)!SCONN288_H44441004_PIP-SCONN,HA!!!F166!VSS(12)!!!!
S!GND!J1G2!254!@baseboard_fab2_lib.baseboard_fab2(sch_1):page79_i43@mstr_sconn.sconn288_h44441004(chips)!SCONN288_H44441004_PIP-SCONN,HA!!!F166!VSS(13)!!!!
S!GND!J1G2!252!@baseboard_fab2_lib.baseboard_fab2(sch_1):page79_i43@mstr_sconn.sconn288_h44441004(chips)!SCONN288_H44441004_PIP-SCONN,HA!!!F166!VSS(14)!!!!
S!GND!J1G2!250!@baseboard_fab2_lib.baseboard_fab2(sch_1):page79_i43@mstr_sconn.sconn288_h44441004(chips)!SCONN288_H44441004_PIP-SCONN,HA!!!F166!VSS(15)!!!!
S!GND!J1G2!248!@baseboard_fab2_lib.baseboard_fab2(sch_1):page79_i43@mstr_sconn.sconn288_h44441004(chips)!SCONN288_H44441004_PIP-SCONN,HA!!!F166!VSS(16)!!!!
S!GND!J1G2!246!@baseboard_fab2_lib.baseboard_fab2(sch_1):page79_i43@mstr_sconn.sconn288_h44441004(chips)!SCONN288_H44441004_PIP-SCONN,HA!!!F166!VSS(17)!!!!
S!GND!J1G2!243!@baseboard_fab2_lib.baseboard_fab2(sch_1):page79_i43@mstr_sconn.sconn288_h44441004(chips)!SCONN288_H44441004_PIP-SCONN,HA!!!F166!VSS(18)!!!!
S!GND!J1G2!241!@baseboard_fab2_lib.baseboard_fab2(sch_1):page79_i43@mstr_sconn.sconn288_h44441004(chips)!SCONN288_H44441004_PIP-SCONN,HA!!!F166!VSS(19)!!!!
S!GND!J1G2!281!@baseboard_fab2_lib.baseboard_fab2(sch_1):page79_i43@mstr_sconn.sconn288_h44441004(chips)!SCONN288_H44441004_PIP-SCONN,HA!!!F166!VSS(1)!!!!
S!GND!J1G2!239!@baseboard_fab2_lib.baseboard_fab2(sch_1):page79_i43@mstr_sconn.sconn288_h44441004(chips)!SCONN288_H44441004_PIP-SCONN,HA!!!F166!VSS(20)!!!!
S!GND!J1G2!202!@baseboard_fab2_lib.baseboard_fab2(sch_1):page79_i43@mstr_sconn.sconn288_h44441004(chips)!SCONN288_H44441004_PIP-SCONN,HA!!!F166!VSS(21)!!!!
S!GND!J1G2!200!@baseboard_fab2_lib.baseboard_fab2(sch_1):page79_i43@mstr_sconn.sconn288_h44441004(chips)!SCONN288_H44441004_PIP-SCONN,HA!!!F166!VSS(22)!!!!
S!GND!J1G2!198!@baseboard_fab2_lib.baseboard_fab2(sch_1):page79_i43@mstr_sconn.sconn288_h44441004(chips)!SCONN288_H44441004_PIP-SCONN,HA!!!F166!VSS(23)!!!!
S!GND!J1G2!195!@baseboard_fab2_lib.baseboard_fab2(sch_1):page79_i43@mstr_sconn.sconn288_h44441004(chips)!SCONN288_H44441004_PIP-SCONN,HA!!!F166!VSS(24)!!!!
S!GND!J1G2!193!@baseboard_fab2_lib.baseboard_fab2(sch_1):page79_i43@mstr_sconn.sconn288_h44441004(chips)!SCONN288_H44441004_PIP-SCONN,HA!!!F166!VSS(25)!!!!
S!GND!J1G2!191!@baseboard_fab2_lib.baseboard_fab2(sch_1):page79_i43@mstr_sconn.sconn288_h44441004(chips)!SCONN288_H44441004_PIP-SCONN,HA!!!F166!VSS(26)!!!!
S!GND!J1G2!189!@baseboard_fab2_lib.baseboard_fab2(sch_1):page79_i43@mstr_sconn.sconn288_h44441004(chips)!SCONN288_H44441004_PIP-SCONN,HA!!!F166!VSS(27)!!!!
S!GND!J1G2!187!@baseboard_fab2_lib.baseboard_fab2(sch_1):page79_i43@mstr_sconn.sconn288_h44441004(chips)!SCONN288_H44441004_PIP-SCONN,HA!!!F166!VSS(28)!!!!
S!GND!J1G2!184!@baseboard_fab2_lib.baseboard_fab2(sch_1):page79_i43@mstr_sconn.sconn288_h44441004(chips)!SCONN288_H44441004_PIP-SCONN,HA!!!F166!VSS(29)!!!!
S!GND!J1G2!279!@baseboard_fab2_lib.baseboard_fab2(sch_1):page79_i43@mstr_sconn.sconn288_h44441004(chips)!SCONN288_H44441004_PIP-SCONN,HA!!!F166!VSS(2)!!!!
S!GND!J1G2!182!@baseboard_fab2_lib.baseboard_fab2(sch_1):page79_i43@mstr_sconn.sconn288_h44441004(chips)!SCONN288_H44441004_PIP-SCONN,HA!!!F166!VSS(30)!!!!
S!GND!J1G2!180!@baseboard_fab2_lib.baseboard_fab2(sch_1):page79_i43@mstr_sconn.sconn288_h44441004(chips)!SCONN288_H44441004_PIP-SCONN,HA!!!F166!VSS(31)!!!!
S!GND!J1G2!178!@baseboard_fab2_lib.baseboard_fab2(sch_1):page79_i43@mstr_sconn.sconn288_h44441004(chips)!SCONN288_H44441004_PIP-SCONN,HA!!!F166!VSS(32)!!!!
S!GND!J1G2!176!@baseboard_fab2_lib.baseboard_fab2(sch_1):page79_i43@mstr_sconn.sconn288_h44441004(chips)!SCONN288_H44441004_PIP-SCONN,HA!!!F166!VSS(33)!!!!
S!GND!J1G2!173!@baseboard_fab2_lib.baseboard_fab2(sch_1):page79_i43@mstr_sconn.sconn288_h44441004(chips)!SCONN288_H44441004_PIP-SCONN,HA!!!F166!VSS(34)!!!!
S!GND!J1G2!171!@baseboard_fab2_lib.baseboard_fab2(sch_1):page79_i43@mstr_sconn.sconn288_h44441004(chips)!SCONN288_H44441004_PIP-SCONN,HA!!!F166!VSS(35)!!!!
S!GND!J1G2!169!@baseboard_fab2_lib.baseboard_fab2(sch_1):page79_i43@mstr_sconn.sconn288_h44441004(chips)!SCONN288_H44441004_PIP-SCONN,HA!!!F166!VSS(36)!!!!
S!GND!J1G2!167!@baseboard_fab2_lib.baseboard_fab2(sch_1):page79_i43@mstr_sconn.sconn288_h44441004(chips)!SCONN288_H44441004_PIP-SCONN,HA!!!F166!VSS(37)!!!!
S!GND!J1G2!165!@baseboard_fab2_lib.baseboard_fab2(sch_1):page79_i43@mstr_sconn.sconn288_h44441004(chips)!SCONN288_H44441004_PIP-SCONN,HA!!!F166!VSS(38)!!!!
S!GND!J1G2!162!@baseboard_fab2_lib.baseboard_fab2(sch_1):page79_i43@mstr_sconn.sconn288_h44441004(chips)!SCONN288_H44441004_PIP-SCONN,HA!!!F166!VSS(39)!!!!
S!GND!J1G2!276!@baseboard_fab2_lib.baseboard_fab2(sch_1):page79_i43@mstr_sconn.sconn288_h44441004(chips)!SCONN288_H44441004_PIP-SCONN,HA!!!F166!VSS(3)!!!!
S!GND!J1G2!160!@baseboard_fab2_lib.baseboard_fab2(sch_1):page79_i43@mstr_sconn.sconn288_h44441004(chips)!SCONN288_H44441004_PIP-SCONN,HA!!!F166!VSS(40)!!!!
S!GND!J1G2!158!@baseboard_fab2_lib.baseboard_fab2(sch_1):page79_i43@mstr_sconn.sconn288_h44441004(chips)!SCONN288_H44441004_PIP-SCONN,HA!!!F166!VSS(41)!!!!
S!GND!J1G2!156!@baseboard_fab2_lib.baseboard_fab2(sch_1):page79_i43@mstr_sconn.sconn288_h44441004(chips)!SCONN288_H44441004_PIP-SCONN,HA!!!F166!VSS(42)!!!!
S!GND!J1G2!154!@baseboard_fab2_lib.baseboard_fab2(sch_1):page79_i43@mstr_sconn.sconn288_h44441004(chips)!SCONN288_H44441004_PIP-SCONN,HA!!!F166!VSS(43)!!!!
S!GND!J1G2!151!@baseboard_fab2_lib.baseboard_fab2(sch_1):page79_i43@mstr_sconn.sconn288_h44441004(chips)!SCONN288_H44441004_PIP-SCONN,HA!!!F166!VSS(44)!!!!
S!GND!J1G2!149!@baseboard_fab2_lib.baseboard_fab2(sch_1):page79_i43@mstr_sconn.sconn288_h44441004(chips)!SCONN288_H44441004_PIP-SCONN,HA!!!F166!VSS(45)!!!!
S!GND!J1G2!147!@baseboard_fab2_lib.baseboard_fab2(sch_1):page79_i43@mstr_sconn.sconn288_h44441004(chips)!SCONN288_H44441004_PIP-SCONN,HA!!!F166!VSS(46)!!!!
S!GND!J1G2!138!@baseboard_fab2_lib.baseboard_fab2(sch_1):page79_i43@mstr_sconn.sconn288_h44441004(chips)!SCONN288_H44441004_PIP-SCONN,HA!!!F166!VSS(47)!!!!
S!GND!J1G2!136!@baseboard_fab2_lib.baseboard_fab2(sch_1):page79_i43@mstr_sconn.sconn288_h44441004(chips)!SCONN288_H44441004_PIP-SCONN,HA!!!F166!VSS(48)!!!!
S!GND!J1G2!134!@baseboard_fab2_lib.baseboard_fab2(sch_1):page79_i43@mstr_sconn.sconn288_h44441004(chips)!SCONN288_H44441004_PIP-SCONN,HA!!!F166!VSS(49)!!!!
S!GND!J1G2!274!@baseboard_fab2_lib.baseboard_fab2(sch_1):page79_i43@mstr_sconn.sconn288_h44441004(chips)!SCONN288_H44441004_PIP-SCONN,HA!!!F166!VSS(4)!!!!
S!GND!J1G2!131!@baseboard_fab2_lib.baseboard_fab2(sch_1):page79_i43@mstr_sconn.sconn288_h44441004(chips)!SCONN288_H44441004_PIP-SCONN,HA!!!F166!VSS(50)!!!!
S!GND!J1G2!129!@baseboard_fab2_lib.baseboard_fab2(sch_1):page79_i43@mstr_sconn.sconn288_h44441004(chips)!SCONN288_H44441004_PIP-SCONN,HA!!!F166!VSS(51)!!!!
S!GND!J1G2!127!@baseboard_fab2_lib.baseboard_fab2(sch_1):page79_i43@mstr_sconn.sconn288_h44441004(chips)!SCONN288_H44441004_PIP-SCONN,HA!!!F166!VSS(52)!!!!
S!GND!J1G2!125!@baseboard_fab2_lib.baseboard_fab2(sch_1):page79_i43@mstr_sconn.sconn288_h44441004(chips)!SCONN288_H44441004_PIP-SCONN,HA!!!F166!VSS(53)!!!!
S!GND!J1G2!123!@baseboard_fab2_lib.baseboard_fab2(sch_1):page79_i43@mstr_sconn.sconn288_h44441004(chips)!SCONN288_H44441004_PIP-SCONN,HA!!!F166!VSS(54)!!!!
S!GND!J1G2!120!@baseboard_fab2_lib.baseboard_fab2(sch_1):page79_i43@mstr_sconn.sconn288_h44441004(chips)!SCONN288_H44441004_PIP-SCONN,HA!!!F166!VSS(55)!!!!
S!GND!J1G2!118!@baseboard_fab2_lib.baseboard_fab2(sch_1):page79_i43@mstr_sconn.sconn288_h44441004(chips)!SCONN288_H44441004_PIP-SCONN,HA!!!F166!VSS(56)!!!!
S!GND!J1G2!116!@baseboard_fab2_lib.baseboard_fab2(sch_1):page79_i43@mstr_sconn.sconn288_h44441004(chips)!SCONN288_H44441004_PIP-SCONN,HA!!!F166!VSS(57)!!!!
S!GND!J1G2!114!@baseboard_fab2_lib.baseboard_fab2(sch_1):page79_i43@mstr_sconn.sconn288_h44441004(chips)!SCONN288_H44441004_PIP-SCONN,HA!!!F166!VSS(58)!!!!
S!GND!J1G2!112!@baseboard_fab2_lib.baseboard_fab2(sch_1):page79_i43@mstr_sconn.sconn288_h44441004(chips)!SCONN288_H44441004_PIP-SCONN,HA!!!F166!VSS(59)!!!!
S!GND!J1G2!272!@baseboard_fab2_lib.baseboard_fab2(sch_1):page79_i43@mstr_sconn.sconn288_h44441004(chips)!SCONN288_H44441004_PIP-SCONN,HA!!!F166!VSS(5)!!!!
S!GND!J1G2!109!@baseboard_fab2_lib.baseboard_fab2(sch_1):page79_i43@mstr_sconn.sconn288_h44441004(chips)!SCONN288_H44441004_PIP-SCONN,HA!!!F166!VSS(60)!!!!
S!GND!J1G2!107!@baseboard_fab2_lib.baseboard_fab2(sch_1):page79_i43@mstr_sconn.sconn288_h44441004(chips)!SCONN288_H44441004_PIP-SCONN,HA!!!F166!VSS(61)!!!!
S!GND!J1G2!105!@baseboard_fab2_lib.baseboard_fab2(sch_1):page79_i43@mstr_sconn.sconn288_h44441004(chips)!SCONN288_H44441004_PIP-SCONN,HA!!!F166!VSS(62)!!!!
S!GND!J1G2!103!@baseboard_fab2_lib.baseboard_fab2(sch_1):page79_i43@mstr_sconn.sconn288_h44441004(chips)!SCONN288_H44441004_PIP-SCONN,HA!!!F166!VSS(63)!!!!
S!GND!J1G2!101!@baseboard_fab2_lib.baseboard_fab2(sch_1):page79_i43@mstr_sconn.sconn288_h44441004(chips)!SCONN288_H44441004_PIP-SCONN,HA!!!F166!VSS(64)!!!!
S!GND!J1G2!98!@baseboard_fab2_lib.baseboard_fab2(sch_1):page79_i43@mstr_sconn.sconn288_h44441004(chips)!SCONN288_H44441004_PIP-SCONN,HA!!!F166!VSS(65)!!!!
S!GND!J1G2!96!@baseboard_fab2_lib.baseboard_fab2(sch_1):page79_i43@mstr_sconn.sconn288_h44441004(chips)!SCONN288_H44441004_PIP-SCONN,HA!!!F166!VSS(66)!!!!
S!GND!J1G2!94!@baseboard_fab2_lib.baseboard_fab2(sch_1):page79_i43@mstr_sconn.sconn288_h44441004(chips)!SCONN288_H44441004_PIP-SCONN,HA!!!F166!VSS(67)!!!!
S!GND!J1G2!57!@baseboard_fab2_lib.baseboard_fab2(sch_1):page79_i43@mstr_sconn.sconn288_h44441004(chips)!SCONN288_H44441004_PIP-SCONN,HA!!!F166!VSS(68)!!!!
S!GND!J1G2!55!@baseboard_fab2_lib.baseboard_fab2(sch_1):page79_i43@mstr_sconn.sconn288_h44441004(chips)!SCONN288_H44441004_PIP-SCONN,HA!!!F166!VSS(69)!!!!
S!GND!J1G2!270!@baseboard_fab2_lib.baseboard_fab2(sch_1):page79_i43@mstr_sconn.sconn288_h44441004(chips)!SCONN288_H44441004_PIP-SCONN,HA!!!F166!VSS(6)!!!!
S!GND!J1G2!53!@baseboard_fab2_lib.baseboard_fab2(sch_1):page79_i43@mstr_sconn.sconn288_h44441004(chips)!SCONN288_H44441004_PIP-SCONN,HA!!!F166!VSS(70)!!!!
S!GND!J1G2!50!@baseboard_fab2_lib.baseboard_fab2(sch_1):page79_i43@mstr_sconn.sconn288_h44441004(chips)!SCONN288_H44441004_PIP-SCONN,HA!!!F166!VSS(71)!!!!
S!GND!J1G2!48!@baseboard_fab2_lib.baseboard_fab2(sch_1):page79_i43@mstr_sconn.sconn288_h44441004(chips)!SCONN288_H44441004_PIP-SCONN,HA!!!F166!VSS(72)!!!!
S!GND!J1G2!46!@baseboard_fab2_lib.baseboard_fab2(sch_1):page79_i43@mstr_sconn.sconn288_h44441004(chips)!SCONN288_H44441004_PIP-SCONN,HA!!!F166!VSS(73)!!!!
S!GND!J1G2!44!@baseboard_fab2_lib.baseboard_fab2(sch_1):page79_i43@mstr_sconn.sconn288_h44441004(chips)!SCONN288_H44441004_PIP-SCONN,HA!!!F166!VSS(74)!!!!
S!GND!J1G2!42!@baseboard_fab2_lib.baseboard_fab2(sch_1):page79_i43@mstr_sconn.sconn288_h44441004(chips)!SCONN288_H44441004_PIP-SCONN,HA!!!F166!VSS(75)!!!!
S!GND!J1G2!39!@baseboard_fab2_lib.baseboard_fab2(sch_1):page79_i43@mstr_sconn.sconn288_h44441004(chips)!SCONN288_H44441004_PIP-SCONN,HA!!!F166!VSS(76)!!!!
S!GND!J1G2!37!@baseboard_fab2_lib.baseboard_fab2(sch_1):page79_i43@mstr_sconn.sconn288_h44441004(chips)!SCONN288_H44441004_PIP-SCONN,HA!!!F166!VSS(77)!!!!
S!GND!J1G2!35!@baseboard_fab2_lib.baseboard_fab2(sch_1):page79_i43@mstr_sconn.sconn288_h44441004(chips)!SCONN288_H44441004_PIP-SCONN,HA!!!F166!VSS(78)!!!!
S!GND!J1G2!33!@baseboard_fab2_lib.baseboard_fab2(sch_1):page79_i43@mstr_sconn.sconn288_h44441004(chips)!SCONN288_H44441004_PIP-SCONN,HA!!!F166!VSS(79)!!!!
S!GND!J1G2!268!@baseboard_fab2_lib.baseboard_fab2(sch_1):page79_i43@mstr_sconn.sconn288_h44441004(chips)!SCONN288_H44441004_PIP-SCONN,HA!!!F166!VSS(7)!!!!
S!GND!J1G2!31!@baseboard_fab2_lib.baseboard_fab2(sch_1):page79_i43@mstr_sconn.sconn288_h44441004(chips)!SCONN288_H44441004_PIP-SCONN,HA!!!F166!VSS(80)!!!!
S!GND!J1G2!28!@baseboard_fab2_lib.baseboard_fab2(sch_1):page79_i43@mstr_sconn.sconn288_h44441004(chips)!SCONN288_H44441004_PIP-SCONN,HA!!!F166!VSS(81)!!!!
S!GND!J1G2!26!@baseboard_fab2_lib.baseboard_fab2(sch_1):page79_i43@mstr_sconn.sconn288_h44441004(chips)!SCONN288_H44441004_PIP-SCONN,HA!!!F166!VSS(82)!!!!
S!GND!J1G2!24!@baseboard_fab2_lib.baseboard_fab2(sch_1):page79_i43@mstr_sconn.sconn288_h44441004(chips)!SCONN288_H44441004_PIP-SCONN,HA!!!F166!VSS(83)!!!!
S!GND!J1G2!22!@baseboard_fab2_lib.baseboard_fab2(sch_1):page79_i43@mstr_sconn.sconn288_h44441004(chips)!SCONN288_H44441004_PIP-SCONN,HA!!!F166!VSS(84)!!!!
S!GND!J1G2!20!@baseboard_fab2_lib.baseboard_fab2(sch_1):page79_i43@mstr_sconn.sconn288_h44441004(chips)!SCONN288_H44441004_PIP-SCONN,HA!!!F166!VSS(85)!!!!
S!GND!J1G2!17!@baseboard_fab2_lib.baseboard_fab2(sch_1):page79_i43@mstr_sconn.sconn288_h44441004(chips)!SCONN288_H44441004_PIP-SCONN,HA!!!F166!VSS(86)!!!!
S!GND!J1G2!15!@baseboard_fab2_lib.baseboard_fab2(sch_1):page79_i43@mstr_sconn.sconn288_h44441004(chips)!SCONN288_H44441004_PIP-SCONN,HA!!!F166!VSS(87)!!!!
S!GND!J1G2!13!@baseboard_fab2_lib.baseboard_fab2(sch_1):page79_i43@mstr_sconn.sconn288_h44441004(chips)!SCONN288_H44441004_PIP-SCONN,HA!!!F166!VSS(88)!!!!
S!GND!J1G2!11!@baseboard_fab2_lib.baseboard_fab2(sch_1):page79_i43@mstr_sconn.sconn288_h44441004(chips)!SCONN288_H44441004_PIP-SCONN,HA!!!F166!VSS(89)!!!!
S!GND!J1G2!265!@baseboard_fab2_lib.baseboard_fab2(sch_1):page79_i43@mstr_sconn.sconn288_h44441004(chips)!SCONN288_H44441004_PIP-SCONN,HA!!!F166!VSS(8)!!!!
S!GND!J1G2!9!@baseboard_fab2_lib.baseboard_fab2(sch_1):page79_i43@mstr_sconn.sconn288_h44441004(chips)!SCONN288_H44441004_PIP-SCONN,HA!!!F166!VSS(90)!!!!
S!GND!J1G2!6!@baseboard_fab2_lib.baseboard_fab2(sch_1):page79_i43@mstr_sconn.sconn288_h44441004(chips)!SCONN288_H44441004_PIP-SCONN,HA!!!F166!VSS(91)!!!!
S!GND!J1G2!4!@baseboard_fab2_lib.baseboard_fab2(sch_1):page79_i43@mstr_sconn.sconn288_h44441004(chips)!SCONN288_H44441004_PIP-SCONN,HA!!!F166!VSS(92)!!!!
S!GND!J1G2!2!@baseboard_fab2_lib.baseboard_fab2(sch_1):page79_i43@mstr_sconn.sconn288_h44441004(chips)!SCONN288_H44441004_PIP-SCONN,HA!!!F166!VSS(93)!!!!
S!GND!J1G2!263!@baseboard_fab2_lib.baseboard_fab2(sch_1):page79_i43@mstr_sconn.sconn288_h44441004(chips)!SCONN288_H44441004_PIP-SCONN,HA!!!F166!VSS(9)!!!!
S!P12V_NVDIMM_GHJ!J1G2!145!@baseboard_fab2_lib.baseboard_fab2(sch_1):page79_i169@mstr_sconn.sconn288_h44441004(chips)!SCONN288_H44441004_PIP-SCONN,HA!!!F165!\12v\(0)!!!!
S!P12V_NVDIMM_GHJ!J1G2!1!@baseboard_fab2_lib.baseboard_fab2(sch_1):page79_i169@mstr_sconn.sconn288_h44441004(chips)!SCONN288_H44441004_PIP-SCONN,HA!!!F165!\12v\(1)!!!!
S!PVDDQ_GHJ!J1G2!236!@baseboard_fab2_lib.baseboard_fab2(sch_1):page79_i169@mstr_sconn.sconn288_h44441004(chips)!SCONN288_H44441004_PIP-SCONN,HA!!!F165!VDD(0)!!!!
S!PVDDQ_GHJ!J1G2!209!@baseboard_fab2_lib.baseboard_fab2(sch_1):page79_i169@mstr_sconn.sconn288_h44441004(chips)!SCONN288_H44441004_PIP-SCONN,HA!!!F165!VDD(10)!!!!
S!PVDDQ_GHJ!J1G2!206!@baseboard_fab2_lib.baseboard_fab2(sch_1):page79_i169@mstr_sconn.sconn288_h44441004(chips)!SCONN288_H44441004_PIP-SCONN,HA!!!F165!VDD(11)!!!!
S!PVDDQ_GHJ!J1G2!204!@baseboard_fab2_lib.baseboard_fab2(sch_1):page79_i169@mstr_sconn.sconn288_h44441004(chips)!SCONN288_H44441004_PIP-SCONN,HA!!!F165!VDD(12)!!!!
S!PVDDQ_GHJ!J1G2!92!@baseboard_fab2_lib.baseboard_fab2(sch_1):page79_i169@mstr_sconn.sconn288_h44441004(chips)!SCONN288_H44441004_PIP-SCONN,HA!!!F165!VDD(13)!!!!
S!PVDDQ_GHJ!J1G2!90!@baseboard_fab2_lib.baseboard_fab2(sch_1):page79_i169@mstr_sconn.sconn288_h44441004(chips)!SCONN288_H44441004_PIP-SCONN,HA!!!F165!VDD(14)!!!!
S!PVDDQ_GHJ!J1G2!88!@baseboard_fab2_lib.baseboard_fab2(sch_1):page79_i169@mstr_sconn.sconn288_h44441004(chips)!SCONN288_H44441004_PIP-SCONN,HA!!!F165!VDD(15)!!!!
S!PVDDQ_GHJ!J1G2!85!@baseboard_fab2_lib.baseboard_fab2(sch_1):page79_i169@mstr_sconn.sconn288_h44441004(chips)!SCONN288_H44441004_PIP-SCONN,HA!!!F165!VDD(16)!!!!
S!PVDDQ_GHJ!J1G2!83!@baseboard_fab2_lib.baseboard_fab2(sch_1):page79_i169@mstr_sconn.sconn288_h44441004(chips)!SCONN288_H44441004_PIP-SCONN,HA!!!F165!VDD(17)!!!!
S!PVDDQ_GHJ!J1G2!80!@baseboard_fab2_lib.baseboard_fab2(sch_1):page79_i169@mstr_sconn.sconn288_h44441004(chips)!SCONN288_H44441004_PIP-SCONN,HA!!!F165!VDD(18)!!!!
S!PVDDQ_GHJ!J1G2!76!@baseboard_fab2_lib.baseboard_fab2(sch_1):page79_i169@mstr_sconn.sconn288_h44441004(chips)!SCONN288_H44441004_PIP-SCONN,HA!!!F165!VDD(19)!!!!
S!PVDDQ_GHJ!J1G2!233!@baseboard_fab2_lib.baseboard_fab2(sch_1):page79_i169@mstr_sconn.sconn288_h44441004(chips)!SCONN288_H44441004_PIP-SCONN,HA!!!F165!VDD(1)!!!!
S!PVDDQ_GHJ!J1G2!73!@baseboard_fab2_lib.baseboard_fab2(sch_1):page79_i169@mstr_sconn.sconn288_h44441004(chips)!SCONN288_H44441004_PIP-SCONN,HA!!!F165!VDD(20)!!!!
S!PVDDQ_GHJ!J1G2!70!@baseboard_fab2_lib.baseboard_fab2(sch_1):page79_i169@mstr_sconn.sconn288_h44441004(chips)!SCONN288_H44441004_PIP-SCONN,HA!!!F165!VDD(21)!!!!
S!PVDDQ_GHJ!J1G2!67!@baseboard_fab2_lib.baseboard_fab2(sch_1):page79_i169@mstr_sconn.sconn288_h44441004(chips)!SCONN288_H44441004_PIP-SCONN,HA!!!F165!VDD(22)!!!!
S!PVDDQ_GHJ!J1G2!64!@baseboard_fab2_lib.baseboard_fab2(sch_1):page79_i169@mstr_sconn.sconn288_h44441004(chips)!SCONN288_H44441004_PIP-SCONN,HA!!!F165!VDD(23)!!!!
S!PVDDQ_GHJ!J1G2!61!@baseboard_fab2_lib.baseboard_fab2(sch_1):page79_i169@mstr_sconn.sconn288_h44441004(chips)!SCONN288_H44441004_PIP-SCONN,HA!!!F165!VDD(24)!!!!
S!PVDDQ_GHJ!J1G2!59!@baseboard_fab2_lib.baseboard_fab2(sch_1):page79_i169@mstr_sconn.sconn288_h44441004(chips)!SCONN288_H44441004_PIP-SCONN,HA!!!F165!VDD(25)!!!!
S!PVDDQ_GHJ!J1G2!231!@baseboard_fab2_lib.baseboard_fab2(sch_1):page79_i169@mstr_sconn.sconn288_h44441004(chips)!SCONN288_H44441004_PIP-SCONN,HA!!!F165!VDD(2)!!!!
S!PVDDQ_GHJ!J1G2!229!@baseboard_fab2_lib.baseboard_fab2(sch_1):page79_i169@mstr_sconn.sconn288_h44441004(chips)!SCONN288_H44441004_PIP-SCONN,HA!!!F165!VDD(3)!!!!
S!PVDDQ_GHJ!J1G2!226!@baseboard_fab2_lib.baseboard_fab2(sch_1):page79_i169@mstr_sconn.sconn288_h44441004(chips)!SCONN288_H44441004_PIP-SCONN,HA!!!F165!VDD(4)!!!!
S!PVDDQ_GHJ!J1G2!223!@baseboard_fab2_lib.baseboard_fab2(sch_1):page79_i169@mstr_sconn.sconn288_h44441004(chips)!SCONN288_H44441004_PIP-SCONN,HA!!!F165!VDD(5)!!!!
S!PVDDQ_GHJ!J1G2!220!@baseboard_fab2_lib.baseboard_fab2(sch_1):page79_i169@mstr_sconn.sconn288_h44441004(chips)!SCONN288_H44441004_PIP-SCONN,HA!!!F165!VDD(6)!!!!
S!PVDDQ_GHJ!J1G2!217!@baseboard_fab2_lib.baseboard_fab2(sch_1):page79_i169@mstr_sconn.sconn288_h44441004(chips)!SCONN288_H44441004_PIP-SCONN,HA!!!F165!VDD(7)!!!!
S!PVDDQ_GHJ!J1G2!215!@baseboard_fab2_lib.baseboard_fab2(sch_1):page79_i169@mstr_sconn.sconn288_h44441004(chips)!SCONN288_H44441004_PIP-SCONN,HA!!!F165!VDD(8)!!!!
S!PVDDQ_GHJ!J1G2!212!@baseboard_fab2_lib.baseboard_fab2(sch_1):page79_i169@mstr_sconn.sconn288_h44441004(chips)!SCONN288_H44441004_PIP-SCONN,HA!!!F165!VDD(9)!!!!
S!PVPP_GHJ!J1G2!287!@baseboard_fab2_lib.baseboard_fab2(sch_1):page79_i169@mstr_sconn.sconn288_h44441004(chips)!SCONN288_H44441004_PIP-SCONN,HA!!!F165!VPP(0)!!!!
S!PVPP_GHJ!J1G2!286!@baseboard_fab2_lib.baseboard_fab2(sch_1):page79_i169@mstr_sconn.sconn288_h44441004(chips)!SCONN288_H44441004_PIP-SCONN,HA!!!F165!VPP(1)!!!!
S!PVPP_GHJ!J1G2!288!@baseboard_fab2_lib.baseboard_fab2(sch_1):page79_i169@mstr_sconn.sconn288_h44441004(chips)!SCONN288_H44441004_PIP-SCONN,HA!!!F165!VPP(2)!!!!
S!PVPP_GHJ!J1G2!143!@baseboard_fab2_lib.baseboard_fab2(sch_1):page79_i169@mstr_sconn.sconn288_h44441004(chips)!SCONN288_H44441004_PIP-SCONN,HA!!!F165!VPP(3)!!!!
S!PVPP_GHJ!J1G2!142!@baseboard_fab2_lib.baseboard_fab2(sch_1):page79_i169@mstr_sconn.sconn288_h44441004(chips)!SCONN288_H44441004_PIP-SCONN,HA!!!F165!VPP(4)!!!!
S!PVTT_GHJ!J1G2!221!@baseboard_fab2_lib.baseboard_fab2(sch_1):page79_i169@mstr_sconn.sconn288_h44441004(chips)!SCONN288_H44441004_PIP-SCONN,HA!!!F165!VTT(0)!!!!
S!PVTT_GHJ!J1G2!77!@baseboard_fab2_lib.baseboard_fab2(sch_1):page79_i169@mstr_sconn.sconn288_h44441004(chips)!SCONN288_H44441004_PIP-SCONN,HA!!!F165!VTT(1)!!!!
S!M_J_MA<0>!J1G3!79!@baseboard_fab2_lib.baseboard_fab2(sch_1):page81_i186@mstr_sconn.sconn288_h44441004(chips)!SCONN288_H44441004_PIP-SCONN,HA!!!F164!A0!!!!
S!M_J_MA<1>!J1G3!72!@baseboard_fab2_lib.baseboard_fab2(sch_1):page81_i186@mstr_sconn.sconn288_h44441004(chips)!SCONN288_H44441004_PIP-SCONN,HA!!!F164!A1!!!!
S!M_J_MA<10>!J1G3!225!@baseboard_fab2_lib.baseboard_fab2(sch_1):page81_i186@mstr_sconn.sconn288_h44441004(chips)!SCONN288_H44441004_PIP-SCONN,HA!!!F164!A10!!!!
S!M_J_MA<11>!J1G3!210!@baseboard_fab2_lib.baseboard_fab2(sch_1):page81_i186@mstr_sconn.sconn288_h44441004(chips)!SCONN288_H44441004_PIP-SCONN,HA!!!F164!A11!!!!
S!M_J_MA<12>!J1G3!65!@baseboard_fab2_lib.baseboard_fab2(sch_1):page81_i186@mstr_sconn.sconn288_h44441004(chips)!SCONN288_H44441004_PIP-SCONN,HA!!!F164!A12!!!!
S!M_J_MA<13>!J1G3!232!@baseboard_fab2_lib.baseboard_fab2(sch_1):page81_i186@mstr_sconn.sconn288_h44441004(chips)!SCONN288_H44441004_PIP-SCONN,HA!!!F164!A13!!!!
S!M_J_MA<14>!J1G3!228!@baseboard_fab2_lib.baseboard_fab2(sch_1):page81_i186@mstr_sconn.sconn288_h44441004(chips)!SCONN288_H44441004_PIP-SCONN,HA!!!F164!A14_WE_N!!!!
S!M_J_MA<15>!J1G3!86!@baseboard_fab2_lib.baseboard_fab2(sch_1):page81_i186@mstr_sconn.sconn288_h44441004(chips)!SCONN288_H44441004_PIP-SCONN,HA!!!F164!A15_CAS_N!!!!
S!M_J_MA<16>!J1G3!82!@baseboard_fab2_lib.baseboard_fab2(sch_1):page81_i186@mstr_sconn.sconn288_h44441004(chips)!SCONN288_H44441004_PIP-SCONN,HA!!!F164!A16_RAS_N!!!!
S!M_J_MA<17>!J1G3!234!@baseboard_fab2_lib.baseboard_fab2(sch_1):page81_i186@mstr_sconn.sconn288_h44441004(chips)!SCONN288_H44441004_PIP-SCONN,HA!!!F164!A17!!!!
S!M_J_MA<2>!J1G3!216!@baseboard_fab2_lib.baseboard_fab2(sch_1):page81_i186@mstr_sconn.sconn288_h44441004(chips)!SCONN288_H44441004_PIP-SCONN,HA!!!F164!A2!!!!
S!M_J_MA<3>!J1G3!71!@baseboard_fab2_lib.baseboard_fab2(sch_1):page81_i186@mstr_sconn.sconn288_h44441004(chips)!SCONN288_H44441004_PIP-SCONN,HA!!!F164!A3!!!!
S!M_J_MA<4>!J1G3!214!@baseboard_fab2_lib.baseboard_fab2(sch_1):page81_i186@mstr_sconn.sconn288_h44441004(chips)!SCONN288_H44441004_PIP-SCONN,HA!!!F164!A4!!!!
S!M_J_MA<5>!J1G3!213!@baseboard_fab2_lib.baseboard_fab2(sch_1):page81_i186@mstr_sconn.sconn288_h44441004(chips)!SCONN288_H44441004_PIP-SCONN,HA!!!F164!A5!!!!
S!M_J_MA<6>!J1G3!69!@baseboard_fab2_lib.baseboard_fab2(sch_1):page81_i186@mstr_sconn.sconn288_h44441004(chips)!SCONN288_H44441004_PIP-SCONN,HA!!!F164!A6!!!!
S!M_J_MA<7>!J1G3!211!@baseboard_fab2_lib.baseboard_fab2(sch_1):page81_i186@mstr_sconn.sconn288_h44441004(chips)!SCONN288_H44441004_PIP-SCONN,HA!!!F164!A7!!!!
S!M_J_MA<8>!J1G3!68!@baseboard_fab2_lib.baseboard_fab2(sch_1):page81_i186@mstr_sconn.sconn288_h44441004(chips)!SCONN288_H44441004_PIP-SCONN,HA!!!F164!A8!!!!
S!M_J_MA<9>!J1G3!66!@baseboard_fab2_lib.baseboard_fab2(sch_1):page81_i186@mstr_sconn.sconn288_h44441004(chips)!SCONN288_H44441004_PIP-SCONN,HA!!!F164!A9!!!!
S!M_J_ACT_N!J1G3!62!@baseboard_fab2_lib.baseboard_fab2(sch_1):page81_i186@mstr_sconn.sconn288_h44441004(chips)!SCONN288_H44441004_PIP-SCONN,HA!!!F164!ACT_N!!!!
S!M_J_ALERT_N!J1G3!208!@baseboard_fab2_lib.baseboard_fab2(sch_1):page81_i186@mstr_sconn.sconn288_h44441004(chips)!SCONN288_H44441004_PIP-SCONN,HA!!!F164!ALERT_N!!!!
S!M_J_BA<0>!J1G3!81!@baseboard_fab2_lib.baseboard_fab2(sch_1):page81_i186@mstr_sconn.sconn288_h44441004(chips)!SCONN288_H44441004_PIP-SCONN,HA!!!F164!BA(0)!!!!
S!M_J_BA<1>!J1G3!224!@baseboard_fab2_lib.baseboard_fab2(sch_1):page81_i186@mstr_sconn.sconn288_h44441004(chips)!SCONN288_H44441004_PIP-SCONN,HA!!!F164!BA(1)!!!!
S!M_J_BG<0>!J1G3!63!@baseboard_fab2_lib.baseboard_fab2(sch_1):page81_i186@mstr_sconn.sconn288_h44441004(chips)!SCONN288_H44441004_PIP-SCONN,HA!!!F164!BG(0)!!!!
S!M_J_BG<1>!J1G3!207!@baseboard_fab2_lib.baseboard_fab2(sch_1):page81_i186@mstr_sconn.sconn288_h44441004(chips)!SCONN288_H44441004_PIP-SCONN,HA!!!F164!BG(1)!!!!
S!M_J_C<2>!J1G3!235!@baseboard_fab2_lib.baseboard_fab2(sch_1):page81_i186@mstr_sconn.sconn288_h44441004(chips)!SCONN288_H44441004_PIP-SCONN,HA!!!F164!C(2)!!!!
S!M_J_ECC<1>!J1G3!49!@baseboard_fab2_lib.baseboard_fab2(sch_1):page81_i186@mstr_sconn.sconn288_h44441004(chips)!SCONN288_H44441004_PIP-SCONN,HA!!!F164!CB(0)!!!!
S!M_J_ECC<0>!J1G3!194!@baseboard_fab2_lib.baseboard_fab2(sch_1):page81_i186@mstr_sconn.sconn288_h44441004(chips)!SCONN288_H44441004_PIP-SCONN,HA!!!F164!CB(1)!!!!
S!M_J_ECC<3>!J1G3!56!@baseboard_fab2_lib.baseboard_fab2(sch_1):page81_i186@mstr_sconn.sconn288_h44441004(chips)!SCONN288_H44441004_PIP-SCONN,HA!!!F164!CB(2)!!!!
S!M_J_ECC<2>!J1G3!201!@baseboard_fab2_lib.baseboard_fab2(sch_1):page81_i186@mstr_sconn.sconn288_h44441004(chips)!SCONN288_H44441004_PIP-SCONN,HA!!!F164!CB(3)!!!!
S!M_J_ECC<5>!J1G3!47!@baseboard_fab2_lib.baseboard_fab2(sch_1):page81_i186@mstr_sconn.sconn288_h44441004(chips)!SCONN288_H44441004_PIP-SCONN,HA!!!F164!CB(4)!!!!
S!M_J_ECC<4>!J1G3!192!@baseboard_fab2_lib.baseboard_fab2(sch_1):page81_i186@mstr_sconn.sconn288_h44441004(chips)!SCONN288_H44441004_PIP-SCONN,HA!!!F164!CB(5)!!!!
S!M_J_ECC<7>!J1G3!54!@baseboard_fab2_lib.baseboard_fab2(sch_1):page81_i186@mstr_sconn.sconn288_h44441004(chips)!SCONN288_H44441004_PIP-SCONN,HA!!!F164!CB(6)!!!!
S!M_J_ECC<6>!J1G3!199!@baseboard_fab2_lib.baseboard_fab2(sch_1):page81_i186@mstr_sconn.sconn288_h44441004(chips)!SCONN288_H44441004_PIP-SCONN,HA!!!F164!CB(7)!!!!
S!M_J_CLK_DN<0>!J1G3!75!@baseboard_fab2_lib.baseboard_fab2(sch_1):page81_i186@mstr_sconn.sconn288_h44441004(chips)!SCONN288_H44441004_PIP-SCONN,HA!!!F164!CK0N!!!!
S!M_J_CLK_DP<0>!J1G3!74!@baseboard_fab2_lib.baseboard_fab2(sch_1):page81_i186@mstr_sconn.sconn288_h44441004(chips)!SCONN288_H44441004_PIP-SCONN,HA!!!F164!CK0P!!!!
S!M_J_CLK_DN<1>!J1G3!219!@baseboard_fab2_lib.baseboard_fab2(sch_1):page81_i186@mstr_sconn.sconn288_h44441004(chips)!SCONN288_H44441004_PIP-SCONN,HA!!!F164!CK1N!!!!
S!M_J_CLK_DP<1>!J1G3!218!@baseboard_fab2_lib.baseboard_fab2(sch_1):page81_i186@mstr_sconn.sconn288_h44441004(chips)!SCONN288_H44441004_PIP-SCONN,HA!!!F164!CK1P!!!!
S!M_J_CKE<0>!J1G3!60!@baseboard_fab2_lib.baseboard_fab2(sch_1):page81_i186@mstr_sconn.sconn288_h44441004(chips)!SCONN288_H44441004_PIP-SCONN,HA!!!F164!CKE(0)!!!!
S!M_J_CKE<1>!J1G3!203!@baseboard_fab2_lib.baseboard_fab2(sch_1):page81_i186@mstr_sconn.sconn288_h44441004(chips)!SCONN288_H44441004_PIP-SCONN,HA!!!F164!CKE(1)!!!!
S!M_J_DQ<1>!J1G3!5!@baseboard_fab2_lib.baseboard_fab2(sch_1):page81_i186@mstr_sconn.sconn288_h44441004(chips)!SCONN288_H44441004_PIP-SCONN,HA!!!F164!DQ(0)!!!!
S!M_J_DQ<11>!J1G3!23!@baseboard_fab2_lib.baseboard_fab2(sch_1):page81_i186@mstr_sconn.sconn288_h44441004(chips)!SCONN288_H44441004_PIP-SCONN,HA!!!F164!DQ(10)!!!!
S!M_J_DQ<10>!J1G3!168!@baseboard_fab2_lib.baseboard_fab2(sch_1):page81_i186@mstr_sconn.sconn288_h44441004(chips)!SCONN288_H44441004_PIP-SCONN,HA!!!F164!DQ(11)!!!!
S!M_J_DQ<13>!J1G3!14!@baseboard_fab2_lib.baseboard_fab2(sch_1):page81_i186@mstr_sconn.sconn288_h44441004(chips)!SCONN288_H44441004_PIP-SCONN,HA!!!F164!DQ(12)!!!!
S!M_J_DQ<12>!J1G3!159!@baseboard_fab2_lib.baseboard_fab2(sch_1):page81_i186@mstr_sconn.sconn288_h44441004(chips)!SCONN288_H44441004_PIP-SCONN,HA!!!F164!DQ(13)!!!!
S!M_J_DQ<15>!J1G3!21!@baseboard_fab2_lib.baseboard_fab2(sch_1):page81_i186@mstr_sconn.sconn288_h44441004(chips)!SCONN288_H44441004_PIP-SCONN,HA!!!F164!DQ(14)!!!!
S!M_J_DQ<14>!J1G3!166!@baseboard_fab2_lib.baseboard_fab2(sch_1):page81_i186@mstr_sconn.sconn288_h44441004(chips)!SCONN288_H44441004_PIP-SCONN,HA!!!F164!DQ(15)!!!!
S!M_J_DQ<17>!J1G3!27!@baseboard_fab2_lib.baseboard_fab2(sch_1):page81_i186@mstr_sconn.sconn288_h44441004(chips)!SCONN288_H44441004_PIP-SCONN,HA!!!F164!DQ(16)!!!!
S!M_J_DQ<16>!J1G3!172!@baseboard_fab2_lib.baseboard_fab2(sch_1):page81_i186@mstr_sconn.sconn288_h44441004(chips)!SCONN288_H44441004_PIP-SCONN,HA!!!F164!DQ(17)!!!!
S!M_J_DQ<19>!J1G3!34!@baseboard_fab2_lib.baseboard_fab2(sch_1):page81_i186@mstr_sconn.sconn288_h44441004(chips)!SCONN288_H44441004_PIP-SCONN,HA!!!F164!DQ(18)!!!!
S!M_J_DQ<18>!J1G3!179!@baseboard_fab2_lib.baseboard_fab2(sch_1):page81_i186@mstr_sconn.sconn288_h44441004(chips)!SCONN288_H44441004_PIP-SCONN,HA!!!F164!DQ(19)!!!!
S!M_J_DQ<0>!J1G3!150!@baseboard_fab2_lib.baseboard_fab2(sch_1):page81_i186@mstr_sconn.sconn288_h44441004(chips)!SCONN288_H44441004_PIP-SCONN,HA!!!F164!DQ(1)!!!!
S!M_J_DQ<21>!J1G3!25!@baseboard_fab2_lib.baseboard_fab2(sch_1):page81_i186@mstr_sconn.sconn288_h44441004(chips)!SCONN288_H44441004_PIP-SCONN,HA!!!F164!DQ(20)!!!!
S!M_J_DQ<20>!J1G3!170!@baseboard_fab2_lib.baseboard_fab2(sch_1):page81_i186@mstr_sconn.sconn288_h44441004(chips)!SCONN288_H44441004_PIP-SCONN,HA!!!F164!DQ(21)!!!!
S!M_J_DQ<23>!J1G3!32!@baseboard_fab2_lib.baseboard_fab2(sch_1):page81_i186@mstr_sconn.sconn288_h44441004(chips)!SCONN288_H44441004_PIP-SCONN,HA!!!F164!DQ(22)!!!!
S!M_J_DQ<22>!J1G3!177!@baseboard_fab2_lib.baseboard_fab2(sch_1):page81_i186@mstr_sconn.sconn288_h44441004(chips)!SCONN288_H44441004_PIP-SCONN,HA!!!F164!DQ(23)!!!!
S!M_J_DQ<25>!J1G3!38!@baseboard_fab2_lib.baseboard_fab2(sch_1):page81_i186@mstr_sconn.sconn288_h44441004(chips)!SCONN288_H44441004_PIP-SCONN,HA!!!F164!DQ(24)!!!!
S!M_J_DQ<24>!J1G3!183!@baseboard_fab2_lib.baseboard_fab2(sch_1):page81_i186@mstr_sconn.sconn288_h44441004(chips)!SCONN288_H44441004_PIP-SCONN,HA!!!F164!DQ(25)!!!!
S!M_J_DQ<27>!J1G3!45!@baseboard_fab2_lib.baseboard_fab2(sch_1):page81_i186@mstr_sconn.sconn288_h44441004(chips)!SCONN288_H44441004_PIP-SCONN,HA!!!F164!DQ(26)!!!!
S!M_J_DQ<26>!J1G3!190!@baseboard_fab2_lib.baseboard_fab2(sch_1):page81_i186@mstr_sconn.sconn288_h44441004(chips)!SCONN288_H44441004_PIP-SCONN,HA!!!F164!DQ(27)!!!!
S!M_J_DQ<29>!J1G3!36!@baseboard_fab2_lib.baseboard_fab2(sch_1):page81_i186@mstr_sconn.sconn288_h44441004(chips)!SCONN288_H44441004_PIP-SCONN,HA!!!F164!DQ(28)!!!!
S!M_J_DQ<28>!J1G3!181!@baseboard_fab2_lib.baseboard_fab2(sch_1):page81_i186@mstr_sconn.sconn288_h44441004(chips)!SCONN288_H44441004_PIP-SCONN,HA!!!F164!DQ(29)!!!!
S!M_J_DQ<3>!J1G3!12!@baseboard_fab2_lib.baseboard_fab2(sch_1):page81_i186@mstr_sconn.sconn288_h44441004(chips)!SCONN288_H44441004_PIP-SCONN,HA!!!F164!DQ(2)!!!!
S!M_J_DQ<31>!J1G3!43!@baseboard_fab2_lib.baseboard_fab2(sch_1):page81_i186@mstr_sconn.sconn288_h44441004(chips)!SCONN288_H44441004_PIP-SCONN,HA!!!F164!DQ(30)!!!!
S!M_J_DQ<30>!J1G3!188!@baseboard_fab2_lib.baseboard_fab2(sch_1):page81_i186@mstr_sconn.sconn288_h44441004(chips)!SCONN288_H44441004_PIP-SCONN,HA!!!F164!DQ(31)!!!!
S!M_J_DQ<33>!J1G3!97!@baseboard_fab2_lib.baseboard_fab2(sch_1):page81_i186@mstr_sconn.sconn288_h44441004(chips)!SCONN288_H44441004_PIP-SCONN,HA!!!F164!DQ(32)!!!!
S!M_J_DQ<32>!J1G3!242!@baseboard_fab2_lib.baseboard_fab2(sch_1):page81_i186@mstr_sconn.sconn288_h44441004(chips)!SCONN288_H44441004_PIP-SCONN,HA!!!F164!DQ(33)!!!!
S!M_J_DQ<35>!J1G3!104!@baseboard_fab2_lib.baseboard_fab2(sch_1):page81_i186@mstr_sconn.sconn288_h44441004(chips)!SCONN288_H44441004_PIP-SCONN,HA!!!F164!DQ(34)!!!!
S!M_J_DQ<34>!J1G3!249!@baseboard_fab2_lib.baseboard_fab2(sch_1):page81_i186@mstr_sconn.sconn288_h44441004(chips)!SCONN288_H44441004_PIP-SCONN,HA!!!F164!DQ(35)!!!!
S!M_J_DQ<37>!J1G3!95!@baseboard_fab2_lib.baseboard_fab2(sch_1):page81_i186@mstr_sconn.sconn288_h44441004(chips)!SCONN288_H44441004_PIP-SCONN,HA!!!F164!DQ(36)!!!!
S!M_J_DQ<36>!J1G3!240!@baseboard_fab2_lib.baseboard_fab2(sch_1):page81_i186@mstr_sconn.sconn288_h44441004(chips)!SCONN288_H44441004_PIP-SCONN,HA!!!F164!DQ(37)!!!!
S!M_J_DQ<39>!J1G3!102!@baseboard_fab2_lib.baseboard_fab2(sch_1):page81_i186@mstr_sconn.sconn288_h44441004(chips)!SCONN288_H44441004_PIP-SCONN,HA!!!F164!DQ(38)!!!!
S!M_J_DQ<38>!J1G3!247!@baseboard_fab2_lib.baseboard_fab2(sch_1):page81_i186@mstr_sconn.sconn288_h44441004(chips)!SCONN288_H44441004_PIP-SCONN,HA!!!F164!DQ(39)!!!!
S!M_J_DQ<2>!J1G3!157!@baseboard_fab2_lib.baseboard_fab2(sch_1):page81_i186@mstr_sconn.sconn288_h44441004(chips)!SCONN288_H44441004_PIP-SCONN,HA!!!F164!DQ(3)!!!!
S!M_J_DQ<41>!J1G3!108!@baseboard_fab2_lib.baseboard_fab2(sch_1):page81_i186@mstr_sconn.sconn288_h44441004(chips)!SCONN288_H44441004_PIP-SCONN,HA!!!F164!DQ(40)!!!!
S!M_J_DQ<40>!J1G3!253!@baseboard_fab2_lib.baseboard_fab2(sch_1):page81_i186@mstr_sconn.sconn288_h44441004(chips)!SCONN288_H44441004_PIP-SCONN,HA!!!F164!DQ(41)!!!!
S!M_J_DQ<43>!J1G3!115!@baseboard_fab2_lib.baseboard_fab2(sch_1):page81_i186@mstr_sconn.sconn288_h44441004(chips)!SCONN288_H44441004_PIP-SCONN,HA!!!F164!DQ(42)!!!!
S!M_J_DQ<42>!J1G3!260!@baseboard_fab2_lib.baseboard_fab2(sch_1):page81_i186@mstr_sconn.sconn288_h44441004(chips)!SCONN288_H44441004_PIP-SCONN,HA!!!F164!DQ(43)!!!!
S!M_J_DQ<45>!J1G3!106!@baseboard_fab2_lib.baseboard_fab2(sch_1):page81_i186@mstr_sconn.sconn288_h44441004(chips)!SCONN288_H44441004_PIP-SCONN,HA!!!F164!DQ(44)!!!!
S!M_J_DQ<44>!J1G3!251!@baseboard_fab2_lib.baseboard_fab2(sch_1):page81_i186@mstr_sconn.sconn288_h44441004(chips)!SCONN288_H44441004_PIP-SCONN,HA!!!F164!DQ(45)!!!!
S!M_J_DQ<47>!J1G3!113!@baseboard_fab2_lib.baseboard_fab2(sch_1):page81_i186@mstr_sconn.sconn288_h44441004(chips)!SCONN288_H44441004_PIP-SCONN,HA!!!F164!DQ(46)!!!!
S!M_J_DQ<46>!J1G3!258!@baseboard_fab2_lib.baseboard_fab2(sch_1):page81_i186@mstr_sconn.sconn288_h44441004(chips)!SCONN288_H44441004_PIP-SCONN,HA!!!F164!DQ(47)!!!!
S!M_J_DQ<49>!J1G3!119!@baseboard_fab2_lib.baseboard_fab2(sch_1):page81_i186@mstr_sconn.sconn288_h44441004(chips)!SCONN288_H44441004_PIP-SCONN,HA!!!F164!DQ(48)!!!!
S!M_J_DQ<48>!J1G3!264!@baseboard_fab2_lib.baseboard_fab2(sch_1):page81_i186@mstr_sconn.sconn288_h44441004(chips)!SCONN288_H44441004_PIP-SCONN,HA!!!F164!DQ(49)!!!!
S!M_J_DQ<5>!J1G3!3!@baseboard_fab2_lib.baseboard_fab2(sch_1):page81_i186@mstr_sconn.sconn288_h44441004(chips)!SCONN288_H44441004_PIP-SCONN,HA!!!F164!DQ(4)!!!!
S!M_J_DQ<51>!J1G3!126!@baseboard_fab2_lib.baseboard_fab2(sch_1):page81_i186@mstr_sconn.sconn288_h44441004(chips)!SCONN288_H44441004_PIP-SCONN,HA!!!F164!DQ(50)!!!!
S!M_J_DQ<50>!J1G3!271!@baseboard_fab2_lib.baseboard_fab2(sch_1):page81_i186@mstr_sconn.sconn288_h44441004(chips)!SCONN288_H44441004_PIP-SCONN,HA!!!F164!DQ(51)!!!!
S!M_J_DQ<53>!J1G3!117!@baseboard_fab2_lib.baseboard_fab2(sch_1):page81_i186@mstr_sconn.sconn288_h44441004(chips)!SCONN288_H44441004_PIP-SCONN,HA!!!F164!DQ(52)!!!!
S!M_J_DQ<52>!J1G3!262!@baseboard_fab2_lib.baseboard_fab2(sch_1):page81_i186@mstr_sconn.sconn288_h44441004(chips)!SCONN288_H44441004_PIP-SCONN,HA!!!F164!DQ(53)!!!!
S!M_J_DQ<55>!J1G3!124!@baseboard_fab2_lib.baseboard_fab2(sch_1):page81_i186@mstr_sconn.sconn288_h44441004(chips)!SCONN288_H44441004_PIP-SCONN,HA!!!F164!DQ(54)!!!!
S!M_J_DQ<54>!J1G3!269!@baseboard_fab2_lib.baseboard_fab2(sch_1):page81_i186@mstr_sconn.sconn288_h44441004(chips)!SCONN288_H44441004_PIP-SCONN,HA!!!F164!DQ(55)!!!!
S!M_J_DQ<57>!J1G3!130!@baseboard_fab2_lib.baseboard_fab2(sch_1):page81_i186@mstr_sconn.sconn288_h44441004(chips)!SCONN288_H44441004_PIP-SCONN,HA!!!F164!DQ(56)!!!!
S!M_J_DQ<56>!J1G3!275!@baseboard_fab2_lib.baseboard_fab2(sch_1):page81_i186@mstr_sconn.sconn288_h44441004(chips)!SCONN288_H44441004_PIP-SCONN,HA!!!F164!DQ(57)!!!!
S!M_J_DQ<59>!J1G3!137!@baseboard_fab2_lib.baseboard_fab2(sch_1):page81_i186@mstr_sconn.sconn288_h44441004(chips)!SCONN288_H44441004_PIP-SCONN,HA!!!F164!DQ(58)!!!!
S!M_J_DQ<58>!J1G3!282!@baseboard_fab2_lib.baseboard_fab2(sch_1):page81_i186@mstr_sconn.sconn288_h44441004(chips)!SCONN288_H44441004_PIP-SCONN,HA!!!F164!DQ(59)!!!!
S!M_J_DQ<4>!J1G3!148!@baseboard_fab2_lib.baseboard_fab2(sch_1):page81_i186@mstr_sconn.sconn288_h44441004(chips)!SCONN288_H44441004_PIP-SCONN,HA!!!F164!DQ(5)!!!!
S!M_J_DQ<61>!J1G3!128!@baseboard_fab2_lib.baseboard_fab2(sch_1):page81_i186@mstr_sconn.sconn288_h44441004(chips)!SCONN288_H44441004_PIP-SCONN,HA!!!F164!DQ(60)!!!!
S!M_J_DQ<60>!J1G3!273!@baseboard_fab2_lib.baseboard_fab2(sch_1):page81_i186@mstr_sconn.sconn288_h44441004(chips)!SCONN288_H44441004_PIP-SCONN,HA!!!F164!DQ(61)!!!!
S!M_J_DQ<63>!J1G3!135!@baseboard_fab2_lib.baseboard_fab2(sch_1):page81_i186@mstr_sconn.sconn288_h44441004(chips)!SCONN288_H44441004_PIP-SCONN,HA!!!F164!DQ(62)!!!!
S!M_J_DQ<62>!J1G3!280!@baseboard_fab2_lib.baseboard_fab2(sch_1):page81_i186@mstr_sconn.sconn288_h44441004(chips)!SCONN288_H44441004_PIP-SCONN,HA!!!F164!DQ(63)!!!!
S!M_J_DQ<7>!J1G3!10!@baseboard_fab2_lib.baseboard_fab2(sch_1):page81_i186@mstr_sconn.sconn288_h44441004(chips)!SCONN288_H44441004_PIP-SCONN,HA!!!F164!DQ(6)!!!!
S!M_J_DQ<6>!J1G3!155!@baseboard_fab2_lib.baseboard_fab2(sch_1):page81_i186@mstr_sconn.sconn288_h44441004(chips)!SCONN288_H44441004_PIP-SCONN,HA!!!F164!DQ(7)!!!!
S!M_J_DQ<9>!J1G3!16!@baseboard_fab2_lib.baseboard_fab2(sch_1):page81_i186@mstr_sconn.sconn288_h44441004(chips)!SCONN288_H44441004_PIP-SCONN,HA!!!F164!DQ(8)!!!!
S!M_J_DQ<8>!J1G3!161!@baseboard_fab2_lib.baseboard_fab2(sch_1):page81_i186@mstr_sconn.sconn288_h44441004(chips)!SCONN288_H44441004_PIP-SCONN,HA!!!F164!DQ(9)!!!!
S!FM_DIMM_EVENT_COD_N!J1G3!78!@baseboard_fab2_lib.baseboard_fab2(sch_1):page81_i186@mstr_sconn.sconn288_h44441004(chips)!SCONN288_H44441004_PIP-SCONN,HA!!!F164!EVENT_N!!!!
S!M_J_ODT<0>!J1G3!87!@baseboard_fab2_lib.baseboard_fab2(sch_1):page81_i186@mstr_sconn.sconn288_h44441004(chips)!SCONN288_H44441004_PIP-SCONN,HA!!!F164!ODT(0)!!!!
S!M_J_ODT<1>!J1G3!91!@baseboard_fab2_lib.baseboard_fab2(sch_1):page81_i186@mstr_sconn.sconn288_h44441004(chips)!SCONN288_H44441004_PIP-SCONN,HA!!!F164!ODT(1)!!!!
S!M_J_PAR!J1G3!222!@baseboard_fab2_lib.baseboard_fab2(sch_1):page81_i186@mstr_sconn.sconn288_h44441004(chips)!SCONN288_H44441004_PIP-SCONN,HA!!!F164!PAR!!!!
S!M_GHJ_RST_N!J1G3!58!@baseboard_fab2_lib.baseboard_fab2(sch_1):page81_i186@mstr_sconn.sconn288_h44441004(chips)!SCONN288_H44441004_PIP-SCONN,HA!!!F164!RESET_N!!!!
S!TP_CH_J_DIMM_J0_RFU_0!J1G3!205!@baseboard_fab2_lib.baseboard_fab2(sch_1):page81_i186@mstr_sconn.sconn288_h44441004(chips)!SCONN288_H44441004_PIP-SCONN,HA!!!F164!RFU(0)!!!!
S!TP_CH_J_DIMM_J0_RFU_1!J1G3!227!@baseboard_fab2_lib.baseboard_fab2(sch_1):page81_i186@mstr_sconn.sconn288_h44441004(chips)!SCONN288_H44441004_PIP-SCONN,HA!!!F164!RFU(1)!!!!
S!TP_CH_J_DIMM_J0_RFU_2!J1G3!144!@baseboard_fab2_lib.baseboard_fab2(sch_1):page81_i186@mstr_sconn.sconn288_h44441004(chips)!SCONN288_H44441004_PIP-SCONN,HA!!!F164!RFU(2)!!!!
S!M_J_CS_N<0>!J1G3!84!@baseboard_fab2_lib.baseboard_fab2(sch_1):page81_i186@mstr_sconn.sconn288_h44441004(chips)!SCONN288_H44441004_PIP-SCONN,HA!!!F164!S0_N!!!!
S!M_J_CS_N<1>!J1G3!89!@baseboard_fab2_lib.baseboard_fab2(sch_1):page81_i186@mstr_sconn.sconn288_h44441004(chips)!SCONN288_H44441004_PIP-SCONN,HA!!!F164!S1_N!!!!
S!M_J_CS_N<2>!J1G3!93!@baseboard_fab2_lib.baseboard_fab2(sch_1):page81_i186@mstr_sconn.sconn288_h44441004(chips)!SCONN288_H44441004_PIP-SCONN,HA!!!F164!S2_N_C(0)!!!!
S!M_J_CS_N<3>!J1G3!237!@baseboard_fab2_lib.baseboard_fab2(sch_1):page81_i186@mstr_sconn.sconn288_h44441004(chips)!SCONN288_H44441004_PIP-SCONN,HA!!!F164!S3_N_C(1)!!!!
S!GND!J1G3!139!@baseboard_fab2_lib.baseboard_fab2(sch_1):page81_i186@mstr_sconn.sconn288_h44441004(chips)!SCONN288_H44441004_PIP-SCONN,HA!!!F164!SA(0)!!!!
S!GND!J1G3!140!@baseboard_fab2_lib.baseboard_fab2(sch_1):page81_i186@mstr_sconn.sconn288_h44441004(chips)!SCONN288_H44441004_PIP-SCONN,HA!!!F164!SA(1)!!!!
S!PVPP_GHJ!J1G3!238!@baseboard_fab2_lib.baseboard_fab2(sch_1):page81_i186@mstr_sconn.sconn288_h44441004(chips)!SCONN288_H44441004_PIP-SCONN,HA!!!F164!SA(2)!!!!
S!FM_ADR_COMPLETE_GHJ_N!J1G3!230!@baseboard_fab2_lib.baseboard_fab2(sch_1):page81_i186@mstr_sconn.sconn288_h44441004(chips)!SCONN288_H44441004_PIP-SCONN,HA!!!F164!SAVE_N_NC!!!!
S!SMB_DDR_GHJ_VPP_SCL!J1G3!141!@baseboard_fab2_lib.baseboard_fab2(sch_1):page81_i186@mstr_sconn.sconn288_h44441004(chips)!SCONN288_H44441004_PIP-SCONN,HA!!!F164!SCL!!!!
S!SMB_DDR_GHJ_VPP_SDA!J1G3!285!@baseboard_fab2_lib.baseboard_fab2(sch_1):page81_i186@mstr_sconn.sconn288_h44441004(chips)!SCONN288_H44441004_PIP-SCONN,HA!!!F164!SDA!!!!
S!PVPP_GHJ!J1G3!284!@baseboard_fab2_lib.baseboard_fab2(sch_1):page81_i186@mstr_sconn.sconn288_h44441004(chips)!SCONN288_H44441004_PIP-SCONN,HA!!!F164!VDDSPD!!!!
S!M_J_VREF!J1G3!146!@baseboard_fab2_lib.baseboard_fab2(sch_1):page81_i186@mstr_sconn.sconn288_h44441004(chips)!SCONN288_H44441004_PIP-SCONN,HA!!!F164!VREFCA!!!!
S!M_J_DQS_DN<0>!J1G3!152!@baseboard_fab2_lib.baseboard_fab2(sch_1):page81_i67@mstr_sconn.sconn288_h44441004(chips)!SCONN288_H44441004_PIP-SCONN,HA!!!F163!DQS0N!!!!
S!M_J_DQS_DP<0>!J1G3!153!@baseboard_fab2_lib.baseboard_fab2(sch_1):page81_i67@mstr_sconn.sconn288_h44441004(chips)!SCONN288_H44441004_PIP-SCONN,HA!!!F163!DQS0P!!!!
S!M_J_DQS_DN<10>!J1G3!19!@baseboard_fab2_lib.baseboard_fab2(sch_1):page81_i67@mstr_sconn.sconn288_h44441004(chips)!SCONN288_H44441004_PIP-SCONN,HA!!!F163!DQS10N!!!!
S!M_J_DQS_DP<10>!J1G3!18!@baseboard_fab2_lib.baseboard_fab2(sch_1):page81_i67@mstr_sconn.sconn288_h44441004(chips)!SCONN288_H44441004_PIP-SCONN,HA!!!F163!DQS10P!!!!
S!M_J_DQS_DN<11>!J1G3!30!@baseboard_fab2_lib.baseboard_fab2(sch_1):page81_i67@mstr_sconn.sconn288_h44441004(chips)!SCONN288_H44441004_PIP-SCONN,HA!!!F163!DQS11N!!!!
S!M_J_DQS_DP<11>!J1G3!29!@baseboard_fab2_lib.baseboard_fab2(sch_1):page81_i67@mstr_sconn.sconn288_h44441004(chips)!SCONN288_H44441004_PIP-SCONN,HA!!!F163!DQS11P!!!!
S!M_J_DQS_DN<12>!J1G3!41!@baseboard_fab2_lib.baseboard_fab2(sch_1):page81_i67@mstr_sconn.sconn288_h44441004(chips)!SCONN288_H44441004_PIP-SCONN,HA!!!F163!DQS12N!!!!
S!M_J_DQS_DP<12>!J1G3!40!@baseboard_fab2_lib.baseboard_fab2(sch_1):page81_i67@mstr_sconn.sconn288_h44441004(chips)!SCONN288_H44441004_PIP-SCONN,HA!!!F163!DQS12P!!!!
S!M_J_DQS_DN<13>!J1G3!100!@baseboard_fab2_lib.baseboard_fab2(sch_1):page81_i67@mstr_sconn.sconn288_h44441004(chips)!SCONN288_H44441004_PIP-SCONN,HA!!!F163!DQS13N!!!!
S!M_J_DQS_DP<13>!J1G3!99!@baseboard_fab2_lib.baseboard_fab2(sch_1):page81_i67@mstr_sconn.sconn288_h44441004(chips)!SCONN288_H44441004_PIP-SCONN,HA!!!F163!DQS13P!!!!
S!M_J_DQS_DN<14>!J1G3!111!@baseboard_fab2_lib.baseboard_fab2(sch_1):page81_i67@mstr_sconn.sconn288_h44441004(chips)!SCONN288_H44441004_PIP-SCONN,HA!!!F163!DQS14N!!!!
S!M_J_DQS_DP<14>!J1G3!110!@baseboard_fab2_lib.baseboard_fab2(sch_1):page81_i67@mstr_sconn.sconn288_h44441004(chips)!SCONN288_H44441004_PIP-SCONN,HA!!!F163!DQS14P!!!!
S!M_J_DQS_DN<15>!J1G3!122!@baseboard_fab2_lib.baseboard_fab2(sch_1):page81_i67@mstr_sconn.sconn288_h44441004(chips)!SCONN288_H44441004_PIP-SCONN,HA!!!F163!DQS15N!!!!
S!M_J_DQS_DP<15>!J1G3!121!@baseboard_fab2_lib.baseboard_fab2(sch_1):page81_i67@mstr_sconn.sconn288_h44441004(chips)!SCONN288_H44441004_PIP-SCONN,HA!!!F163!DQS15P!!!!
S!M_J_DQS_DN<16>!J1G3!133!@baseboard_fab2_lib.baseboard_fab2(sch_1):page81_i67@mstr_sconn.sconn288_h44441004(chips)!SCONN288_H44441004_PIP-SCONN,HA!!!F163!DQS16N!!!!
S!M_J_DQS_DP<16>!J1G3!132!@baseboard_fab2_lib.baseboard_fab2(sch_1):page81_i67@mstr_sconn.sconn288_h44441004(chips)!SCONN288_H44441004_PIP-SCONN,HA!!!F163!DQS16P!!!!
S!M_J_DQS_DN<17>!J1G3!52!@baseboard_fab2_lib.baseboard_fab2(sch_1):page81_i67@mstr_sconn.sconn288_h44441004(chips)!SCONN288_H44441004_PIP-SCONN,HA!!!F163!DQS17N!!!!
S!M_J_DQS_DP<17>!J1G3!51!@baseboard_fab2_lib.baseboard_fab2(sch_1):page81_i67@mstr_sconn.sconn288_h44441004(chips)!SCONN288_H44441004_PIP-SCONN,HA!!!F163!DQS17P!!!!
S!M_J_DQS_DN<1>!J1G3!163!@baseboard_fab2_lib.baseboard_fab2(sch_1):page81_i67@mstr_sconn.sconn288_h44441004(chips)!SCONN288_H44441004_PIP-SCONN,HA!!!F163!DQS1N!!!!
S!M_J_DQS_DP<1>!J1G3!164!@baseboard_fab2_lib.baseboard_fab2(sch_1):page81_i67@mstr_sconn.sconn288_h44441004(chips)!SCONN288_H44441004_PIP-SCONN,HA!!!F163!DQS1P!!!!
S!M_J_DQS_DN<2>!J1G3!174!@baseboard_fab2_lib.baseboard_fab2(sch_1):page81_i67@mstr_sconn.sconn288_h44441004(chips)!SCONN288_H44441004_PIP-SCONN,HA!!!F163!DQS2N!!!!
S!M_J_DQS_DP<2>!J1G3!175!@baseboard_fab2_lib.baseboard_fab2(sch_1):page81_i67@mstr_sconn.sconn288_h44441004(chips)!SCONN288_H44441004_PIP-SCONN,HA!!!F163!DQS2P!!!!
S!M_J_DQS_DN<3>!J1G3!185!@baseboard_fab2_lib.baseboard_fab2(sch_1):page81_i67@mstr_sconn.sconn288_h44441004(chips)!SCONN288_H44441004_PIP-SCONN,HA!!!F163!DQS3N!!!!
S!M_J_DQS_DP<3>!J1G3!186!@baseboard_fab2_lib.baseboard_fab2(sch_1):page81_i67@mstr_sconn.sconn288_h44441004(chips)!SCONN288_H44441004_PIP-SCONN,HA!!!F163!DQS3P!!!!
S!M_J_DQS_DN<4>!J1G3!244!@baseboard_fab2_lib.baseboard_fab2(sch_1):page81_i67@mstr_sconn.sconn288_h44441004(chips)!SCONN288_H44441004_PIP-SCONN,HA!!!F163!DQS4N!!!!
S!M_J_DQS_DP<4>!J1G3!245!@baseboard_fab2_lib.baseboard_fab2(sch_1):page81_i67@mstr_sconn.sconn288_h44441004(chips)!SCONN288_H44441004_PIP-SCONN,HA!!!F163!DQS4P!!!!
S!M_J_DQS_DN<5>!J1G3!255!@baseboard_fab2_lib.baseboard_fab2(sch_1):page81_i67@mstr_sconn.sconn288_h44441004(chips)!SCONN288_H44441004_PIP-SCONN,HA!!!F163!DQS5N!!!!
S!M_J_DQS_DP<5>!J1G3!256!@baseboard_fab2_lib.baseboard_fab2(sch_1):page81_i67@mstr_sconn.sconn288_h44441004(chips)!SCONN288_H44441004_PIP-SCONN,HA!!!F163!DQS5P!!!!
S!M_J_DQS_DN<6>!J1G3!266!@baseboard_fab2_lib.baseboard_fab2(sch_1):page81_i67@mstr_sconn.sconn288_h44441004(chips)!SCONN288_H44441004_PIP-SCONN,HA!!!F163!DQS6N!!!!
S!M_J_DQS_DP<6>!J1G3!267!@baseboard_fab2_lib.baseboard_fab2(sch_1):page81_i67@mstr_sconn.sconn288_h44441004(chips)!SCONN288_H44441004_PIP-SCONN,HA!!!F163!DQS6P!!!!
S!M_J_DQS_DN<7>!J1G3!277!@baseboard_fab2_lib.baseboard_fab2(sch_1):page81_i67@mstr_sconn.sconn288_h44441004(chips)!SCONN288_H44441004_PIP-SCONN,HA!!!F163!DQS7N!!!!
S!M_J_DQS_DP<7>!J1G3!278!@baseboard_fab2_lib.baseboard_fab2(sch_1):page81_i67@mstr_sconn.sconn288_h44441004(chips)!SCONN288_H44441004_PIP-SCONN,HA!!!F163!DQS7P!!!!
S!M_J_DQS_DN<8>!J1G3!196!@baseboard_fab2_lib.baseboard_fab2(sch_1):page81_i67@mstr_sconn.sconn288_h44441004(chips)!SCONN288_H44441004_PIP-SCONN,HA!!!F163!DQS8N!!!!
S!M_J_DQS_DP<8>!J1G3!197!@baseboard_fab2_lib.baseboard_fab2(sch_1):page81_i67@mstr_sconn.sconn288_h44441004(chips)!SCONN288_H44441004_PIP-SCONN,HA!!!F163!DQS8P!!!!
S!M_J_DQS_DN<9>!J1G3!8!@baseboard_fab2_lib.baseboard_fab2(sch_1):page81_i67@mstr_sconn.sconn288_h44441004(chips)!SCONN288_H44441004_PIP-SCONN,HA!!!F163!DQS9N!!!!
S!M_J_DQS_DP<9>!J1G3!7!@baseboard_fab2_lib.baseboard_fab2(sch_1):page81_i67@mstr_sconn.sconn288_h44441004(chips)!SCONN288_H44441004_PIP-SCONN,HA!!!F163!DQS9P!!!!
S!GND!J1G3!283!@baseboard_fab2_lib.baseboard_fab2(sch_1):page81_i185@mstr_sconn.sconn288_h44441004(chips)!SCONN288_H44441004_PIP-SCONN,HA!!!F162!VSS(0)!!!!
S!GND!J1G3!261!@baseboard_fab2_lib.baseboard_fab2(sch_1):page81_i185@mstr_sconn.sconn288_h44441004(chips)!SCONN288_H44441004_PIP-SCONN,HA!!!F162!VSS(10)!!!!
S!GND!J1G3!259!@baseboard_fab2_lib.baseboard_fab2(sch_1):page81_i185@mstr_sconn.sconn288_h44441004(chips)!SCONN288_H44441004_PIP-SCONN,HA!!!F162!VSS(11)!!!!
S!GND!J1G3!257!@baseboard_fab2_lib.baseboard_fab2(sch_1):page81_i185@mstr_sconn.sconn288_h44441004(chips)!SCONN288_H44441004_PIP-SCONN,HA!!!F162!VSS(12)!!!!
S!GND!J1G3!254!@baseboard_fab2_lib.baseboard_fab2(sch_1):page81_i185@mstr_sconn.sconn288_h44441004(chips)!SCONN288_H44441004_PIP-SCONN,HA!!!F162!VSS(13)!!!!
S!GND!J1G3!252!@baseboard_fab2_lib.baseboard_fab2(sch_1):page81_i185@mstr_sconn.sconn288_h44441004(chips)!SCONN288_H44441004_PIP-SCONN,HA!!!F162!VSS(14)!!!!
S!GND!J1G3!250!@baseboard_fab2_lib.baseboard_fab2(sch_1):page81_i185@mstr_sconn.sconn288_h44441004(chips)!SCONN288_H44441004_PIP-SCONN,HA!!!F162!VSS(15)!!!!
S!GND!J1G3!248!@baseboard_fab2_lib.baseboard_fab2(sch_1):page81_i185@mstr_sconn.sconn288_h44441004(chips)!SCONN288_H44441004_PIP-SCONN,HA!!!F162!VSS(16)!!!!
S!GND!J1G3!246!@baseboard_fab2_lib.baseboard_fab2(sch_1):page81_i185@mstr_sconn.sconn288_h44441004(chips)!SCONN288_H44441004_PIP-SCONN,HA!!!F162!VSS(17)!!!!
S!GND!J1G3!243!@baseboard_fab2_lib.baseboard_fab2(sch_1):page81_i185@mstr_sconn.sconn288_h44441004(chips)!SCONN288_H44441004_PIP-SCONN,HA!!!F162!VSS(18)!!!!
S!GND!J1G3!241!@baseboard_fab2_lib.baseboard_fab2(sch_1):page81_i185@mstr_sconn.sconn288_h44441004(chips)!SCONN288_H44441004_PIP-SCONN,HA!!!F162!VSS(19)!!!!
S!GND!J1G3!281!@baseboard_fab2_lib.baseboard_fab2(sch_1):page81_i185@mstr_sconn.sconn288_h44441004(chips)!SCONN288_H44441004_PIP-SCONN,HA!!!F162!VSS(1)!!!!
S!GND!J1G3!239!@baseboard_fab2_lib.baseboard_fab2(sch_1):page81_i185@mstr_sconn.sconn288_h44441004(chips)!SCONN288_H44441004_PIP-SCONN,HA!!!F162!VSS(20)!!!!
S!GND!J1G3!202!@baseboard_fab2_lib.baseboard_fab2(sch_1):page81_i185@mstr_sconn.sconn288_h44441004(chips)!SCONN288_H44441004_PIP-SCONN,HA!!!F162!VSS(21)!!!!
S!GND!J1G3!200!@baseboard_fab2_lib.baseboard_fab2(sch_1):page81_i185@mstr_sconn.sconn288_h44441004(chips)!SCONN288_H44441004_PIP-SCONN,HA!!!F162!VSS(22)!!!!
S!GND!J1G3!198!@baseboard_fab2_lib.baseboard_fab2(sch_1):page81_i185@mstr_sconn.sconn288_h44441004(chips)!SCONN288_H44441004_PIP-SCONN,HA!!!F162!VSS(23)!!!!
S!GND!J1G3!195!@baseboard_fab2_lib.baseboard_fab2(sch_1):page81_i185@mstr_sconn.sconn288_h44441004(chips)!SCONN288_H44441004_PIP-SCONN,HA!!!F162!VSS(24)!!!!
S!GND!J1G3!193!@baseboard_fab2_lib.baseboard_fab2(sch_1):page81_i185@mstr_sconn.sconn288_h44441004(chips)!SCONN288_H44441004_PIP-SCONN,HA!!!F162!VSS(25)!!!!
S!GND!J1G3!191!@baseboard_fab2_lib.baseboard_fab2(sch_1):page81_i185@mstr_sconn.sconn288_h44441004(chips)!SCONN288_H44441004_PIP-SCONN,HA!!!F162!VSS(26)!!!!
S!GND!J1G3!189!@baseboard_fab2_lib.baseboard_fab2(sch_1):page81_i185@mstr_sconn.sconn288_h44441004(chips)!SCONN288_H44441004_PIP-SCONN,HA!!!F162!VSS(27)!!!!
S!GND!J1G3!187!@baseboard_fab2_lib.baseboard_fab2(sch_1):page81_i185@mstr_sconn.sconn288_h44441004(chips)!SCONN288_H44441004_PIP-SCONN,HA!!!F162!VSS(28)!!!!
S!GND!J1G3!184!@baseboard_fab2_lib.baseboard_fab2(sch_1):page81_i185@mstr_sconn.sconn288_h44441004(chips)!SCONN288_H44441004_PIP-SCONN,HA!!!F162!VSS(29)!!!!
S!GND!J1G3!279!@baseboard_fab2_lib.baseboard_fab2(sch_1):page81_i185@mstr_sconn.sconn288_h44441004(chips)!SCONN288_H44441004_PIP-SCONN,HA!!!F162!VSS(2)!!!!
S!GND!J1G3!182!@baseboard_fab2_lib.baseboard_fab2(sch_1):page81_i185@mstr_sconn.sconn288_h44441004(chips)!SCONN288_H44441004_PIP-SCONN,HA!!!F162!VSS(30)!!!!
S!GND!J1G3!180!@baseboard_fab2_lib.baseboard_fab2(sch_1):page81_i185@mstr_sconn.sconn288_h44441004(chips)!SCONN288_H44441004_PIP-SCONN,HA!!!F162!VSS(31)!!!!
S!GND!J1G3!178!@baseboard_fab2_lib.baseboard_fab2(sch_1):page81_i185@mstr_sconn.sconn288_h44441004(chips)!SCONN288_H44441004_PIP-SCONN,HA!!!F162!VSS(32)!!!!
S!GND!J1G3!176!@baseboard_fab2_lib.baseboard_fab2(sch_1):page81_i185@mstr_sconn.sconn288_h44441004(chips)!SCONN288_H44441004_PIP-SCONN,HA!!!F162!VSS(33)!!!!
S!GND!J1G3!173!@baseboard_fab2_lib.baseboard_fab2(sch_1):page81_i185@mstr_sconn.sconn288_h44441004(chips)!SCONN288_H44441004_PIP-SCONN,HA!!!F162!VSS(34)!!!!
S!GND!J1G3!171!@baseboard_fab2_lib.baseboard_fab2(sch_1):page81_i185@mstr_sconn.sconn288_h44441004(chips)!SCONN288_H44441004_PIP-SCONN,HA!!!F162!VSS(35)!!!!
S!GND!J1G3!169!@baseboard_fab2_lib.baseboard_fab2(sch_1):page81_i185@mstr_sconn.sconn288_h44441004(chips)!SCONN288_H44441004_PIP-SCONN,HA!!!F162!VSS(36)!!!!
S!GND!J1G3!167!@baseboard_fab2_lib.baseboard_fab2(sch_1):page81_i185@mstr_sconn.sconn288_h44441004(chips)!SCONN288_H44441004_PIP-SCONN,HA!!!F162!VSS(37)!!!!
S!GND!J1G3!165!@baseboard_fab2_lib.baseboard_fab2(sch_1):page81_i185@mstr_sconn.sconn288_h44441004(chips)!SCONN288_H44441004_PIP-SCONN,HA!!!F162!VSS(38)!!!!
S!GND!J1G3!162!@baseboard_fab2_lib.baseboard_fab2(sch_1):page81_i185@mstr_sconn.sconn288_h44441004(chips)!SCONN288_H44441004_PIP-SCONN,HA!!!F162!VSS(39)!!!!
S!GND!J1G3!276!@baseboard_fab2_lib.baseboard_fab2(sch_1):page81_i185@mstr_sconn.sconn288_h44441004(chips)!SCONN288_H44441004_PIP-SCONN,HA!!!F162!VSS(3)!!!!
S!GND!J1G3!160!@baseboard_fab2_lib.baseboard_fab2(sch_1):page81_i185@mstr_sconn.sconn288_h44441004(chips)!SCONN288_H44441004_PIP-SCONN,HA!!!F162!VSS(40)!!!!
S!GND!J1G3!158!@baseboard_fab2_lib.baseboard_fab2(sch_1):page81_i185@mstr_sconn.sconn288_h44441004(chips)!SCONN288_H44441004_PIP-SCONN,HA!!!F162!VSS(41)!!!!
S!GND!J1G3!156!@baseboard_fab2_lib.baseboard_fab2(sch_1):page81_i185@mstr_sconn.sconn288_h44441004(chips)!SCONN288_H44441004_PIP-SCONN,HA!!!F162!VSS(42)!!!!
S!GND!J1G3!154!@baseboard_fab2_lib.baseboard_fab2(sch_1):page81_i185@mstr_sconn.sconn288_h44441004(chips)!SCONN288_H44441004_PIP-SCONN,HA!!!F162!VSS(43)!!!!
S!GND!J1G3!151!@baseboard_fab2_lib.baseboard_fab2(sch_1):page81_i185@mstr_sconn.sconn288_h44441004(chips)!SCONN288_H44441004_PIP-SCONN,HA!!!F162!VSS(44)!!!!
S!GND!J1G3!149!@baseboard_fab2_lib.baseboard_fab2(sch_1):page81_i185@mstr_sconn.sconn288_h44441004(chips)!SCONN288_H44441004_PIP-SCONN,HA!!!F162!VSS(45)!!!!
S!GND!J1G3!147!@baseboard_fab2_lib.baseboard_fab2(sch_1):page81_i185@mstr_sconn.sconn288_h44441004(chips)!SCONN288_H44441004_PIP-SCONN,HA!!!F162!VSS(46)!!!!
S!GND!J1G3!138!@baseboard_fab2_lib.baseboard_fab2(sch_1):page81_i185@mstr_sconn.sconn288_h44441004(chips)!SCONN288_H44441004_PIP-SCONN,HA!!!F162!VSS(47)!!!!
S!GND!J1G3!136!@baseboard_fab2_lib.baseboard_fab2(sch_1):page81_i185@mstr_sconn.sconn288_h44441004(chips)!SCONN288_H44441004_PIP-SCONN,HA!!!F162!VSS(48)!!!!
S!GND!J1G3!134!@baseboard_fab2_lib.baseboard_fab2(sch_1):page81_i185@mstr_sconn.sconn288_h44441004(chips)!SCONN288_H44441004_PIP-SCONN,HA!!!F162!VSS(49)!!!!
S!GND!J1G3!274!@baseboard_fab2_lib.baseboard_fab2(sch_1):page81_i185@mstr_sconn.sconn288_h44441004(chips)!SCONN288_H44441004_PIP-SCONN,HA!!!F162!VSS(4)!!!!
S!GND!J1G3!131!@baseboard_fab2_lib.baseboard_fab2(sch_1):page81_i185@mstr_sconn.sconn288_h44441004(chips)!SCONN288_H44441004_PIP-SCONN,HA!!!F162!VSS(50)!!!!
S!GND!J1G3!129!@baseboard_fab2_lib.baseboard_fab2(sch_1):page81_i185@mstr_sconn.sconn288_h44441004(chips)!SCONN288_H44441004_PIP-SCONN,HA!!!F162!VSS(51)!!!!
S!GND!J1G3!127!@baseboard_fab2_lib.baseboard_fab2(sch_1):page81_i185@mstr_sconn.sconn288_h44441004(chips)!SCONN288_H44441004_PIP-SCONN,HA!!!F162!VSS(52)!!!!
S!GND!J1G3!125!@baseboard_fab2_lib.baseboard_fab2(sch_1):page81_i185@mstr_sconn.sconn288_h44441004(chips)!SCONN288_H44441004_PIP-SCONN,HA!!!F162!VSS(53)!!!!
S!GND!J1G3!123!@baseboard_fab2_lib.baseboard_fab2(sch_1):page81_i185@mstr_sconn.sconn288_h44441004(chips)!SCONN288_H44441004_PIP-SCONN,HA!!!F162!VSS(54)!!!!
S!GND!J1G3!120!@baseboard_fab2_lib.baseboard_fab2(sch_1):page81_i185@mstr_sconn.sconn288_h44441004(chips)!SCONN288_H44441004_PIP-SCONN,HA!!!F162!VSS(55)!!!!
S!GND!J1G3!118!@baseboard_fab2_lib.baseboard_fab2(sch_1):page81_i185@mstr_sconn.sconn288_h44441004(chips)!SCONN288_H44441004_PIP-SCONN,HA!!!F162!VSS(56)!!!!
S!GND!J1G3!116!@baseboard_fab2_lib.baseboard_fab2(sch_1):page81_i185@mstr_sconn.sconn288_h44441004(chips)!SCONN288_H44441004_PIP-SCONN,HA!!!F162!VSS(57)!!!!
S!GND!J1G3!114!@baseboard_fab2_lib.baseboard_fab2(sch_1):page81_i185@mstr_sconn.sconn288_h44441004(chips)!SCONN288_H44441004_PIP-SCONN,HA!!!F162!VSS(58)!!!!
S!GND!J1G3!112!@baseboard_fab2_lib.baseboard_fab2(sch_1):page81_i185@mstr_sconn.sconn288_h44441004(chips)!SCONN288_H44441004_PIP-SCONN,HA!!!F162!VSS(59)!!!!
S!GND!J1G3!272!@baseboard_fab2_lib.baseboard_fab2(sch_1):page81_i185@mstr_sconn.sconn288_h44441004(chips)!SCONN288_H44441004_PIP-SCONN,HA!!!F162!VSS(5)!!!!
S!GND!J1G3!109!@baseboard_fab2_lib.baseboard_fab2(sch_1):page81_i185@mstr_sconn.sconn288_h44441004(chips)!SCONN288_H44441004_PIP-SCONN,HA!!!F162!VSS(60)!!!!
S!GND!J1G3!107!@baseboard_fab2_lib.baseboard_fab2(sch_1):page81_i185@mstr_sconn.sconn288_h44441004(chips)!SCONN288_H44441004_PIP-SCONN,HA!!!F162!VSS(61)!!!!
S!GND!J1G3!105!@baseboard_fab2_lib.baseboard_fab2(sch_1):page81_i185@mstr_sconn.sconn288_h44441004(chips)!SCONN288_H44441004_PIP-SCONN,HA!!!F162!VSS(62)!!!!
S!GND!J1G3!103!@baseboard_fab2_lib.baseboard_fab2(sch_1):page81_i185@mstr_sconn.sconn288_h44441004(chips)!SCONN288_H44441004_PIP-SCONN,HA!!!F162!VSS(63)!!!!
S!GND!J1G3!101!@baseboard_fab2_lib.baseboard_fab2(sch_1):page81_i185@mstr_sconn.sconn288_h44441004(chips)!SCONN288_H44441004_PIP-SCONN,HA!!!F162!VSS(64)!!!!
S!GND!J1G3!98!@baseboard_fab2_lib.baseboard_fab2(sch_1):page81_i185@mstr_sconn.sconn288_h44441004(chips)!SCONN288_H44441004_PIP-SCONN,HA!!!F162!VSS(65)!!!!
S!GND!J1G3!96!@baseboard_fab2_lib.baseboard_fab2(sch_1):page81_i185@mstr_sconn.sconn288_h44441004(chips)!SCONN288_H44441004_PIP-SCONN,HA!!!F162!VSS(66)!!!!
S!GND!J1G3!94!@baseboard_fab2_lib.baseboard_fab2(sch_1):page81_i185@mstr_sconn.sconn288_h44441004(chips)!SCONN288_H44441004_PIP-SCONN,HA!!!F162!VSS(67)!!!!
S!GND!J1G3!57!@baseboard_fab2_lib.baseboard_fab2(sch_1):page81_i185@mstr_sconn.sconn288_h44441004(chips)!SCONN288_H44441004_PIP-SCONN,HA!!!F162!VSS(68)!!!!
S!GND!J1G3!55!@baseboard_fab2_lib.baseboard_fab2(sch_1):page81_i185@mstr_sconn.sconn288_h44441004(chips)!SCONN288_H44441004_PIP-SCONN,HA!!!F162!VSS(69)!!!!
S!GND!J1G3!270!@baseboard_fab2_lib.baseboard_fab2(sch_1):page81_i185@mstr_sconn.sconn288_h44441004(chips)!SCONN288_H44441004_PIP-SCONN,HA!!!F162!VSS(6)!!!!
S!GND!J1G3!53!@baseboard_fab2_lib.baseboard_fab2(sch_1):page81_i185@mstr_sconn.sconn288_h44441004(chips)!SCONN288_H44441004_PIP-SCONN,HA!!!F162!VSS(70)!!!!
S!GND!J1G3!50!@baseboard_fab2_lib.baseboard_fab2(sch_1):page81_i185@mstr_sconn.sconn288_h44441004(chips)!SCONN288_H44441004_PIP-SCONN,HA!!!F162!VSS(71)!!!!
S!GND!J1G3!48!@baseboard_fab2_lib.baseboard_fab2(sch_1):page81_i185@mstr_sconn.sconn288_h44441004(chips)!SCONN288_H44441004_PIP-SCONN,HA!!!F162!VSS(72)!!!!
S!GND!J1G3!46!@baseboard_fab2_lib.baseboard_fab2(sch_1):page81_i185@mstr_sconn.sconn288_h44441004(chips)!SCONN288_H44441004_PIP-SCONN,HA!!!F162!VSS(73)!!!!
S!GND!J1G3!44!@baseboard_fab2_lib.baseboard_fab2(sch_1):page81_i185@mstr_sconn.sconn288_h44441004(chips)!SCONN288_H44441004_PIP-SCONN,HA!!!F162!VSS(74)!!!!
S!GND!J1G3!42!@baseboard_fab2_lib.baseboard_fab2(sch_1):page81_i185@mstr_sconn.sconn288_h44441004(chips)!SCONN288_H44441004_PIP-SCONN,HA!!!F162!VSS(75)!!!!
S!GND!J1G3!39!@baseboard_fab2_lib.baseboard_fab2(sch_1):page81_i185@mstr_sconn.sconn288_h44441004(chips)!SCONN288_H44441004_PIP-SCONN,HA!!!F162!VSS(76)!!!!
S!GND!J1G3!37!@baseboard_fab2_lib.baseboard_fab2(sch_1):page81_i185@mstr_sconn.sconn288_h44441004(chips)!SCONN288_H44441004_PIP-SCONN,HA!!!F162!VSS(77)!!!!
S!GND!J1G3!35!@baseboard_fab2_lib.baseboard_fab2(sch_1):page81_i185@mstr_sconn.sconn288_h44441004(chips)!SCONN288_H44441004_PIP-SCONN,HA!!!F162!VSS(78)!!!!
S!GND!J1G3!33!@baseboard_fab2_lib.baseboard_fab2(sch_1):page81_i185@mstr_sconn.sconn288_h44441004(chips)!SCONN288_H44441004_PIP-SCONN,HA!!!F162!VSS(79)!!!!
S!GND!J1G3!268!@baseboard_fab2_lib.baseboard_fab2(sch_1):page81_i185@mstr_sconn.sconn288_h44441004(chips)!SCONN288_H44441004_PIP-SCONN,HA!!!F162!VSS(7)!!!!
S!GND!J1G3!31!@baseboard_fab2_lib.baseboard_fab2(sch_1):page81_i185@mstr_sconn.sconn288_h44441004(chips)!SCONN288_H44441004_PIP-SCONN,HA!!!F162!VSS(80)!!!!
S!GND!J1G3!28!@baseboard_fab2_lib.baseboard_fab2(sch_1):page81_i185@mstr_sconn.sconn288_h44441004(chips)!SCONN288_H44441004_PIP-SCONN,HA!!!F162!VSS(81)!!!!
S!GND!J1G3!26!@baseboard_fab2_lib.baseboard_fab2(sch_1):page81_i185@mstr_sconn.sconn288_h44441004(chips)!SCONN288_H44441004_PIP-SCONN,HA!!!F162!VSS(82)!!!!
S!GND!J1G3!24!@baseboard_fab2_lib.baseboard_fab2(sch_1):page81_i185@mstr_sconn.sconn288_h44441004(chips)!SCONN288_H44441004_PIP-SCONN,HA!!!F162!VSS(83)!!!!
S!GND!J1G3!22!@baseboard_fab2_lib.baseboard_fab2(sch_1):page81_i185@mstr_sconn.sconn288_h44441004(chips)!SCONN288_H44441004_PIP-SCONN,HA!!!F162!VSS(84)!!!!
S!GND!J1G3!20!@baseboard_fab2_lib.baseboard_fab2(sch_1):page81_i185@mstr_sconn.sconn288_h44441004(chips)!SCONN288_H44441004_PIP-SCONN,HA!!!F162!VSS(85)!!!!
S!GND!J1G3!17!@baseboard_fab2_lib.baseboard_fab2(sch_1):page81_i185@mstr_sconn.sconn288_h44441004(chips)!SCONN288_H44441004_PIP-SCONN,HA!!!F162!VSS(86)!!!!
S!GND!J1G3!15!@baseboard_fab2_lib.baseboard_fab2(sch_1):page81_i185@mstr_sconn.sconn288_h44441004(chips)!SCONN288_H44441004_PIP-SCONN,HA!!!F162!VSS(87)!!!!
S!GND!J1G3!13!@baseboard_fab2_lib.baseboard_fab2(sch_1):page81_i185@mstr_sconn.sconn288_h44441004(chips)!SCONN288_H44441004_PIP-SCONN,HA!!!F162!VSS(88)!!!!
S!GND!J1G3!11!@baseboard_fab2_lib.baseboard_fab2(sch_1):page81_i185@mstr_sconn.sconn288_h44441004(chips)!SCONN288_H44441004_PIP-SCONN,HA!!!F162!VSS(89)!!!!
S!GND!J1G3!265!@baseboard_fab2_lib.baseboard_fab2(sch_1):page81_i185@mstr_sconn.sconn288_h44441004(chips)!SCONN288_H44441004_PIP-SCONN,HA!!!F162!VSS(8)!!!!
S!GND!J1G3!9!@baseboard_fab2_lib.baseboard_fab2(sch_1):page81_i185@mstr_sconn.sconn288_h44441004(chips)!SCONN288_H44441004_PIP-SCONN,HA!!!F162!VSS(90)!!!!
S!GND!J1G3!6!@baseboard_fab2_lib.baseboard_fab2(sch_1):page81_i185@mstr_sconn.sconn288_h44441004(chips)!SCONN288_H44441004_PIP-SCONN,HA!!!F162!VSS(91)!!!!
S!GND!J1G3!4!@baseboard_fab2_lib.baseboard_fab2(sch_1):page81_i185@mstr_sconn.sconn288_h44441004(chips)!SCONN288_H44441004_PIP-SCONN,HA!!!F162!VSS(92)!!!!
S!GND!J1G3!2!@baseboard_fab2_lib.baseboard_fab2(sch_1):page81_i185@mstr_sconn.sconn288_h44441004(chips)!SCONN288_H44441004_PIP-SCONN,HA!!!F162!VSS(93)!!!!
S!GND!J1G3!263!@baseboard_fab2_lib.baseboard_fab2(sch_1):page81_i185@mstr_sconn.sconn288_h44441004(chips)!SCONN288_H44441004_PIP-SCONN,HA!!!F162!VSS(9)!!!!
S!P12V_NVDIMM_GHJ!J1G3!145!@baseboard_fab2_lib.baseboard_fab2(sch_1):page81_i169@mstr_sconn.sconn288_h44441004(chips)!SCONN288_H44441004_PIP-SCONN,HA!!!F161!\12v\(0)!!!!
S!P12V_NVDIMM_GHJ!J1G3!1!@baseboard_fab2_lib.baseboard_fab2(sch_1):page81_i169@mstr_sconn.sconn288_h44441004(chips)!SCONN288_H44441004_PIP-SCONN,HA!!!F161!\12v\(1)!!!!
S!PVDDQ_GHJ!J1G3!236!@baseboard_fab2_lib.baseboard_fab2(sch_1):page81_i169@mstr_sconn.sconn288_h44441004(chips)!SCONN288_H44441004_PIP-SCONN,HA!!!F161!VDD(0)!!!!
S!PVDDQ_GHJ!J1G3!209!@baseboard_fab2_lib.baseboard_fab2(sch_1):page81_i169@mstr_sconn.sconn288_h44441004(chips)!SCONN288_H44441004_PIP-SCONN,HA!!!F161!VDD(10)!!!!
S!PVDDQ_GHJ!J1G3!206!@baseboard_fab2_lib.baseboard_fab2(sch_1):page81_i169@mstr_sconn.sconn288_h44441004(chips)!SCONN288_H44441004_PIP-SCONN,HA!!!F161!VDD(11)!!!!
S!PVDDQ_GHJ!J1G3!204!@baseboard_fab2_lib.baseboard_fab2(sch_1):page81_i169@mstr_sconn.sconn288_h44441004(chips)!SCONN288_H44441004_PIP-SCONN,HA!!!F161!VDD(12)!!!!
S!PVDDQ_GHJ!J1G3!92!@baseboard_fab2_lib.baseboard_fab2(sch_1):page81_i169@mstr_sconn.sconn288_h44441004(chips)!SCONN288_H44441004_PIP-SCONN,HA!!!F161!VDD(13)!!!!
S!PVDDQ_GHJ!J1G3!90!@baseboard_fab2_lib.baseboard_fab2(sch_1):page81_i169@mstr_sconn.sconn288_h44441004(chips)!SCONN288_H44441004_PIP-SCONN,HA!!!F161!VDD(14)!!!!
S!PVDDQ_GHJ!J1G3!88!@baseboard_fab2_lib.baseboard_fab2(sch_1):page81_i169@mstr_sconn.sconn288_h44441004(chips)!SCONN288_H44441004_PIP-SCONN,HA!!!F161!VDD(15)!!!!
S!PVDDQ_GHJ!J1G3!85!@baseboard_fab2_lib.baseboard_fab2(sch_1):page81_i169@mstr_sconn.sconn288_h44441004(chips)!SCONN288_H44441004_PIP-SCONN,HA!!!F161!VDD(16)!!!!
S!PVDDQ_GHJ!J1G3!83!@baseboard_fab2_lib.baseboard_fab2(sch_1):page81_i169@mstr_sconn.sconn288_h44441004(chips)!SCONN288_H44441004_PIP-SCONN,HA!!!F161!VDD(17)!!!!
S!PVDDQ_GHJ!J1G3!80!@baseboard_fab2_lib.baseboard_fab2(sch_1):page81_i169@mstr_sconn.sconn288_h44441004(chips)!SCONN288_H44441004_PIP-SCONN,HA!!!F161!VDD(18)!!!!
S!PVDDQ_GHJ!J1G3!76!@baseboard_fab2_lib.baseboard_fab2(sch_1):page81_i169@mstr_sconn.sconn288_h44441004(chips)!SCONN288_H44441004_PIP-SCONN,HA!!!F161!VDD(19)!!!!
S!PVDDQ_GHJ!J1G3!233!@baseboard_fab2_lib.baseboard_fab2(sch_1):page81_i169@mstr_sconn.sconn288_h44441004(chips)!SCONN288_H44441004_PIP-SCONN,HA!!!F161!VDD(1)!!!!
S!PVDDQ_GHJ!J1G3!73!@baseboard_fab2_lib.baseboard_fab2(sch_1):page81_i169@mstr_sconn.sconn288_h44441004(chips)!SCONN288_H44441004_PIP-SCONN,HA!!!F161!VDD(20)!!!!
S!PVDDQ_GHJ!J1G3!70!@baseboard_fab2_lib.baseboard_fab2(sch_1):page81_i169@mstr_sconn.sconn288_h44441004(chips)!SCONN288_H44441004_PIP-SCONN,HA!!!F161!VDD(21)!!!!
S!PVDDQ_GHJ!J1G3!67!@baseboard_fab2_lib.baseboard_fab2(sch_1):page81_i169@mstr_sconn.sconn288_h44441004(chips)!SCONN288_H44441004_PIP-SCONN,HA!!!F161!VDD(22)!!!!
S!PVDDQ_GHJ!J1G3!64!@baseboard_fab2_lib.baseboard_fab2(sch_1):page81_i169@mstr_sconn.sconn288_h44441004(chips)!SCONN288_H44441004_PIP-SCONN,HA!!!F161!VDD(23)!!!!
S!PVDDQ_GHJ!J1G3!61!@baseboard_fab2_lib.baseboard_fab2(sch_1):page81_i169@mstr_sconn.sconn288_h44441004(chips)!SCONN288_H44441004_PIP-SCONN,HA!!!F161!VDD(24)!!!!
S!PVDDQ_GHJ!J1G3!59!@baseboard_fab2_lib.baseboard_fab2(sch_1):page81_i169@mstr_sconn.sconn288_h44441004(chips)!SCONN288_H44441004_PIP-SCONN,HA!!!F161!VDD(25)!!!!
S!PVDDQ_GHJ!J1G3!231!@baseboard_fab2_lib.baseboard_fab2(sch_1):page81_i169@mstr_sconn.sconn288_h44441004(chips)!SCONN288_H44441004_PIP-SCONN,HA!!!F161!VDD(2)!!!!
S!PVDDQ_GHJ!J1G3!229!@baseboard_fab2_lib.baseboard_fab2(sch_1):page81_i169@mstr_sconn.sconn288_h44441004(chips)!SCONN288_H44441004_PIP-SCONN,HA!!!F161!VDD(3)!!!!
S!PVDDQ_GHJ!J1G3!226!@baseboard_fab2_lib.baseboard_fab2(sch_1):page81_i169@mstr_sconn.sconn288_h44441004(chips)!SCONN288_H44441004_PIP-SCONN,HA!!!F161!VDD(4)!!!!
S!PVDDQ_GHJ!J1G3!223!@baseboard_fab2_lib.baseboard_fab2(sch_1):page81_i169@mstr_sconn.sconn288_h44441004(chips)!SCONN288_H44441004_PIP-SCONN,HA!!!F161!VDD(5)!!!!
S!PVDDQ_GHJ!J1G3!220!@baseboard_fab2_lib.baseboard_fab2(sch_1):page81_i169@mstr_sconn.sconn288_h44441004(chips)!SCONN288_H44441004_PIP-SCONN,HA!!!F161!VDD(6)!!!!
S!PVDDQ_GHJ!J1G3!217!@baseboard_fab2_lib.baseboard_fab2(sch_1):page81_i169@mstr_sconn.sconn288_h44441004(chips)!SCONN288_H44441004_PIP-SCONN,HA!!!F161!VDD(7)!!!!
S!PVDDQ_GHJ!J1G3!215!@baseboard_fab2_lib.baseboard_fab2(sch_1):page81_i169@mstr_sconn.sconn288_h44441004(chips)!SCONN288_H44441004_PIP-SCONN,HA!!!F161!VDD(8)!!!!
S!PVDDQ_GHJ!J1G3!212!@baseboard_fab2_lib.baseboard_fab2(sch_1):page81_i169@mstr_sconn.sconn288_h44441004(chips)!SCONN288_H44441004_PIP-SCONN,HA!!!F161!VDD(9)!!!!
S!PVPP_GHJ!J1G3!287!@baseboard_fab2_lib.baseboard_fab2(sch_1):page81_i169@mstr_sconn.sconn288_h44441004(chips)!SCONN288_H44441004_PIP-SCONN,HA!!!F161!VPP(0)!!!!
S!PVPP_GHJ!J1G3!286!@baseboard_fab2_lib.baseboard_fab2(sch_1):page81_i169@mstr_sconn.sconn288_h44441004(chips)!SCONN288_H44441004_PIP-SCONN,HA!!!F161!VPP(1)!!!!
S!PVPP_GHJ!J1G3!288!@baseboard_fab2_lib.baseboard_fab2(sch_1):page81_i169@mstr_sconn.sconn288_h44441004(chips)!SCONN288_H44441004_PIP-SCONN,HA!!!F161!VPP(2)!!!!
S!PVPP_GHJ!J1G3!143!@baseboard_fab2_lib.baseboard_fab2(sch_1):page81_i169@mstr_sconn.sconn288_h44441004(chips)!SCONN288_H44441004_PIP-SCONN,HA!!!F161!VPP(3)!!!!
S!PVPP_GHJ!J1G3!142!@baseboard_fab2_lib.baseboard_fab2(sch_1):page81_i169@mstr_sconn.sconn288_h44441004(chips)!SCONN288_H44441004_PIP-SCONN,HA!!!F161!VPP(4)!!!!
S!PVTT_GHJ!J1G3!221!@baseboard_fab2_lib.baseboard_fab2(sch_1):page81_i169@mstr_sconn.sconn288_h44441004(chips)!SCONN288_H44441004_PIP-SCONN,HA!!!F161!VTT(0)!!!!
S!PVTT_GHJ!J1G3!77!@baseboard_fab2_lib.baseboard_fab2(sch_1):page81_i169@mstr_sconn.sconn288_h44441004(chips)!SCONN288_H44441004_PIP-SCONN,HA!!!F161!VTT(1)!!!!
S!M_K_MA<0>!J1B1!79!@baseboard_fab2_lib.baseboard_fab2(sch_1):page83_i111@mstr_sconn.sconn288_h44441004(chips)!SCONN288_H44441004_PIP-SCONN,HA!!!F176!A0!!!!
S!M_K_MA<1>!J1B1!72!@baseboard_fab2_lib.baseboard_fab2(sch_1):page83_i111@mstr_sconn.sconn288_h44441004(chips)!SCONN288_H44441004_PIP-SCONN,HA!!!F176!A1!!!!
S!M_K_MA<10>!J1B1!225!@baseboard_fab2_lib.baseboard_fab2(sch_1):page83_i111@mstr_sconn.sconn288_h44441004(chips)!SCONN288_H44441004_PIP-SCONN,HA!!!F176!A10!!!!
S!M_K_MA<11>!J1B1!210!@baseboard_fab2_lib.baseboard_fab2(sch_1):page83_i111@mstr_sconn.sconn288_h44441004(chips)!SCONN288_H44441004_PIP-SCONN,HA!!!F176!A11!!!!
S!M_K_MA<12>!J1B1!65!@baseboard_fab2_lib.baseboard_fab2(sch_1):page83_i111@mstr_sconn.sconn288_h44441004(chips)!SCONN288_H44441004_PIP-SCONN,HA!!!F176!A12!!!!
S!M_K_MA<13>!J1B1!232!@baseboard_fab2_lib.baseboard_fab2(sch_1):page83_i111@mstr_sconn.sconn288_h44441004(chips)!SCONN288_H44441004_PIP-SCONN,HA!!!F176!A13!!!!
S!M_K_MA<14>!J1B1!228!@baseboard_fab2_lib.baseboard_fab2(sch_1):page83_i111@mstr_sconn.sconn288_h44441004(chips)!SCONN288_H44441004_PIP-SCONN,HA!!!F176!A14_WE_N!!!!
S!M_K_MA<15>!J1B1!86!@baseboard_fab2_lib.baseboard_fab2(sch_1):page83_i111@mstr_sconn.sconn288_h44441004(chips)!SCONN288_H44441004_PIP-SCONN,HA!!!F176!A15_CAS_N!!!!
S!M_K_MA<16>!J1B1!82!@baseboard_fab2_lib.baseboard_fab2(sch_1):page83_i111@mstr_sconn.sconn288_h44441004(chips)!SCONN288_H44441004_PIP-SCONN,HA!!!F176!A16_RAS_N!!!!
S!M_K_MA<17>!J1B1!234!@baseboard_fab2_lib.baseboard_fab2(sch_1):page83_i111@mstr_sconn.sconn288_h44441004(chips)!SCONN288_H44441004_PIP-SCONN,HA!!!F176!A17!!!!
S!M_K_MA<2>!J1B1!216!@baseboard_fab2_lib.baseboard_fab2(sch_1):page83_i111@mstr_sconn.sconn288_h44441004(chips)!SCONN288_H44441004_PIP-SCONN,HA!!!F176!A2!!!!
S!M_K_MA<3>!J1B1!71!@baseboard_fab2_lib.baseboard_fab2(sch_1):page83_i111@mstr_sconn.sconn288_h44441004(chips)!SCONN288_H44441004_PIP-SCONN,HA!!!F176!A3!!!!
S!M_K_MA<4>!J1B1!214!@baseboard_fab2_lib.baseboard_fab2(sch_1):page83_i111@mstr_sconn.sconn288_h44441004(chips)!SCONN288_H44441004_PIP-SCONN,HA!!!F176!A4!!!!
S!M_K_MA<5>!J1B1!213!@baseboard_fab2_lib.baseboard_fab2(sch_1):page83_i111@mstr_sconn.sconn288_h44441004(chips)!SCONN288_H44441004_PIP-SCONN,HA!!!F176!A5!!!!
S!M_K_MA<6>!J1B1!69!@baseboard_fab2_lib.baseboard_fab2(sch_1):page83_i111@mstr_sconn.sconn288_h44441004(chips)!SCONN288_H44441004_PIP-SCONN,HA!!!F176!A6!!!!
S!M_K_MA<7>!J1B1!211!@baseboard_fab2_lib.baseboard_fab2(sch_1):page83_i111@mstr_sconn.sconn288_h44441004(chips)!SCONN288_H44441004_PIP-SCONN,HA!!!F176!A7!!!!
S!M_K_MA<8>!J1B1!68!@baseboard_fab2_lib.baseboard_fab2(sch_1):page83_i111@mstr_sconn.sconn288_h44441004(chips)!SCONN288_H44441004_PIP-SCONN,HA!!!F176!A8!!!!
S!M_K_MA<9>!J1B1!66!@baseboard_fab2_lib.baseboard_fab2(sch_1):page83_i111@mstr_sconn.sconn288_h44441004(chips)!SCONN288_H44441004_PIP-SCONN,HA!!!F176!A9!!!!
S!M_K_ACT_N!J1B1!62!@baseboard_fab2_lib.baseboard_fab2(sch_1):page83_i111@mstr_sconn.sconn288_h44441004(chips)!SCONN288_H44441004_PIP-SCONN,HA!!!F176!ACT_N!!!!
S!M_K_ALERT_N!J1B1!208!@baseboard_fab2_lib.baseboard_fab2(sch_1):page83_i111@mstr_sconn.sconn288_h44441004(chips)!SCONN288_H44441004_PIP-SCONN,HA!!!F176!ALERT_N!!!!
S!M_K_BA<0>!J1B1!81!@baseboard_fab2_lib.baseboard_fab2(sch_1):page83_i111@mstr_sconn.sconn288_h44441004(chips)!SCONN288_H44441004_PIP-SCONN,HA!!!F176!BA(0)!!!!
S!M_K_BA<1>!J1B1!224!@baseboard_fab2_lib.baseboard_fab2(sch_1):page83_i111@mstr_sconn.sconn288_h44441004(chips)!SCONN288_H44441004_PIP-SCONN,HA!!!F176!BA(1)!!!!
S!M_K_BG<0>!J1B1!63!@baseboard_fab2_lib.baseboard_fab2(sch_1):page83_i111@mstr_sconn.sconn288_h44441004(chips)!SCONN288_H44441004_PIP-SCONN,HA!!!F176!BG(0)!!!!
S!M_K_BG<1>!J1B1!207!@baseboard_fab2_lib.baseboard_fab2(sch_1):page83_i111@mstr_sconn.sconn288_h44441004(chips)!SCONN288_H44441004_PIP-SCONN,HA!!!F176!BG(1)!!!!
S!M_K_C<2>!J1B1!235!@baseboard_fab2_lib.baseboard_fab2(sch_1):page83_i111@mstr_sconn.sconn288_h44441004(chips)!SCONN288_H44441004_PIP-SCONN,HA!!!F176!C(2)!!!!
S!M_K_ECC<1>!J1B1!49!@baseboard_fab2_lib.baseboard_fab2(sch_1):page83_i111@mstr_sconn.sconn288_h44441004(chips)!SCONN288_H44441004_PIP-SCONN,HA!!!F176!CB(0)!!!!
S!M_K_ECC<0>!J1B1!194!@baseboard_fab2_lib.baseboard_fab2(sch_1):page83_i111@mstr_sconn.sconn288_h44441004(chips)!SCONN288_H44441004_PIP-SCONN,HA!!!F176!CB(1)!!!!
S!M_K_ECC<3>!J1B1!56!@baseboard_fab2_lib.baseboard_fab2(sch_1):page83_i111@mstr_sconn.sconn288_h44441004(chips)!SCONN288_H44441004_PIP-SCONN,HA!!!F176!CB(2)!!!!
S!M_K_ECC<2>!J1B1!201!@baseboard_fab2_lib.baseboard_fab2(sch_1):page83_i111@mstr_sconn.sconn288_h44441004(chips)!SCONN288_H44441004_PIP-SCONN,HA!!!F176!CB(3)!!!!
S!M_K_ECC<5>!J1B1!47!@baseboard_fab2_lib.baseboard_fab2(sch_1):page83_i111@mstr_sconn.sconn288_h44441004(chips)!SCONN288_H44441004_PIP-SCONN,HA!!!F176!CB(4)!!!!
S!M_K_ECC<4>!J1B1!192!@baseboard_fab2_lib.baseboard_fab2(sch_1):page83_i111@mstr_sconn.sconn288_h44441004(chips)!SCONN288_H44441004_PIP-SCONN,HA!!!F176!CB(5)!!!!
S!M_K_ECC<7>!J1B1!54!@baseboard_fab2_lib.baseboard_fab2(sch_1):page83_i111@mstr_sconn.sconn288_h44441004(chips)!SCONN288_H44441004_PIP-SCONN,HA!!!F176!CB(6)!!!!
S!M_K_ECC<6>!J1B1!199!@baseboard_fab2_lib.baseboard_fab2(sch_1):page83_i111@mstr_sconn.sconn288_h44441004(chips)!SCONN288_H44441004_PIP-SCONN,HA!!!F176!CB(7)!!!!
S!M_K_CLK_DN<0>!J1B1!75!@baseboard_fab2_lib.baseboard_fab2(sch_1):page83_i111@mstr_sconn.sconn288_h44441004(chips)!SCONN288_H44441004_PIP-SCONN,HA!!!F176!CK0N!!!!
S!M_K_CLK_DP<0>!J1B1!74!@baseboard_fab2_lib.baseboard_fab2(sch_1):page83_i111@mstr_sconn.sconn288_h44441004(chips)!SCONN288_H44441004_PIP-SCONN,HA!!!F176!CK0P!!!!
S!M_K_CLK_DN<1>!J1B1!219!@baseboard_fab2_lib.baseboard_fab2(sch_1):page83_i111@mstr_sconn.sconn288_h44441004(chips)!SCONN288_H44441004_PIP-SCONN,HA!!!F176!CK1N!!!!
S!M_K_CLK_DP<1>!J1B1!218!@baseboard_fab2_lib.baseboard_fab2(sch_1):page83_i111@mstr_sconn.sconn288_h44441004(chips)!SCONN288_H44441004_PIP-SCONN,HA!!!F176!CK1P!!!!
S!M_K_CKE<0>!J1B1!60!@baseboard_fab2_lib.baseboard_fab2(sch_1):page83_i111@mstr_sconn.sconn288_h44441004(chips)!SCONN288_H44441004_PIP-SCONN,HA!!!F176!CKE(0)!!!!
S!M_K_CKE<1>!J1B1!203!@baseboard_fab2_lib.baseboard_fab2(sch_1):page83_i111@mstr_sconn.sconn288_h44441004(chips)!SCONN288_H44441004_PIP-SCONN,HA!!!F176!CKE(1)!!!!
S!M_K_DQ<1>!J1B1!5!@baseboard_fab2_lib.baseboard_fab2(sch_1):page83_i111@mstr_sconn.sconn288_h44441004(chips)!SCONN288_H44441004_PIP-SCONN,HA!!!F176!DQ(0)!!!!
S!M_K_DQ<11>!J1B1!23!@baseboard_fab2_lib.baseboard_fab2(sch_1):page83_i111@mstr_sconn.sconn288_h44441004(chips)!SCONN288_H44441004_PIP-SCONN,HA!!!F176!DQ(10)!!!!
S!M_K_DQ<10>!J1B1!168!@baseboard_fab2_lib.baseboard_fab2(sch_1):page83_i111@mstr_sconn.sconn288_h44441004(chips)!SCONN288_H44441004_PIP-SCONN,HA!!!F176!DQ(11)!!!!
S!M_K_DQ<13>!J1B1!14!@baseboard_fab2_lib.baseboard_fab2(sch_1):page83_i111@mstr_sconn.sconn288_h44441004(chips)!SCONN288_H44441004_PIP-SCONN,HA!!!F176!DQ(12)!!!!
S!M_K_DQ<12>!J1B1!159!@baseboard_fab2_lib.baseboard_fab2(sch_1):page83_i111@mstr_sconn.sconn288_h44441004(chips)!SCONN288_H44441004_PIP-SCONN,HA!!!F176!DQ(13)!!!!
S!M_K_DQ<15>!J1B1!21!@baseboard_fab2_lib.baseboard_fab2(sch_1):page83_i111@mstr_sconn.sconn288_h44441004(chips)!SCONN288_H44441004_PIP-SCONN,HA!!!F176!DQ(14)!!!!
S!M_K_DQ<14>!J1B1!166!@baseboard_fab2_lib.baseboard_fab2(sch_1):page83_i111@mstr_sconn.sconn288_h44441004(chips)!SCONN288_H44441004_PIP-SCONN,HA!!!F176!DQ(15)!!!!
S!M_K_DQ<17>!J1B1!27!@baseboard_fab2_lib.baseboard_fab2(sch_1):page83_i111@mstr_sconn.sconn288_h44441004(chips)!SCONN288_H44441004_PIP-SCONN,HA!!!F176!DQ(16)!!!!
S!M_K_DQ<16>!J1B1!172!@baseboard_fab2_lib.baseboard_fab2(sch_1):page83_i111@mstr_sconn.sconn288_h44441004(chips)!SCONN288_H44441004_PIP-SCONN,HA!!!F176!DQ(17)!!!!
S!M_K_DQ<19>!J1B1!34!@baseboard_fab2_lib.baseboard_fab2(sch_1):page83_i111@mstr_sconn.sconn288_h44441004(chips)!SCONN288_H44441004_PIP-SCONN,HA!!!F176!DQ(18)!!!!
S!M_K_DQ<18>!J1B1!179!@baseboard_fab2_lib.baseboard_fab2(sch_1):page83_i111@mstr_sconn.sconn288_h44441004(chips)!SCONN288_H44441004_PIP-SCONN,HA!!!F176!DQ(19)!!!!
S!M_K_DQ<0>!J1B1!150!@baseboard_fab2_lib.baseboard_fab2(sch_1):page83_i111@mstr_sconn.sconn288_h44441004(chips)!SCONN288_H44441004_PIP-SCONN,HA!!!F176!DQ(1)!!!!
S!M_K_DQ<21>!J1B1!25!@baseboard_fab2_lib.baseboard_fab2(sch_1):page83_i111@mstr_sconn.sconn288_h44441004(chips)!SCONN288_H44441004_PIP-SCONN,HA!!!F176!DQ(20)!!!!
S!M_K_DQ<20>!J1B1!170!@baseboard_fab2_lib.baseboard_fab2(sch_1):page83_i111@mstr_sconn.sconn288_h44441004(chips)!SCONN288_H44441004_PIP-SCONN,HA!!!F176!DQ(21)!!!!
S!M_K_DQ<23>!J1B1!32!@baseboard_fab2_lib.baseboard_fab2(sch_1):page83_i111@mstr_sconn.sconn288_h44441004(chips)!SCONN288_H44441004_PIP-SCONN,HA!!!F176!DQ(22)!!!!
S!M_K_DQ<22>!J1B1!177!@baseboard_fab2_lib.baseboard_fab2(sch_1):page83_i111@mstr_sconn.sconn288_h44441004(chips)!SCONN288_H44441004_PIP-SCONN,HA!!!F176!DQ(23)!!!!
S!M_K_DQ<25>!J1B1!38!@baseboard_fab2_lib.baseboard_fab2(sch_1):page83_i111@mstr_sconn.sconn288_h44441004(chips)!SCONN288_H44441004_PIP-SCONN,HA!!!F176!DQ(24)!!!!
S!M_K_DQ<24>!J1B1!183!@baseboard_fab2_lib.baseboard_fab2(sch_1):page83_i111@mstr_sconn.sconn288_h44441004(chips)!SCONN288_H44441004_PIP-SCONN,HA!!!F176!DQ(25)!!!!
S!M_K_DQ<27>!J1B1!45!@baseboard_fab2_lib.baseboard_fab2(sch_1):page83_i111@mstr_sconn.sconn288_h44441004(chips)!SCONN288_H44441004_PIP-SCONN,HA!!!F176!DQ(26)!!!!
S!M_K_DQ<26>!J1B1!190!@baseboard_fab2_lib.baseboard_fab2(sch_1):page83_i111@mstr_sconn.sconn288_h44441004(chips)!SCONN288_H44441004_PIP-SCONN,HA!!!F176!DQ(27)!!!!
S!M_K_DQ<29>!J1B1!36!@baseboard_fab2_lib.baseboard_fab2(sch_1):page83_i111@mstr_sconn.sconn288_h44441004(chips)!SCONN288_H44441004_PIP-SCONN,HA!!!F176!DQ(28)!!!!
S!M_K_DQ<28>!J1B1!181!@baseboard_fab2_lib.baseboard_fab2(sch_1):page83_i111@mstr_sconn.sconn288_h44441004(chips)!SCONN288_H44441004_PIP-SCONN,HA!!!F176!DQ(29)!!!!
S!M_K_DQ<3>!J1B1!12!@baseboard_fab2_lib.baseboard_fab2(sch_1):page83_i111@mstr_sconn.sconn288_h44441004(chips)!SCONN288_H44441004_PIP-SCONN,HA!!!F176!DQ(2)!!!!
S!M_K_DQ<31>!J1B1!43!@baseboard_fab2_lib.baseboard_fab2(sch_1):page83_i111@mstr_sconn.sconn288_h44441004(chips)!SCONN288_H44441004_PIP-SCONN,HA!!!F176!DQ(30)!!!!
S!M_K_DQ<30>!J1B1!188!@baseboard_fab2_lib.baseboard_fab2(sch_1):page83_i111@mstr_sconn.sconn288_h44441004(chips)!SCONN288_H44441004_PIP-SCONN,HA!!!F176!DQ(31)!!!!
S!M_K_DQ<33>!J1B1!97!@baseboard_fab2_lib.baseboard_fab2(sch_1):page83_i111@mstr_sconn.sconn288_h44441004(chips)!SCONN288_H44441004_PIP-SCONN,HA!!!F176!DQ(32)!!!!
S!M_K_DQ<32>!J1B1!242!@baseboard_fab2_lib.baseboard_fab2(sch_1):page83_i111@mstr_sconn.sconn288_h44441004(chips)!SCONN288_H44441004_PIP-SCONN,HA!!!F176!DQ(33)!!!!
S!M_K_DQ<35>!J1B1!104!@baseboard_fab2_lib.baseboard_fab2(sch_1):page83_i111@mstr_sconn.sconn288_h44441004(chips)!SCONN288_H44441004_PIP-SCONN,HA!!!F176!DQ(34)!!!!
S!M_K_DQ<34>!J1B1!249!@baseboard_fab2_lib.baseboard_fab2(sch_1):page83_i111@mstr_sconn.sconn288_h44441004(chips)!SCONN288_H44441004_PIP-SCONN,HA!!!F176!DQ(35)!!!!
S!M_K_DQ<37>!J1B1!95!@baseboard_fab2_lib.baseboard_fab2(sch_1):page83_i111@mstr_sconn.sconn288_h44441004(chips)!SCONN288_H44441004_PIP-SCONN,HA!!!F176!DQ(36)!!!!
S!M_K_DQ<36>!J1B1!240!@baseboard_fab2_lib.baseboard_fab2(sch_1):page83_i111@mstr_sconn.sconn288_h44441004(chips)!SCONN288_H44441004_PIP-SCONN,HA!!!F176!DQ(37)!!!!
S!M_K_DQ<39>!J1B1!102!@baseboard_fab2_lib.baseboard_fab2(sch_1):page83_i111@mstr_sconn.sconn288_h44441004(chips)!SCONN288_H44441004_PIP-SCONN,HA!!!F176!DQ(38)!!!!
S!M_K_DQ<38>!J1B1!247!@baseboard_fab2_lib.baseboard_fab2(sch_1):page83_i111@mstr_sconn.sconn288_h44441004(chips)!SCONN288_H44441004_PIP-SCONN,HA!!!F176!DQ(39)!!!!
S!M_K_DQ<2>!J1B1!157!@baseboard_fab2_lib.baseboard_fab2(sch_1):page83_i111@mstr_sconn.sconn288_h44441004(chips)!SCONN288_H44441004_PIP-SCONN,HA!!!F176!DQ(3)!!!!
S!M_K_DQ<41>!J1B1!108!@baseboard_fab2_lib.baseboard_fab2(sch_1):page83_i111@mstr_sconn.sconn288_h44441004(chips)!SCONN288_H44441004_PIP-SCONN,HA!!!F176!DQ(40)!!!!
S!M_K_DQ<40>!J1B1!253!@baseboard_fab2_lib.baseboard_fab2(sch_1):page83_i111@mstr_sconn.sconn288_h44441004(chips)!SCONN288_H44441004_PIP-SCONN,HA!!!F176!DQ(41)!!!!
S!M_K_DQ<43>!J1B1!115!@baseboard_fab2_lib.baseboard_fab2(sch_1):page83_i111@mstr_sconn.sconn288_h44441004(chips)!SCONN288_H44441004_PIP-SCONN,HA!!!F176!DQ(42)!!!!
S!M_K_DQ<42>!J1B1!260!@baseboard_fab2_lib.baseboard_fab2(sch_1):page83_i111@mstr_sconn.sconn288_h44441004(chips)!SCONN288_H44441004_PIP-SCONN,HA!!!F176!DQ(43)!!!!
S!M_K_DQ<45>!J1B1!106!@baseboard_fab2_lib.baseboard_fab2(sch_1):page83_i111@mstr_sconn.sconn288_h44441004(chips)!SCONN288_H44441004_PIP-SCONN,HA!!!F176!DQ(44)!!!!
S!M_K_DQ<44>!J1B1!251!@baseboard_fab2_lib.baseboard_fab2(sch_1):page83_i111@mstr_sconn.sconn288_h44441004(chips)!SCONN288_H44441004_PIP-SCONN,HA!!!F176!DQ(45)!!!!
S!M_K_DQ<47>!J1B1!113!@baseboard_fab2_lib.baseboard_fab2(sch_1):page83_i111@mstr_sconn.sconn288_h44441004(chips)!SCONN288_H44441004_PIP-SCONN,HA!!!F176!DQ(46)!!!!
S!M_K_DQ<46>!J1B1!258!@baseboard_fab2_lib.baseboard_fab2(sch_1):page83_i111@mstr_sconn.sconn288_h44441004(chips)!SCONN288_H44441004_PIP-SCONN,HA!!!F176!DQ(47)!!!!
S!M_K_DQ<49>!J1B1!119!@baseboard_fab2_lib.baseboard_fab2(sch_1):page83_i111@mstr_sconn.sconn288_h44441004(chips)!SCONN288_H44441004_PIP-SCONN,HA!!!F176!DQ(48)!!!!
S!M_K_DQ<48>!J1B1!264!@baseboard_fab2_lib.baseboard_fab2(sch_1):page83_i111@mstr_sconn.sconn288_h44441004(chips)!SCONN288_H44441004_PIP-SCONN,HA!!!F176!DQ(49)!!!!
S!M_K_DQ<5>!J1B1!3!@baseboard_fab2_lib.baseboard_fab2(sch_1):page83_i111@mstr_sconn.sconn288_h44441004(chips)!SCONN288_H44441004_PIP-SCONN,HA!!!F176!DQ(4)!!!!
S!M_K_DQ<51>!J1B1!126!@baseboard_fab2_lib.baseboard_fab2(sch_1):page83_i111@mstr_sconn.sconn288_h44441004(chips)!SCONN288_H44441004_PIP-SCONN,HA!!!F176!DQ(50)!!!!
S!M_K_DQ<50>!J1B1!271!@baseboard_fab2_lib.baseboard_fab2(sch_1):page83_i111@mstr_sconn.sconn288_h44441004(chips)!SCONN288_H44441004_PIP-SCONN,HA!!!F176!DQ(51)!!!!
S!M_K_DQ<53>!J1B1!117!@baseboard_fab2_lib.baseboard_fab2(sch_1):page83_i111@mstr_sconn.sconn288_h44441004(chips)!SCONN288_H44441004_PIP-SCONN,HA!!!F176!DQ(52)!!!!
S!M_K_DQ<52>!J1B1!262!@baseboard_fab2_lib.baseboard_fab2(sch_1):page83_i111@mstr_sconn.sconn288_h44441004(chips)!SCONN288_H44441004_PIP-SCONN,HA!!!F176!DQ(53)!!!!
S!M_K_DQ<55>!J1B1!124!@baseboard_fab2_lib.baseboard_fab2(sch_1):page83_i111@mstr_sconn.sconn288_h44441004(chips)!SCONN288_H44441004_PIP-SCONN,HA!!!F176!DQ(54)!!!!
S!M_K_DQ<54>!J1B1!269!@baseboard_fab2_lib.baseboard_fab2(sch_1):page83_i111@mstr_sconn.sconn288_h44441004(chips)!SCONN288_H44441004_PIP-SCONN,HA!!!F176!DQ(55)!!!!
S!M_K_DQ<57>!J1B1!130!@baseboard_fab2_lib.baseboard_fab2(sch_1):page83_i111@mstr_sconn.sconn288_h44441004(chips)!SCONN288_H44441004_PIP-SCONN,HA!!!F176!DQ(56)!!!!
S!M_K_DQ<56>!J1B1!275!@baseboard_fab2_lib.baseboard_fab2(sch_1):page83_i111@mstr_sconn.sconn288_h44441004(chips)!SCONN288_H44441004_PIP-SCONN,HA!!!F176!DQ(57)!!!!
S!M_K_DQ<59>!J1B1!137!@baseboard_fab2_lib.baseboard_fab2(sch_1):page83_i111@mstr_sconn.sconn288_h44441004(chips)!SCONN288_H44441004_PIP-SCONN,HA!!!F176!DQ(58)!!!!
S!M_K_DQ<58>!J1B1!282!@baseboard_fab2_lib.baseboard_fab2(sch_1):page83_i111@mstr_sconn.sconn288_h44441004(chips)!SCONN288_H44441004_PIP-SCONN,HA!!!F176!DQ(59)!!!!
S!M_K_DQ<4>!J1B1!148!@baseboard_fab2_lib.baseboard_fab2(sch_1):page83_i111@mstr_sconn.sconn288_h44441004(chips)!SCONN288_H44441004_PIP-SCONN,HA!!!F176!DQ(5)!!!!
S!M_K_DQ<61>!J1B1!128!@baseboard_fab2_lib.baseboard_fab2(sch_1):page83_i111@mstr_sconn.sconn288_h44441004(chips)!SCONN288_H44441004_PIP-SCONN,HA!!!F176!DQ(60)!!!!
S!M_K_DQ<60>!J1B1!273!@baseboard_fab2_lib.baseboard_fab2(sch_1):page83_i111@mstr_sconn.sconn288_h44441004(chips)!SCONN288_H44441004_PIP-SCONN,HA!!!F176!DQ(61)!!!!
S!M_K_DQ<63>!J1B1!135!@baseboard_fab2_lib.baseboard_fab2(sch_1):page83_i111@mstr_sconn.sconn288_h44441004(chips)!SCONN288_H44441004_PIP-SCONN,HA!!!F176!DQ(62)!!!!
S!M_K_DQ<62>!J1B1!280!@baseboard_fab2_lib.baseboard_fab2(sch_1):page83_i111@mstr_sconn.sconn288_h44441004(chips)!SCONN288_H44441004_PIP-SCONN,HA!!!F176!DQ(63)!!!!
S!M_K_DQ<7>!J1B1!10!@baseboard_fab2_lib.baseboard_fab2(sch_1):page83_i111@mstr_sconn.sconn288_h44441004(chips)!SCONN288_H44441004_PIP-SCONN,HA!!!F176!DQ(6)!!!!
S!M_K_DQ<6>!J1B1!155!@baseboard_fab2_lib.baseboard_fab2(sch_1):page83_i111@mstr_sconn.sconn288_h44441004(chips)!SCONN288_H44441004_PIP-SCONN,HA!!!F176!DQ(7)!!!!
S!M_K_DQ<9>!J1B1!16!@baseboard_fab2_lib.baseboard_fab2(sch_1):page83_i111@mstr_sconn.sconn288_h44441004(chips)!SCONN288_H44441004_PIP-SCONN,HA!!!F176!DQ(8)!!!!
S!M_K_DQ<8>!J1B1!161!@baseboard_fab2_lib.baseboard_fab2(sch_1):page83_i111@mstr_sconn.sconn288_h44441004(chips)!SCONN288_H44441004_PIP-SCONN,HA!!!F176!DQ(9)!!!!
S!FM_DIMM_EVENT_COD_N!J1B1!78!@baseboard_fab2_lib.baseboard_fab2(sch_1):page83_i111@mstr_sconn.sconn288_h44441004(chips)!SCONN288_H44441004_PIP-SCONN,HA!!!F176!EVENT_N!!!!
S!M_K_ODT<0>!J1B1!87!@baseboard_fab2_lib.baseboard_fab2(sch_1):page83_i111@mstr_sconn.sconn288_h44441004(chips)!SCONN288_H44441004_PIP-SCONN,HA!!!F176!ODT(0)!!!!
S!M_K_ODT<1>!J1B1!91!@baseboard_fab2_lib.baseboard_fab2(sch_1):page83_i111@mstr_sconn.sconn288_h44441004(chips)!SCONN288_H44441004_PIP-SCONN,HA!!!F176!ODT(1)!!!!
S!M_K_PAR!J1B1!222!@baseboard_fab2_lib.baseboard_fab2(sch_1):page83_i111@mstr_sconn.sconn288_h44441004(chips)!SCONN288_H44441004_PIP-SCONN,HA!!!F176!PAR!!!!
S!M_KLM_RST_N!J1B1!58!@baseboard_fab2_lib.baseboard_fab2(sch_1):page83_i111@mstr_sconn.sconn288_h44441004(chips)!SCONN288_H44441004_PIP-SCONN,HA!!!F176!RESET_N!!!!
S!TP_CH_K_DIMM_K0_RFU_0!J1B1!205!@baseboard_fab2_lib.baseboard_fab2(sch_1):page83_i111@mstr_sconn.sconn288_h44441004(chips)!SCONN288_H44441004_PIP-SCONN,HA!!!F176!RFU(0)!!!!
S!TP_CH_K_DIMM_K0_RFU_1!J1B1!227!@baseboard_fab2_lib.baseboard_fab2(sch_1):page83_i111@mstr_sconn.sconn288_h44441004(chips)!SCONN288_H44441004_PIP-SCONN,HA!!!F176!RFU(1)!!!!
S!TP_CH_K_DIMM_K0_RFU_2!J1B1!144!@baseboard_fab2_lib.baseboard_fab2(sch_1):page83_i111@mstr_sconn.sconn288_h44441004(chips)!SCONN288_H44441004_PIP-SCONN,HA!!!F176!RFU(2)!!!!
S!M_K_CS_N<0>!J1B1!84!@baseboard_fab2_lib.baseboard_fab2(sch_1):page83_i111@mstr_sconn.sconn288_h44441004(chips)!SCONN288_H44441004_PIP-SCONN,HA!!!F176!S0_N!!!!
S!M_K_CS_N<1>!J1B1!89!@baseboard_fab2_lib.baseboard_fab2(sch_1):page83_i111@mstr_sconn.sconn288_h44441004(chips)!SCONN288_H44441004_PIP-SCONN,HA!!!F176!S1_N!!!!
S!M_K_CS_N<2>!J1B1!93!@baseboard_fab2_lib.baseboard_fab2(sch_1):page83_i111@mstr_sconn.sconn288_h44441004(chips)!SCONN288_H44441004_PIP-SCONN,HA!!!F176!S2_N_C(0)!!!!
S!M_K_CS_N<3>!J1B1!237!@baseboard_fab2_lib.baseboard_fab2(sch_1):page83_i111@mstr_sconn.sconn288_h44441004(chips)!SCONN288_H44441004_PIP-SCONN,HA!!!F176!S3_N_C(1)!!!!
S!GND!J1B1!139!@baseboard_fab2_lib.baseboard_fab2(sch_1):page83_i111@mstr_sconn.sconn288_h44441004(chips)!SCONN288_H44441004_PIP-SCONN,HA!!!F176!SA(0)!!!!
S!GND!J1B1!140!@baseboard_fab2_lib.baseboard_fab2(sch_1):page83_i111@mstr_sconn.sconn288_h44441004(chips)!SCONN288_H44441004_PIP-SCONN,HA!!!F176!SA(1)!!!!
S!GND!J1B1!238!@baseboard_fab2_lib.baseboard_fab2(sch_1):page83_i111@mstr_sconn.sconn288_h44441004(chips)!SCONN288_H44441004_PIP-SCONN,HA!!!F176!SA(2)!!!!
S!FM_ADR_COMPLETE_KLM_N!J1B1!230!@baseboard_fab2_lib.baseboard_fab2(sch_1):page83_i111@mstr_sconn.sconn288_h44441004(chips)!SCONN288_H44441004_PIP-SCONN,HA!!!F176!SAVE_N_NC!!!!
S!SMB_DDR_KLM_VPP_SCL!J1B1!141!@baseboard_fab2_lib.baseboard_fab2(sch_1):page83_i111@mstr_sconn.sconn288_h44441004(chips)!SCONN288_H44441004_PIP-SCONN,HA!!!F176!SCL!!!!
S!SMB_DDR_KLM_VPP_SDA!J1B1!285!@baseboard_fab2_lib.baseboard_fab2(sch_1):page83_i111@mstr_sconn.sconn288_h44441004(chips)!SCONN288_H44441004_PIP-SCONN,HA!!!F176!SDA!!!!
S!PVPP_KLM!J1B1!284!@baseboard_fab2_lib.baseboard_fab2(sch_1):page83_i111@mstr_sconn.sconn288_h44441004(chips)!SCONN288_H44441004_PIP-SCONN,HA!!!F176!VDDSPD!!!!
S!M_K_VREF!J1B1!146!@baseboard_fab2_lib.baseboard_fab2(sch_1):page83_i111@mstr_sconn.sconn288_h44441004(chips)!SCONN288_H44441004_PIP-SCONN,HA!!!F176!VREFCA!!!!
S!M_K_DQS_DN<0>!J1B1!152!@baseboard_fab2_lib.baseboard_fab2(sch_1):page83_i66@mstr_sconn.sconn288_h44441004(chips)!SCONN288_H44441004_PIP-SCONN,HA!!!F175!DQS0N!!!!
S!M_K_DQS_DP<0>!J1B1!153!@baseboard_fab2_lib.baseboard_fab2(sch_1):page83_i66@mstr_sconn.sconn288_h44441004(chips)!SCONN288_H44441004_PIP-SCONN,HA!!!F175!DQS0P!!!!
S!M_K_DQS_DN<10>!J1B1!19!@baseboard_fab2_lib.baseboard_fab2(sch_1):page83_i66@mstr_sconn.sconn288_h44441004(chips)!SCONN288_H44441004_PIP-SCONN,HA!!!F175!DQS10N!!!!
S!M_K_DQS_DP<10>!J1B1!18!@baseboard_fab2_lib.baseboard_fab2(sch_1):page83_i66@mstr_sconn.sconn288_h44441004(chips)!SCONN288_H44441004_PIP-SCONN,HA!!!F175!DQS10P!!!!
S!M_K_DQS_DN<11>!J1B1!30!@baseboard_fab2_lib.baseboard_fab2(sch_1):page83_i66@mstr_sconn.sconn288_h44441004(chips)!SCONN288_H44441004_PIP-SCONN,HA!!!F175!DQS11N!!!!
S!M_K_DQS_DP<11>!J1B1!29!@baseboard_fab2_lib.baseboard_fab2(sch_1):page83_i66@mstr_sconn.sconn288_h44441004(chips)!SCONN288_H44441004_PIP-SCONN,HA!!!F175!DQS11P!!!!
S!M_K_DQS_DN<12>!J1B1!41!@baseboard_fab2_lib.baseboard_fab2(sch_1):page83_i66@mstr_sconn.sconn288_h44441004(chips)!SCONN288_H44441004_PIP-SCONN,HA!!!F175!DQS12N!!!!
S!M_K_DQS_DP<12>!J1B1!40!@baseboard_fab2_lib.baseboard_fab2(sch_1):page83_i66@mstr_sconn.sconn288_h44441004(chips)!SCONN288_H44441004_PIP-SCONN,HA!!!F175!DQS12P!!!!
S!M_K_DQS_DN<13>!J1B1!100!@baseboard_fab2_lib.baseboard_fab2(sch_1):page83_i66@mstr_sconn.sconn288_h44441004(chips)!SCONN288_H44441004_PIP-SCONN,HA!!!F175!DQS13N!!!!
S!M_K_DQS_DP<13>!J1B1!99!@baseboard_fab2_lib.baseboard_fab2(sch_1):page83_i66@mstr_sconn.sconn288_h44441004(chips)!SCONN288_H44441004_PIP-SCONN,HA!!!F175!DQS13P!!!!
S!M_K_DQS_DN<14>!J1B1!111!@baseboard_fab2_lib.baseboard_fab2(sch_1):page83_i66@mstr_sconn.sconn288_h44441004(chips)!SCONN288_H44441004_PIP-SCONN,HA!!!F175!DQS14N!!!!
S!M_K_DQS_DP<14>!J1B1!110!@baseboard_fab2_lib.baseboard_fab2(sch_1):page83_i66@mstr_sconn.sconn288_h44441004(chips)!SCONN288_H44441004_PIP-SCONN,HA!!!F175!DQS14P!!!!
S!M_K_DQS_DN<15>!J1B1!122!@baseboard_fab2_lib.baseboard_fab2(sch_1):page83_i66@mstr_sconn.sconn288_h44441004(chips)!SCONN288_H44441004_PIP-SCONN,HA!!!F175!DQS15N!!!!
S!M_K_DQS_DP<15>!J1B1!121!@baseboard_fab2_lib.baseboard_fab2(sch_1):page83_i66@mstr_sconn.sconn288_h44441004(chips)!SCONN288_H44441004_PIP-SCONN,HA!!!F175!DQS15P!!!!
S!M_K_DQS_DN<16>!J1B1!133!@baseboard_fab2_lib.baseboard_fab2(sch_1):page83_i66@mstr_sconn.sconn288_h44441004(chips)!SCONN288_H44441004_PIP-SCONN,HA!!!F175!DQS16N!!!!
S!M_K_DQS_DP<16>!J1B1!132!@baseboard_fab2_lib.baseboard_fab2(sch_1):page83_i66@mstr_sconn.sconn288_h44441004(chips)!SCONN288_H44441004_PIP-SCONN,HA!!!F175!DQS16P!!!!
S!M_K_DQS_DN<17>!J1B1!52!@baseboard_fab2_lib.baseboard_fab2(sch_1):page83_i66@mstr_sconn.sconn288_h44441004(chips)!SCONN288_H44441004_PIP-SCONN,HA!!!F175!DQS17N!!!!
S!M_K_DQS_DP<17>!J1B1!51!@baseboard_fab2_lib.baseboard_fab2(sch_1):page83_i66@mstr_sconn.sconn288_h44441004(chips)!SCONN288_H44441004_PIP-SCONN,HA!!!F175!DQS17P!!!!
S!M_K_DQS_DN<1>!J1B1!163!@baseboard_fab2_lib.baseboard_fab2(sch_1):page83_i66@mstr_sconn.sconn288_h44441004(chips)!SCONN288_H44441004_PIP-SCONN,HA!!!F175!DQS1N!!!!
S!M_K_DQS_DP<1>!J1B1!164!@baseboard_fab2_lib.baseboard_fab2(sch_1):page83_i66@mstr_sconn.sconn288_h44441004(chips)!SCONN288_H44441004_PIP-SCONN,HA!!!F175!DQS1P!!!!
S!M_K_DQS_DN<2>!J1B1!174!@baseboard_fab2_lib.baseboard_fab2(sch_1):page83_i66@mstr_sconn.sconn288_h44441004(chips)!SCONN288_H44441004_PIP-SCONN,HA!!!F175!DQS2N!!!!
S!M_K_DQS_DP<2>!J1B1!175!@baseboard_fab2_lib.baseboard_fab2(sch_1):page83_i66@mstr_sconn.sconn288_h44441004(chips)!SCONN288_H44441004_PIP-SCONN,HA!!!F175!DQS2P!!!!
S!M_K_DQS_DN<3>!J1B1!185!@baseboard_fab2_lib.baseboard_fab2(sch_1):page83_i66@mstr_sconn.sconn288_h44441004(chips)!SCONN288_H44441004_PIP-SCONN,HA!!!F175!DQS3N!!!!
S!M_K_DQS_DP<3>!J1B1!186!@baseboard_fab2_lib.baseboard_fab2(sch_1):page83_i66@mstr_sconn.sconn288_h44441004(chips)!SCONN288_H44441004_PIP-SCONN,HA!!!F175!DQS3P!!!!
S!M_K_DQS_DN<4>!J1B1!244!@baseboard_fab2_lib.baseboard_fab2(sch_1):page83_i66@mstr_sconn.sconn288_h44441004(chips)!SCONN288_H44441004_PIP-SCONN,HA!!!F175!DQS4N!!!!
S!M_K_DQS_DP<4>!J1B1!245!@baseboard_fab2_lib.baseboard_fab2(sch_1):page83_i66@mstr_sconn.sconn288_h44441004(chips)!SCONN288_H44441004_PIP-SCONN,HA!!!F175!DQS4P!!!!
S!M_K_DQS_DN<5>!J1B1!255!@baseboard_fab2_lib.baseboard_fab2(sch_1):page83_i66@mstr_sconn.sconn288_h44441004(chips)!SCONN288_H44441004_PIP-SCONN,HA!!!F175!DQS5N!!!!
S!M_K_DQS_DP<5>!J1B1!256!@baseboard_fab2_lib.baseboard_fab2(sch_1):page83_i66@mstr_sconn.sconn288_h44441004(chips)!SCONN288_H44441004_PIP-SCONN,HA!!!F175!DQS5P!!!!
S!M_K_DQS_DN<6>!J1B1!266!@baseboard_fab2_lib.baseboard_fab2(sch_1):page83_i66@mstr_sconn.sconn288_h44441004(chips)!SCONN288_H44441004_PIP-SCONN,HA!!!F175!DQS6N!!!!
S!M_K_DQS_DP<6>!J1B1!267!@baseboard_fab2_lib.baseboard_fab2(sch_1):page83_i66@mstr_sconn.sconn288_h44441004(chips)!SCONN288_H44441004_PIP-SCONN,HA!!!F175!DQS6P!!!!
S!M_K_DQS_DN<7>!J1B1!277!@baseboard_fab2_lib.baseboard_fab2(sch_1):page83_i66@mstr_sconn.sconn288_h44441004(chips)!SCONN288_H44441004_PIP-SCONN,HA!!!F175!DQS7N!!!!
S!M_K_DQS_DP<7>!J1B1!278!@baseboard_fab2_lib.baseboard_fab2(sch_1):page83_i66@mstr_sconn.sconn288_h44441004(chips)!SCONN288_H44441004_PIP-SCONN,HA!!!F175!DQS7P!!!!
S!M_K_DQS_DN<8>!J1B1!196!@baseboard_fab2_lib.baseboard_fab2(sch_1):page83_i66@mstr_sconn.sconn288_h44441004(chips)!SCONN288_H44441004_PIP-SCONN,HA!!!F175!DQS8N!!!!
S!M_K_DQS_DP<8>!J1B1!197!@baseboard_fab2_lib.baseboard_fab2(sch_1):page83_i66@mstr_sconn.sconn288_h44441004(chips)!SCONN288_H44441004_PIP-SCONN,HA!!!F175!DQS8P!!!!
S!M_K_DQS_DN<9>!J1B1!8!@baseboard_fab2_lib.baseboard_fab2(sch_1):page83_i66@mstr_sconn.sconn288_h44441004(chips)!SCONN288_H44441004_PIP-SCONN,HA!!!F175!DQS9N!!!!
S!M_K_DQS_DP<9>!J1B1!7!@baseboard_fab2_lib.baseboard_fab2(sch_1):page83_i66@mstr_sconn.sconn288_h44441004(chips)!SCONN288_H44441004_PIP-SCONN,HA!!!F175!DQS9P!!!!
S!GND!J1B1!283!@baseboard_fab2_lib.baseboard_fab2(sch_1):page83_i43@mstr_sconn.sconn288_h44441004(chips)!SCONN288_H44441004_PIP-SCONN,HA!!!F174!VSS(0)!!!!
S!GND!J1B1!261!@baseboard_fab2_lib.baseboard_fab2(sch_1):page83_i43@mstr_sconn.sconn288_h44441004(chips)!SCONN288_H44441004_PIP-SCONN,HA!!!F174!VSS(10)!!!!
S!GND!J1B1!259!@baseboard_fab2_lib.baseboard_fab2(sch_1):page83_i43@mstr_sconn.sconn288_h44441004(chips)!SCONN288_H44441004_PIP-SCONN,HA!!!F174!VSS(11)!!!!
S!GND!J1B1!257!@baseboard_fab2_lib.baseboard_fab2(sch_1):page83_i43@mstr_sconn.sconn288_h44441004(chips)!SCONN288_H44441004_PIP-SCONN,HA!!!F174!VSS(12)!!!!
S!GND!J1B1!254!@baseboard_fab2_lib.baseboard_fab2(sch_1):page83_i43@mstr_sconn.sconn288_h44441004(chips)!SCONN288_H44441004_PIP-SCONN,HA!!!F174!VSS(13)!!!!
S!GND!J1B1!252!@baseboard_fab2_lib.baseboard_fab2(sch_1):page83_i43@mstr_sconn.sconn288_h44441004(chips)!SCONN288_H44441004_PIP-SCONN,HA!!!F174!VSS(14)!!!!
S!GND!J1B1!250!@baseboard_fab2_lib.baseboard_fab2(sch_1):page83_i43@mstr_sconn.sconn288_h44441004(chips)!SCONN288_H44441004_PIP-SCONN,HA!!!F174!VSS(15)!!!!
S!GND!J1B1!248!@baseboard_fab2_lib.baseboard_fab2(sch_1):page83_i43@mstr_sconn.sconn288_h44441004(chips)!SCONN288_H44441004_PIP-SCONN,HA!!!F174!VSS(16)!!!!
S!GND!J1B1!246!@baseboard_fab2_lib.baseboard_fab2(sch_1):page83_i43@mstr_sconn.sconn288_h44441004(chips)!SCONN288_H44441004_PIP-SCONN,HA!!!F174!VSS(17)!!!!
S!GND!J1B1!243!@baseboard_fab2_lib.baseboard_fab2(sch_1):page83_i43@mstr_sconn.sconn288_h44441004(chips)!SCONN288_H44441004_PIP-SCONN,HA!!!F174!VSS(18)!!!!
S!GND!J1B1!241!@baseboard_fab2_lib.baseboard_fab2(sch_1):page83_i43@mstr_sconn.sconn288_h44441004(chips)!SCONN288_H44441004_PIP-SCONN,HA!!!F174!VSS(19)!!!!
S!GND!J1B1!281!@baseboard_fab2_lib.baseboard_fab2(sch_1):page83_i43@mstr_sconn.sconn288_h44441004(chips)!SCONN288_H44441004_PIP-SCONN,HA!!!F174!VSS(1)!!!!
S!GND!J1B1!239!@baseboard_fab2_lib.baseboard_fab2(sch_1):page83_i43@mstr_sconn.sconn288_h44441004(chips)!SCONN288_H44441004_PIP-SCONN,HA!!!F174!VSS(20)!!!!
S!GND!J1B1!202!@baseboard_fab2_lib.baseboard_fab2(sch_1):page83_i43@mstr_sconn.sconn288_h44441004(chips)!SCONN288_H44441004_PIP-SCONN,HA!!!F174!VSS(21)!!!!
S!GND!J1B1!200!@baseboard_fab2_lib.baseboard_fab2(sch_1):page83_i43@mstr_sconn.sconn288_h44441004(chips)!SCONN288_H44441004_PIP-SCONN,HA!!!F174!VSS(22)!!!!
S!GND!J1B1!198!@baseboard_fab2_lib.baseboard_fab2(sch_1):page83_i43@mstr_sconn.sconn288_h44441004(chips)!SCONN288_H44441004_PIP-SCONN,HA!!!F174!VSS(23)!!!!
S!GND!J1B1!195!@baseboard_fab2_lib.baseboard_fab2(sch_1):page83_i43@mstr_sconn.sconn288_h44441004(chips)!SCONN288_H44441004_PIP-SCONN,HA!!!F174!VSS(24)!!!!
S!GND!J1B1!193!@baseboard_fab2_lib.baseboard_fab2(sch_1):page83_i43@mstr_sconn.sconn288_h44441004(chips)!SCONN288_H44441004_PIP-SCONN,HA!!!F174!VSS(25)!!!!
S!GND!J1B1!191!@baseboard_fab2_lib.baseboard_fab2(sch_1):page83_i43@mstr_sconn.sconn288_h44441004(chips)!SCONN288_H44441004_PIP-SCONN,HA!!!F174!VSS(26)!!!!
S!GND!J1B1!189!@baseboard_fab2_lib.baseboard_fab2(sch_1):page83_i43@mstr_sconn.sconn288_h44441004(chips)!SCONN288_H44441004_PIP-SCONN,HA!!!F174!VSS(27)!!!!
S!GND!J1B1!187!@baseboard_fab2_lib.baseboard_fab2(sch_1):page83_i43@mstr_sconn.sconn288_h44441004(chips)!SCONN288_H44441004_PIP-SCONN,HA!!!F174!VSS(28)!!!!
S!GND!J1B1!184!@baseboard_fab2_lib.baseboard_fab2(sch_1):page83_i43@mstr_sconn.sconn288_h44441004(chips)!SCONN288_H44441004_PIP-SCONN,HA!!!F174!VSS(29)!!!!
S!GND!J1B1!279!@baseboard_fab2_lib.baseboard_fab2(sch_1):page83_i43@mstr_sconn.sconn288_h44441004(chips)!SCONN288_H44441004_PIP-SCONN,HA!!!F174!VSS(2)!!!!
S!GND!J1B1!182!@baseboard_fab2_lib.baseboard_fab2(sch_1):page83_i43@mstr_sconn.sconn288_h44441004(chips)!SCONN288_H44441004_PIP-SCONN,HA!!!F174!VSS(30)!!!!
S!GND!J1B1!180!@baseboard_fab2_lib.baseboard_fab2(sch_1):page83_i43@mstr_sconn.sconn288_h44441004(chips)!SCONN288_H44441004_PIP-SCONN,HA!!!F174!VSS(31)!!!!
S!GND!J1B1!178!@baseboard_fab2_lib.baseboard_fab2(sch_1):page83_i43@mstr_sconn.sconn288_h44441004(chips)!SCONN288_H44441004_PIP-SCONN,HA!!!F174!VSS(32)!!!!
S!GND!J1B1!176!@baseboard_fab2_lib.baseboard_fab2(sch_1):page83_i43@mstr_sconn.sconn288_h44441004(chips)!SCONN288_H44441004_PIP-SCONN,HA!!!F174!VSS(33)!!!!
S!GND!J1B1!173!@baseboard_fab2_lib.baseboard_fab2(sch_1):page83_i43@mstr_sconn.sconn288_h44441004(chips)!SCONN288_H44441004_PIP-SCONN,HA!!!F174!VSS(34)!!!!
S!GND!J1B1!171!@baseboard_fab2_lib.baseboard_fab2(sch_1):page83_i43@mstr_sconn.sconn288_h44441004(chips)!SCONN288_H44441004_PIP-SCONN,HA!!!F174!VSS(35)!!!!
S!GND!J1B1!169!@baseboard_fab2_lib.baseboard_fab2(sch_1):page83_i43@mstr_sconn.sconn288_h44441004(chips)!SCONN288_H44441004_PIP-SCONN,HA!!!F174!VSS(36)!!!!
S!GND!J1B1!167!@baseboard_fab2_lib.baseboard_fab2(sch_1):page83_i43@mstr_sconn.sconn288_h44441004(chips)!SCONN288_H44441004_PIP-SCONN,HA!!!F174!VSS(37)!!!!
S!GND!J1B1!165!@baseboard_fab2_lib.baseboard_fab2(sch_1):page83_i43@mstr_sconn.sconn288_h44441004(chips)!SCONN288_H44441004_PIP-SCONN,HA!!!F174!VSS(38)!!!!
S!GND!J1B1!162!@baseboard_fab2_lib.baseboard_fab2(sch_1):page83_i43@mstr_sconn.sconn288_h44441004(chips)!SCONN288_H44441004_PIP-SCONN,HA!!!F174!VSS(39)!!!!
S!GND!J1B1!276!@baseboard_fab2_lib.baseboard_fab2(sch_1):page83_i43@mstr_sconn.sconn288_h44441004(chips)!SCONN288_H44441004_PIP-SCONN,HA!!!F174!VSS(3)!!!!
S!GND!J1B1!160!@baseboard_fab2_lib.baseboard_fab2(sch_1):page83_i43@mstr_sconn.sconn288_h44441004(chips)!SCONN288_H44441004_PIP-SCONN,HA!!!F174!VSS(40)!!!!
S!GND!J1B1!158!@baseboard_fab2_lib.baseboard_fab2(sch_1):page83_i43@mstr_sconn.sconn288_h44441004(chips)!SCONN288_H44441004_PIP-SCONN,HA!!!F174!VSS(41)!!!!
S!GND!J1B1!156!@baseboard_fab2_lib.baseboard_fab2(sch_1):page83_i43@mstr_sconn.sconn288_h44441004(chips)!SCONN288_H44441004_PIP-SCONN,HA!!!F174!VSS(42)!!!!
S!GND!J1B1!154!@baseboard_fab2_lib.baseboard_fab2(sch_1):page83_i43@mstr_sconn.sconn288_h44441004(chips)!SCONN288_H44441004_PIP-SCONN,HA!!!F174!VSS(43)!!!!
S!GND!J1B1!151!@baseboard_fab2_lib.baseboard_fab2(sch_1):page83_i43@mstr_sconn.sconn288_h44441004(chips)!SCONN288_H44441004_PIP-SCONN,HA!!!F174!VSS(44)!!!!
S!GND!J1B1!149!@baseboard_fab2_lib.baseboard_fab2(sch_1):page83_i43@mstr_sconn.sconn288_h44441004(chips)!SCONN288_H44441004_PIP-SCONN,HA!!!F174!VSS(45)!!!!
S!GND!J1B1!147!@baseboard_fab2_lib.baseboard_fab2(sch_1):page83_i43@mstr_sconn.sconn288_h44441004(chips)!SCONN288_H44441004_PIP-SCONN,HA!!!F174!VSS(46)!!!!
S!GND!J1B1!138!@baseboard_fab2_lib.baseboard_fab2(sch_1):page83_i43@mstr_sconn.sconn288_h44441004(chips)!SCONN288_H44441004_PIP-SCONN,HA!!!F174!VSS(47)!!!!
S!GND!J1B1!136!@baseboard_fab2_lib.baseboard_fab2(sch_1):page83_i43@mstr_sconn.sconn288_h44441004(chips)!SCONN288_H44441004_PIP-SCONN,HA!!!F174!VSS(48)!!!!
S!GND!J1B1!134!@baseboard_fab2_lib.baseboard_fab2(sch_1):page83_i43@mstr_sconn.sconn288_h44441004(chips)!SCONN288_H44441004_PIP-SCONN,HA!!!F174!VSS(49)!!!!
S!GND!J1B1!274!@baseboard_fab2_lib.baseboard_fab2(sch_1):page83_i43@mstr_sconn.sconn288_h44441004(chips)!SCONN288_H44441004_PIP-SCONN,HA!!!F174!VSS(4)!!!!
S!GND!J1B1!131!@baseboard_fab2_lib.baseboard_fab2(sch_1):page83_i43@mstr_sconn.sconn288_h44441004(chips)!SCONN288_H44441004_PIP-SCONN,HA!!!F174!VSS(50)!!!!
S!GND!J1B1!129!@baseboard_fab2_lib.baseboard_fab2(sch_1):page83_i43@mstr_sconn.sconn288_h44441004(chips)!SCONN288_H44441004_PIP-SCONN,HA!!!F174!VSS(51)!!!!
S!GND!J1B1!127!@baseboard_fab2_lib.baseboard_fab2(sch_1):page83_i43@mstr_sconn.sconn288_h44441004(chips)!SCONN288_H44441004_PIP-SCONN,HA!!!F174!VSS(52)!!!!
S!GND!J1B1!125!@baseboard_fab2_lib.baseboard_fab2(sch_1):page83_i43@mstr_sconn.sconn288_h44441004(chips)!SCONN288_H44441004_PIP-SCONN,HA!!!F174!VSS(53)!!!!
S!GND!J1B1!123!@baseboard_fab2_lib.baseboard_fab2(sch_1):page83_i43@mstr_sconn.sconn288_h44441004(chips)!SCONN288_H44441004_PIP-SCONN,HA!!!F174!VSS(54)!!!!
S!GND!J1B1!120!@baseboard_fab2_lib.baseboard_fab2(sch_1):page83_i43@mstr_sconn.sconn288_h44441004(chips)!SCONN288_H44441004_PIP-SCONN,HA!!!F174!VSS(55)!!!!
S!GND!J1B1!118!@baseboard_fab2_lib.baseboard_fab2(sch_1):page83_i43@mstr_sconn.sconn288_h44441004(chips)!SCONN288_H44441004_PIP-SCONN,HA!!!F174!VSS(56)!!!!
S!GND!J1B1!116!@baseboard_fab2_lib.baseboard_fab2(sch_1):page83_i43@mstr_sconn.sconn288_h44441004(chips)!SCONN288_H44441004_PIP-SCONN,HA!!!F174!VSS(57)!!!!
S!GND!J1B1!114!@baseboard_fab2_lib.baseboard_fab2(sch_1):page83_i43@mstr_sconn.sconn288_h44441004(chips)!SCONN288_H44441004_PIP-SCONN,HA!!!F174!VSS(58)!!!!
S!GND!J1B1!112!@baseboard_fab2_lib.baseboard_fab2(sch_1):page83_i43@mstr_sconn.sconn288_h44441004(chips)!SCONN288_H44441004_PIP-SCONN,HA!!!F174!VSS(59)!!!!
S!GND!J1B1!272!@baseboard_fab2_lib.baseboard_fab2(sch_1):page83_i43@mstr_sconn.sconn288_h44441004(chips)!SCONN288_H44441004_PIP-SCONN,HA!!!F174!VSS(5)!!!!
S!GND!J1B1!109!@baseboard_fab2_lib.baseboard_fab2(sch_1):page83_i43@mstr_sconn.sconn288_h44441004(chips)!SCONN288_H44441004_PIP-SCONN,HA!!!F174!VSS(60)!!!!
S!GND!J1B1!107!@baseboard_fab2_lib.baseboard_fab2(sch_1):page83_i43@mstr_sconn.sconn288_h44441004(chips)!SCONN288_H44441004_PIP-SCONN,HA!!!F174!VSS(61)!!!!
S!GND!J1B1!105!@baseboard_fab2_lib.baseboard_fab2(sch_1):page83_i43@mstr_sconn.sconn288_h44441004(chips)!SCONN288_H44441004_PIP-SCONN,HA!!!F174!VSS(62)!!!!
S!GND!J1B1!103!@baseboard_fab2_lib.baseboard_fab2(sch_1):page83_i43@mstr_sconn.sconn288_h44441004(chips)!SCONN288_H44441004_PIP-SCONN,HA!!!F174!VSS(63)!!!!
S!GND!J1B1!101!@baseboard_fab2_lib.baseboard_fab2(sch_1):page83_i43@mstr_sconn.sconn288_h44441004(chips)!SCONN288_H44441004_PIP-SCONN,HA!!!F174!VSS(64)!!!!
S!GND!J1B1!98!@baseboard_fab2_lib.baseboard_fab2(sch_1):page83_i43@mstr_sconn.sconn288_h44441004(chips)!SCONN288_H44441004_PIP-SCONN,HA!!!F174!VSS(65)!!!!
S!GND!J1B1!96!@baseboard_fab2_lib.baseboard_fab2(sch_1):page83_i43@mstr_sconn.sconn288_h44441004(chips)!SCONN288_H44441004_PIP-SCONN,HA!!!F174!VSS(66)!!!!
S!GND!J1B1!94!@baseboard_fab2_lib.baseboard_fab2(sch_1):page83_i43@mstr_sconn.sconn288_h44441004(chips)!SCONN288_H44441004_PIP-SCONN,HA!!!F174!VSS(67)!!!!
S!GND!J1B1!57!@baseboard_fab2_lib.baseboard_fab2(sch_1):page83_i43@mstr_sconn.sconn288_h44441004(chips)!SCONN288_H44441004_PIP-SCONN,HA!!!F174!VSS(68)!!!!
S!GND!J1B1!55!@baseboard_fab2_lib.baseboard_fab2(sch_1):page83_i43@mstr_sconn.sconn288_h44441004(chips)!SCONN288_H44441004_PIP-SCONN,HA!!!F174!VSS(69)!!!!
S!GND!J1B1!270!@baseboard_fab2_lib.baseboard_fab2(sch_1):page83_i43@mstr_sconn.sconn288_h44441004(chips)!SCONN288_H44441004_PIP-SCONN,HA!!!F174!VSS(6)!!!!
S!GND!J1B1!53!@baseboard_fab2_lib.baseboard_fab2(sch_1):page83_i43@mstr_sconn.sconn288_h44441004(chips)!SCONN288_H44441004_PIP-SCONN,HA!!!F174!VSS(70)!!!!
S!GND!J1B1!50!@baseboard_fab2_lib.baseboard_fab2(sch_1):page83_i43@mstr_sconn.sconn288_h44441004(chips)!SCONN288_H44441004_PIP-SCONN,HA!!!F174!VSS(71)!!!!
S!GND!J1B1!48!@baseboard_fab2_lib.baseboard_fab2(sch_1):page83_i43@mstr_sconn.sconn288_h44441004(chips)!SCONN288_H44441004_PIP-SCONN,HA!!!F174!VSS(72)!!!!
S!GND!J1B1!46!@baseboard_fab2_lib.baseboard_fab2(sch_1):page83_i43@mstr_sconn.sconn288_h44441004(chips)!SCONN288_H44441004_PIP-SCONN,HA!!!F174!VSS(73)!!!!
S!GND!J1B1!44!@baseboard_fab2_lib.baseboard_fab2(sch_1):page83_i43@mstr_sconn.sconn288_h44441004(chips)!SCONN288_H44441004_PIP-SCONN,HA!!!F174!VSS(74)!!!!
S!GND!J1B1!42!@baseboard_fab2_lib.baseboard_fab2(sch_1):page83_i43@mstr_sconn.sconn288_h44441004(chips)!SCONN288_H44441004_PIP-SCONN,HA!!!F174!VSS(75)!!!!
S!GND!J1B1!39!@baseboard_fab2_lib.baseboard_fab2(sch_1):page83_i43@mstr_sconn.sconn288_h44441004(chips)!SCONN288_H44441004_PIP-SCONN,HA!!!F174!VSS(76)!!!!
S!GND!J1B1!37!@baseboard_fab2_lib.baseboard_fab2(sch_1):page83_i43@mstr_sconn.sconn288_h44441004(chips)!SCONN288_H44441004_PIP-SCONN,HA!!!F174!VSS(77)!!!!
S!GND!J1B1!35!@baseboard_fab2_lib.baseboard_fab2(sch_1):page83_i43@mstr_sconn.sconn288_h44441004(chips)!SCONN288_H44441004_PIP-SCONN,HA!!!F174!VSS(78)!!!!
S!GND!J1B1!33!@baseboard_fab2_lib.baseboard_fab2(sch_1):page83_i43@mstr_sconn.sconn288_h44441004(chips)!SCONN288_H44441004_PIP-SCONN,HA!!!F174!VSS(79)!!!!
S!GND!J1B1!268!@baseboard_fab2_lib.baseboard_fab2(sch_1):page83_i43@mstr_sconn.sconn288_h44441004(chips)!SCONN288_H44441004_PIP-SCONN,HA!!!F174!VSS(7)!!!!
S!GND!J1B1!31!@baseboard_fab2_lib.baseboard_fab2(sch_1):page83_i43@mstr_sconn.sconn288_h44441004(chips)!SCONN288_H44441004_PIP-SCONN,HA!!!F174!VSS(80)!!!!
S!GND!J1B1!28!@baseboard_fab2_lib.baseboard_fab2(sch_1):page83_i43@mstr_sconn.sconn288_h44441004(chips)!SCONN288_H44441004_PIP-SCONN,HA!!!F174!VSS(81)!!!!
S!GND!J1B1!26!@baseboard_fab2_lib.baseboard_fab2(sch_1):page83_i43@mstr_sconn.sconn288_h44441004(chips)!SCONN288_H44441004_PIP-SCONN,HA!!!F174!VSS(82)!!!!
S!GND!J1B1!24!@baseboard_fab2_lib.baseboard_fab2(sch_1):page83_i43@mstr_sconn.sconn288_h44441004(chips)!SCONN288_H44441004_PIP-SCONN,HA!!!F174!VSS(83)!!!!
S!GND!J1B1!22!@baseboard_fab2_lib.baseboard_fab2(sch_1):page83_i43@mstr_sconn.sconn288_h44441004(chips)!SCONN288_H44441004_PIP-SCONN,HA!!!F174!VSS(84)!!!!
S!GND!J1B1!20!@baseboard_fab2_lib.baseboard_fab2(sch_1):page83_i43@mstr_sconn.sconn288_h44441004(chips)!SCONN288_H44441004_PIP-SCONN,HA!!!F174!VSS(85)!!!!
S!GND!J1B1!17!@baseboard_fab2_lib.baseboard_fab2(sch_1):page83_i43@mstr_sconn.sconn288_h44441004(chips)!SCONN288_H44441004_PIP-SCONN,HA!!!F174!VSS(86)!!!!
S!GND!J1B1!15!@baseboard_fab2_lib.baseboard_fab2(sch_1):page83_i43@mstr_sconn.sconn288_h44441004(chips)!SCONN288_H44441004_PIP-SCONN,HA!!!F174!VSS(87)!!!!
S!GND!J1B1!13!@baseboard_fab2_lib.baseboard_fab2(sch_1):page83_i43@mstr_sconn.sconn288_h44441004(chips)!SCONN288_H44441004_PIP-SCONN,HA!!!F174!VSS(88)!!!!
S!GND!J1B1!11!@baseboard_fab2_lib.baseboard_fab2(sch_1):page83_i43@mstr_sconn.sconn288_h44441004(chips)!SCONN288_H44441004_PIP-SCONN,HA!!!F174!VSS(89)!!!!
S!GND!J1B1!265!@baseboard_fab2_lib.baseboard_fab2(sch_1):page83_i43@mstr_sconn.sconn288_h44441004(chips)!SCONN288_H44441004_PIP-SCONN,HA!!!F174!VSS(8)!!!!
S!GND!J1B1!9!@baseboard_fab2_lib.baseboard_fab2(sch_1):page83_i43@mstr_sconn.sconn288_h44441004(chips)!SCONN288_H44441004_PIP-SCONN,HA!!!F174!VSS(90)!!!!
S!GND!J1B1!6!@baseboard_fab2_lib.baseboard_fab2(sch_1):page83_i43@mstr_sconn.sconn288_h44441004(chips)!SCONN288_H44441004_PIP-SCONN,HA!!!F174!VSS(91)!!!!
S!GND!J1B1!4!@baseboard_fab2_lib.baseboard_fab2(sch_1):page83_i43@mstr_sconn.sconn288_h44441004(chips)!SCONN288_H44441004_PIP-SCONN,HA!!!F174!VSS(92)!!!!
S!GND!J1B1!2!@baseboard_fab2_lib.baseboard_fab2(sch_1):page83_i43@mstr_sconn.sconn288_h44441004(chips)!SCONN288_H44441004_PIP-SCONN,HA!!!F174!VSS(93)!!!!
S!GND!J1B1!263!@baseboard_fab2_lib.baseboard_fab2(sch_1):page83_i43@mstr_sconn.sconn288_h44441004(chips)!SCONN288_H44441004_PIP-SCONN,HA!!!F174!VSS(9)!!!!
S!P12V_NVDIMM_KLM!J1B1!145!@baseboard_fab2_lib.baseboard_fab2(sch_1):page83_i167@mstr_sconn.sconn288_h44441004(chips)!SCONN288_H44441004_PIP-SCONN,HA!!!F173!\12v\(0)!!!!
S!P12V_NVDIMM_KLM!J1B1!1!@baseboard_fab2_lib.baseboard_fab2(sch_1):page83_i167@mstr_sconn.sconn288_h44441004(chips)!SCONN288_H44441004_PIP-SCONN,HA!!!F173!\12v\(1)!!!!
S!PVDDQ_KLM!J1B1!236!@baseboard_fab2_lib.baseboard_fab2(sch_1):page83_i167@mstr_sconn.sconn288_h44441004(chips)!SCONN288_H44441004_PIP-SCONN,HA!!!F173!VDD(0)!!!!
S!PVDDQ_KLM!J1B1!209!@baseboard_fab2_lib.baseboard_fab2(sch_1):page83_i167@mstr_sconn.sconn288_h44441004(chips)!SCONN288_H44441004_PIP-SCONN,HA!!!F173!VDD(10)!!!!
S!PVDDQ_KLM!J1B1!206!@baseboard_fab2_lib.baseboard_fab2(sch_1):page83_i167@mstr_sconn.sconn288_h44441004(chips)!SCONN288_H44441004_PIP-SCONN,HA!!!F173!VDD(11)!!!!
S!PVDDQ_KLM!J1B1!204!@baseboard_fab2_lib.baseboard_fab2(sch_1):page83_i167@mstr_sconn.sconn288_h44441004(chips)!SCONN288_H44441004_PIP-SCONN,HA!!!F173!VDD(12)!!!!
S!PVDDQ_KLM!J1B1!92!@baseboard_fab2_lib.baseboard_fab2(sch_1):page83_i167@mstr_sconn.sconn288_h44441004(chips)!SCONN288_H44441004_PIP-SCONN,HA!!!F173!VDD(13)!!!!
S!PVDDQ_KLM!J1B1!90!@baseboard_fab2_lib.baseboard_fab2(sch_1):page83_i167@mstr_sconn.sconn288_h44441004(chips)!SCONN288_H44441004_PIP-SCONN,HA!!!F173!VDD(14)!!!!
S!PVDDQ_KLM!J1B1!88!@baseboard_fab2_lib.baseboard_fab2(sch_1):page83_i167@mstr_sconn.sconn288_h44441004(chips)!SCONN288_H44441004_PIP-SCONN,HA!!!F173!VDD(15)!!!!
S!PVDDQ_KLM!J1B1!85!@baseboard_fab2_lib.baseboard_fab2(sch_1):page83_i167@mstr_sconn.sconn288_h44441004(chips)!SCONN288_H44441004_PIP-SCONN,HA!!!F173!VDD(16)!!!!
S!PVDDQ_KLM!J1B1!83!@baseboard_fab2_lib.baseboard_fab2(sch_1):page83_i167@mstr_sconn.sconn288_h44441004(chips)!SCONN288_H44441004_PIP-SCONN,HA!!!F173!VDD(17)!!!!
S!PVDDQ_KLM!J1B1!80!@baseboard_fab2_lib.baseboard_fab2(sch_1):page83_i167@mstr_sconn.sconn288_h44441004(chips)!SCONN288_H44441004_PIP-SCONN,HA!!!F173!VDD(18)!!!!
S!PVDDQ_KLM!J1B1!76!@baseboard_fab2_lib.baseboard_fab2(sch_1):page83_i167@mstr_sconn.sconn288_h44441004(chips)!SCONN288_H44441004_PIP-SCONN,HA!!!F173!VDD(19)!!!!
S!PVDDQ_KLM!J1B1!233!@baseboard_fab2_lib.baseboard_fab2(sch_1):page83_i167@mstr_sconn.sconn288_h44441004(chips)!SCONN288_H44441004_PIP-SCONN,HA!!!F173!VDD(1)!!!!
S!PVDDQ_KLM!J1B1!73!@baseboard_fab2_lib.baseboard_fab2(sch_1):page83_i167@mstr_sconn.sconn288_h44441004(chips)!SCONN288_H44441004_PIP-SCONN,HA!!!F173!VDD(20)!!!!
S!PVDDQ_KLM!J1B1!70!@baseboard_fab2_lib.baseboard_fab2(sch_1):page83_i167@mstr_sconn.sconn288_h44441004(chips)!SCONN288_H44441004_PIP-SCONN,HA!!!F173!VDD(21)!!!!
S!PVDDQ_KLM!J1B1!67!@baseboard_fab2_lib.baseboard_fab2(sch_1):page83_i167@mstr_sconn.sconn288_h44441004(chips)!SCONN288_H44441004_PIP-SCONN,HA!!!F173!VDD(22)!!!!
S!PVDDQ_KLM!J1B1!64!@baseboard_fab2_lib.baseboard_fab2(sch_1):page83_i167@mstr_sconn.sconn288_h44441004(chips)!SCONN288_H44441004_PIP-SCONN,HA!!!F173!VDD(23)!!!!
S!PVDDQ_KLM!J1B1!61!@baseboard_fab2_lib.baseboard_fab2(sch_1):page83_i167@mstr_sconn.sconn288_h44441004(chips)!SCONN288_H44441004_PIP-SCONN,HA!!!F173!VDD(24)!!!!
S!PVDDQ_KLM!J1B1!59!@baseboard_fab2_lib.baseboard_fab2(sch_1):page83_i167@mstr_sconn.sconn288_h44441004(chips)!SCONN288_H44441004_PIP-SCONN,HA!!!F173!VDD(25)!!!!
S!PVDDQ_KLM!J1B1!231!@baseboard_fab2_lib.baseboard_fab2(sch_1):page83_i167@mstr_sconn.sconn288_h44441004(chips)!SCONN288_H44441004_PIP-SCONN,HA!!!F173!VDD(2)!!!!
S!PVDDQ_KLM!J1B1!229!@baseboard_fab2_lib.baseboard_fab2(sch_1):page83_i167@mstr_sconn.sconn288_h44441004(chips)!SCONN288_H44441004_PIP-SCONN,HA!!!F173!VDD(3)!!!!
S!PVDDQ_KLM!J1B1!226!@baseboard_fab2_lib.baseboard_fab2(sch_1):page83_i167@mstr_sconn.sconn288_h44441004(chips)!SCONN288_H44441004_PIP-SCONN,HA!!!F173!VDD(4)!!!!
S!PVDDQ_KLM!J1B1!223!@baseboard_fab2_lib.baseboard_fab2(sch_1):page83_i167@mstr_sconn.sconn288_h44441004(chips)!SCONN288_H44441004_PIP-SCONN,HA!!!F173!VDD(5)!!!!
S!PVDDQ_KLM!J1B1!220!@baseboard_fab2_lib.baseboard_fab2(sch_1):page83_i167@mstr_sconn.sconn288_h44441004(chips)!SCONN288_H44441004_PIP-SCONN,HA!!!F173!VDD(6)!!!!
S!PVDDQ_KLM!J1B1!217!@baseboard_fab2_lib.baseboard_fab2(sch_1):page83_i167@mstr_sconn.sconn288_h44441004(chips)!SCONN288_H44441004_PIP-SCONN,HA!!!F173!VDD(7)!!!!
S!PVDDQ_KLM!J1B1!215!@baseboard_fab2_lib.baseboard_fab2(sch_1):page83_i167@mstr_sconn.sconn288_h44441004(chips)!SCONN288_H44441004_PIP-SCONN,HA!!!F173!VDD(8)!!!!
S!PVDDQ_KLM!J1B1!212!@baseboard_fab2_lib.baseboard_fab2(sch_1):page83_i167@mstr_sconn.sconn288_h44441004(chips)!SCONN288_H44441004_PIP-SCONN,HA!!!F173!VDD(9)!!!!
S!PVPP_KLM!J1B1!287!@baseboard_fab2_lib.baseboard_fab2(sch_1):page83_i167@mstr_sconn.sconn288_h44441004(chips)!SCONN288_H44441004_PIP-SCONN,HA!!!F173!VPP(0)!!!!
S!PVPP_KLM!J1B1!286!@baseboard_fab2_lib.baseboard_fab2(sch_1):page83_i167@mstr_sconn.sconn288_h44441004(chips)!SCONN288_H44441004_PIP-SCONN,HA!!!F173!VPP(1)!!!!
S!PVPP_KLM!J1B1!288!@baseboard_fab2_lib.baseboard_fab2(sch_1):page83_i167@mstr_sconn.sconn288_h44441004(chips)!SCONN288_H44441004_PIP-SCONN,HA!!!F173!VPP(2)!!!!
S!PVPP_KLM!J1B1!143!@baseboard_fab2_lib.baseboard_fab2(sch_1):page83_i167@mstr_sconn.sconn288_h44441004(chips)!SCONN288_H44441004_PIP-SCONN,HA!!!F173!VPP(3)!!!!
S!PVPP_KLM!J1B1!142!@baseboard_fab2_lib.baseboard_fab2(sch_1):page83_i167@mstr_sconn.sconn288_h44441004(chips)!SCONN288_H44441004_PIP-SCONN,HA!!!F173!VPP(4)!!!!
S!PVTT_KLM!J1B1!221!@baseboard_fab2_lib.baseboard_fab2(sch_1):page83_i167@mstr_sconn.sconn288_h44441004(chips)!SCONN288_H44441004_PIP-SCONN,HA!!!F173!VTT(0)!!!!
S!PVTT_KLM!J1B1!77!@baseboard_fab2_lib.baseboard_fab2(sch_1):page83_i167@mstr_sconn.sconn288_h44441004(chips)!SCONN288_H44441004_PIP-SCONN,HA!!!F173!VTT(1)!!!!
S!M_L_MA<0>!J1A2!79!@baseboard_fab2_lib.baseboard_fab2(sch_1):page85_i111@mstr_sconn.sconn288_h44441004(chips)!SCONN288_H44441004_PIP-SCONN,HA!!!F180!A0!!!!
S!M_L_MA<1>!J1A2!72!@baseboard_fab2_lib.baseboard_fab2(sch_1):page85_i111@mstr_sconn.sconn288_h44441004(chips)!SCONN288_H44441004_PIP-SCONN,HA!!!F180!A1!!!!
S!M_L_MA<10>!J1A2!225!@baseboard_fab2_lib.baseboard_fab2(sch_1):page85_i111@mstr_sconn.sconn288_h44441004(chips)!SCONN288_H44441004_PIP-SCONN,HA!!!F180!A10!!!!
S!M_L_MA<11>!J1A2!210!@baseboard_fab2_lib.baseboard_fab2(sch_1):page85_i111@mstr_sconn.sconn288_h44441004(chips)!SCONN288_H44441004_PIP-SCONN,HA!!!F180!A11!!!!
S!M_L_MA<12>!J1A2!65!@baseboard_fab2_lib.baseboard_fab2(sch_1):page85_i111@mstr_sconn.sconn288_h44441004(chips)!SCONN288_H44441004_PIP-SCONN,HA!!!F180!A12!!!!
S!M_L_MA<13>!J1A2!232!@baseboard_fab2_lib.baseboard_fab2(sch_1):page85_i111@mstr_sconn.sconn288_h44441004(chips)!SCONN288_H44441004_PIP-SCONN,HA!!!F180!A13!!!!
S!M_L_MA<14>!J1A2!228!@baseboard_fab2_lib.baseboard_fab2(sch_1):page85_i111@mstr_sconn.sconn288_h44441004(chips)!SCONN288_H44441004_PIP-SCONN,HA!!!F180!A14_WE_N!!!!
S!M_L_MA<15>!J1A2!86!@baseboard_fab2_lib.baseboard_fab2(sch_1):page85_i111@mstr_sconn.sconn288_h44441004(chips)!SCONN288_H44441004_PIP-SCONN,HA!!!F180!A15_CAS_N!!!!
S!M_L_MA<16>!J1A2!82!@baseboard_fab2_lib.baseboard_fab2(sch_1):page85_i111@mstr_sconn.sconn288_h44441004(chips)!SCONN288_H44441004_PIP-SCONN,HA!!!F180!A16_RAS_N!!!!
S!M_L_MA<17>!J1A2!234!@baseboard_fab2_lib.baseboard_fab2(sch_1):page85_i111@mstr_sconn.sconn288_h44441004(chips)!SCONN288_H44441004_PIP-SCONN,HA!!!F180!A17!!!!
S!M_L_MA<2>!J1A2!216!@baseboard_fab2_lib.baseboard_fab2(sch_1):page85_i111@mstr_sconn.sconn288_h44441004(chips)!SCONN288_H44441004_PIP-SCONN,HA!!!F180!A2!!!!
S!M_L_MA<3>!J1A2!71!@baseboard_fab2_lib.baseboard_fab2(sch_1):page85_i111@mstr_sconn.sconn288_h44441004(chips)!SCONN288_H44441004_PIP-SCONN,HA!!!F180!A3!!!!
S!M_L_MA<4>!J1A2!214!@baseboard_fab2_lib.baseboard_fab2(sch_1):page85_i111@mstr_sconn.sconn288_h44441004(chips)!SCONN288_H44441004_PIP-SCONN,HA!!!F180!A4!!!!
S!M_L_MA<5>!J1A2!213!@baseboard_fab2_lib.baseboard_fab2(sch_1):page85_i111@mstr_sconn.sconn288_h44441004(chips)!SCONN288_H44441004_PIP-SCONN,HA!!!F180!A5!!!!
S!M_L_MA<6>!J1A2!69!@baseboard_fab2_lib.baseboard_fab2(sch_1):page85_i111@mstr_sconn.sconn288_h44441004(chips)!SCONN288_H44441004_PIP-SCONN,HA!!!F180!A6!!!!
S!M_L_MA<7>!J1A2!211!@baseboard_fab2_lib.baseboard_fab2(sch_1):page85_i111@mstr_sconn.sconn288_h44441004(chips)!SCONN288_H44441004_PIP-SCONN,HA!!!F180!A7!!!!
S!M_L_MA<8>!J1A2!68!@baseboard_fab2_lib.baseboard_fab2(sch_1):page85_i111@mstr_sconn.sconn288_h44441004(chips)!SCONN288_H44441004_PIP-SCONN,HA!!!F180!A8!!!!
S!M_L_MA<9>!J1A2!66!@baseboard_fab2_lib.baseboard_fab2(sch_1):page85_i111@mstr_sconn.sconn288_h44441004(chips)!SCONN288_H44441004_PIP-SCONN,HA!!!F180!A9!!!!
S!M_L_ACT_N!J1A2!62!@baseboard_fab2_lib.baseboard_fab2(sch_1):page85_i111@mstr_sconn.sconn288_h44441004(chips)!SCONN288_H44441004_PIP-SCONN,HA!!!F180!ACT_N!!!!
S!M_L_ALERT_N!J1A2!208!@baseboard_fab2_lib.baseboard_fab2(sch_1):page85_i111@mstr_sconn.sconn288_h44441004(chips)!SCONN288_H44441004_PIP-SCONN,HA!!!F180!ALERT_N!!!!
S!M_L_BA<0>!J1A2!81!@baseboard_fab2_lib.baseboard_fab2(sch_1):page85_i111@mstr_sconn.sconn288_h44441004(chips)!SCONN288_H44441004_PIP-SCONN,HA!!!F180!BA(0)!!!!
S!M_L_BA<1>!J1A2!224!@baseboard_fab2_lib.baseboard_fab2(sch_1):page85_i111@mstr_sconn.sconn288_h44441004(chips)!SCONN288_H44441004_PIP-SCONN,HA!!!F180!BA(1)!!!!
S!M_L_BG<0>!J1A2!63!@baseboard_fab2_lib.baseboard_fab2(sch_1):page85_i111@mstr_sconn.sconn288_h44441004(chips)!SCONN288_H44441004_PIP-SCONN,HA!!!F180!BG(0)!!!!
S!M_L_BG<1>!J1A2!207!@baseboard_fab2_lib.baseboard_fab2(sch_1):page85_i111@mstr_sconn.sconn288_h44441004(chips)!SCONN288_H44441004_PIP-SCONN,HA!!!F180!BG(1)!!!!
S!M_L_C<2>!J1A2!235!@baseboard_fab2_lib.baseboard_fab2(sch_1):page85_i111@mstr_sconn.sconn288_h44441004(chips)!SCONN288_H44441004_PIP-SCONN,HA!!!F180!C(2)!!!!
S!M_L_ECC<1>!J1A2!49!@baseboard_fab2_lib.baseboard_fab2(sch_1):page85_i111@mstr_sconn.sconn288_h44441004(chips)!SCONN288_H44441004_PIP-SCONN,HA!!!F180!CB(0)!!!!
S!M_L_ECC<0>!J1A2!194!@baseboard_fab2_lib.baseboard_fab2(sch_1):page85_i111@mstr_sconn.sconn288_h44441004(chips)!SCONN288_H44441004_PIP-SCONN,HA!!!F180!CB(1)!!!!
S!M_L_ECC<3>!J1A2!56!@baseboard_fab2_lib.baseboard_fab2(sch_1):page85_i111@mstr_sconn.sconn288_h44441004(chips)!SCONN288_H44441004_PIP-SCONN,HA!!!F180!CB(2)!!!!
S!M_L_ECC<2>!J1A2!201!@baseboard_fab2_lib.baseboard_fab2(sch_1):page85_i111@mstr_sconn.sconn288_h44441004(chips)!SCONN288_H44441004_PIP-SCONN,HA!!!F180!CB(3)!!!!
S!M_L_ECC<5>!J1A2!47!@baseboard_fab2_lib.baseboard_fab2(sch_1):page85_i111@mstr_sconn.sconn288_h44441004(chips)!SCONN288_H44441004_PIP-SCONN,HA!!!F180!CB(4)!!!!
S!M_L_ECC<4>!J1A2!192!@baseboard_fab2_lib.baseboard_fab2(sch_1):page85_i111@mstr_sconn.sconn288_h44441004(chips)!SCONN288_H44441004_PIP-SCONN,HA!!!F180!CB(5)!!!!
S!M_L_ECC<7>!J1A2!54!@baseboard_fab2_lib.baseboard_fab2(sch_1):page85_i111@mstr_sconn.sconn288_h44441004(chips)!SCONN288_H44441004_PIP-SCONN,HA!!!F180!CB(6)!!!!
S!M_L_ECC<6>!J1A2!199!@baseboard_fab2_lib.baseboard_fab2(sch_1):page85_i111@mstr_sconn.sconn288_h44441004(chips)!SCONN288_H44441004_PIP-SCONN,HA!!!F180!CB(7)!!!!
S!M_L_CLK_DN<0>!J1A2!75!@baseboard_fab2_lib.baseboard_fab2(sch_1):page85_i111@mstr_sconn.sconn288_h44441004(chips)!SCONN288_H44441004_PIP-SCONN,HA!!!F180!CK0N!!!!
S!M_L_CLK_DP<0>!J1A2!74!@baseboard_fab2_lib.baseboard_fab2(sch_1):page85_i111@mstr_sconn.sconn288_h44441004(chips)!SCONN288_H44441004_PIP-SCONN,HA!!!F180!CK0P!!!!
S!M_L_CLK_DN<1>!J1A2!219!@baseboard_fab2_lib.baseboard_fab2(sch_1):page85_i111@mstr_sconn.sconn288_h44441004(chips)!SCONN288_H44441004_PIP-SCONN,HA!!!F180!CK1N!!!!
S!M_L_CLK_DP<1>!J1A2!218!@baseboard_fab2_lib.baseboard_fab2(sch_1):page85_i111@mstr_sconn.sconn288_h44441004(chips)!SCONN288_H44441004_PIP-SCONN,HA!!!F180!CK1P!!!!
S!M_L_CKE<0>!J1A2!60!@baseboard_fab2_lib.baseboard_fab2(sch_1):page85_i111@mstr_sconn.sconn288_h44441004(chips)!SCONN288_H44441004_PIP-SCONN,HA!!!F180!CKE(0)!!!!
S!M_L_CKE<1>!J1A2!203!@baseboard_fab2_lib.baseboard_fab2(sch_1):page85_i111@mstr_sconn.sconn288_h44441004(chips)!SCONN288_H44441004_PIP-SCONN,HA!!!F180!CKE(1)!!!!
S!M_L_DQ<1>!J1A2!5!@baseboard_fab2_lib.baseboard_fab2(sch_1):page85_i111@mstr_sconn.sconn288_h44441004(chips)!SCONN288_H44441004_PIP-SCONN,HA!!!F180!DQ(0)!!!!
S!M_L_DQ<11>!J1A2!23!@baseboard_fab2_lib.baseboard_fab2(sch_1):page85_i111@mstr_sconn.sconn288_h44441004(chips)!SCONN288_H44441004_PIP-SCONN,HA!!!F180!DQ(10)!!!!
S!M_L_DQ<10>!J1A2!168!@baseboard_fab2_lib.baseboard_fab2(sch_1):page85_i111@mstr_sconn.sconn288_h44441004(chips)!SCONN288_H44441004_PIP-SCONN,HA!!!F180!DQ(11)!!!!
S!M_L_DQ<13>!J1A2!14!@baseboard_fab2_lib.baseboard_fab2(sch_1):page85_i111@mstr_sconn.sconn288_h44441004(chips)!SCONN288_H44441004_PIP-SCONN,HA!!!F180!DQ(12)!!!!
S!M_L_DQ<12>!J1A2!159!@baseboard_fab2_lib.baseboard_fab2(sch_1):page85_i111@mstr_sconn.sconn288_h44441004(chips)!SCONN288_H44441004_PIP-SCONN,HA!!!F180!DQ(13)!!!!
S!M_L_DQ<15>!J1A2!21!@baseboard_fab2_lib.baseboard_fab2(sch_1):page85_i111@mstr_sconn.sconn288_h44441004(chips)!SCONN288_H44441004_PIP-SCONN,HA!!!F180!DQ(14)!!!!
S!M_L_DQ<14>!J1A2!166!@baseboard_fab2_lib.baseboard_fab2(sch_1):page85_i111@mstr_sconn.sconn288_h44441004(chips)!SCONN288_H44441004_PIP-SCONN,HA!!!F180!DQ(15)!!!!
S!M_L_DQ<17>!J1A2!27!@baseboard_fab2_lib.baseboard_fab2(sch_1):page85_i111@mstr_sconn.sconn288_h44441004(chips)!SCONN288_H44441004_PIP-SCONN,HA!!!F180!DQ(16)!!!!
S!M_L_DQ<16>!J1A2!172!@baseboard_fab2_lib.baseboard_fab2(sch_1):page85_i111@mstr_sconn.sconn288_h44441004(chips)!SCONN288_H44441004_PIP-SCONN,HA!!!F180!DQ(17)!!!!
S!M_L_DQ<19>!J1A2!34!@baseboard_fab2_lib.baseboard_fab2(sch_1):page85_i111@mstr_sconn.sconn288_h44441004(chips)!SCONN288_H44441004_PIP-SCONN,HA!!!F180!DQ(18)!!!!
S!M_L_DQ<18>!J1A2!179!@baseboard_fab2_lib.baseboard_fab2(sch_1):page85_i111@mstr_sconn.sconn288_h44441004(chips)!SCONN288_H44441004_PIP-SCONN,HA!!!F180!DQ(19)!!!!
S!M_L_DQ<0>!J1A2!150!@baseboard_fab2_lib.baseboard_fab2(sch_1):page85_i111@mstr_sconn.sconn288_h44441004(chips)!SCONN288_H44441004_PIP-SCONN,HA!!!F180!DQ(1)!!!!
S!M_L_DQ<21>!J1A2!25!@baseboard_fab2_lib.baseboard_fab2(sch_1):page85_i111@mstr_sconn.sconn288_h44441004(chips)!SCONN288_H44441004_PIP-SCONN,HA!!!F180!DQ(20)!!!!
S!M_L_DQ<20>!J1A2!170!@baseboard_fab2_lib.baseboard_fab2(sch_1):page85_i111@mstr_sconn.sconn288_h44441004(chips)!SCONN288_H44441004_PIP-SCONN,HA!!!F180!DQ(21)!!!!
S!M_L_DQ<23>!J1A2!32!@baseboard_fab2_lib.baseboard_fab2(sch_1):page85_i111@mstr_sconn.sconn288_h44441004(chips)!SCONN288_H44441004_PIP-SCONN,HA!!!F180!DQ(22)!!!!
S!M_L_DQ<22>!J1A2!177!@baseboard_fab2_lib.baseboard_fab2(sch_1):page85_i111@mstr_sconn.sconn288_h44441004(chips)!SCONN288_H44441004_PIP-SCONN,HA!!!F180!DQ(23)!!!!
S!M_L_DQ<25>!J1A2!38!@baseboard_fab2_lib.baseboard_fab2(sch_1):page85_i111@mstr_sconn.sconn288_h44441004(chips)!SCONN288_H44441004_PIP-SCONN,HA!!!F180!DQ(24)!!!!
S!M_L_DQ<24>!J1A2!183!@baseboard_fab2_lib.baseboard_fab2(sch_1):page85_i111@mstr_sconn.sconn288_h44441004(chips)!SCONN288_H44441004_PIP-SCONN,HA!!!F180!DQ(25)!!!!
S!M_L_DQ<27>!J1A2!45!@baseboard_fab2_lib.baseboard_fab2(sch_1):page85_i111@mstr_sconn.sconn288_h44441004(chips)!SCONN288_H44441004_PIP-SCONN,HA!!!F180!DQ(26)!!!!
S!M_L_DQ<26>!J1A2!190!@baseboard_fab2_lib.baseboard_fab2(sch_1):page85_i111@mstr_sconn.sconn288_h44441004(chips)!SCONN288_H44441004_PIP-SCONN,HA!!!F180!DQ(27)!!!!
S!M_L_DQ<29>!J1A2!36!@baseboard_fab2_lib.baseboard_fab2(sch_1):page85_i111@mstr_sconn.sconn288_h44441004(chips)!SCONN288_H44441004_PIP-SCONN,HA!!!F180!DQ(28)!!!!
S!M_L_DQ<28>!J1A2!181!@baseboard_fab2_lib.baseboard_fab2(sch_1):page85_i111@mstr_sconn.sconn288_h44441004(chips)!SCONN288_H44441004_PIP-SCONN,HA!!!F180!DQ(29)!!!!
S!M_L_DQ<3>!J1A2!12!@baseboard_fab2_lib.baseboard_fab2(sch_1):page85_i111@mstr_sconn.sconn288_h44441004(chips)!SCONN288_H44441004_PIP-SCONN,HA!!!F180!DQ(2)!!!!
S!M_L_DQ<31>!J1A2!43!@baseboard_fab2_lib.baseboard_fab2(sch_1):page85_i111@mstr_sconn.sconn288_h44441004(chips)!SCONN288_H44441004_PIP-SCONN,HA!!!F180!DQ(30)!!!!
S!M_L_DQ<30>!J1A2!188!@baseboard_fab2_lib.baseboard_fab2(sch_1):page85_i111@mstr_sconn.sconn288_h44441004(chips)!SCONN288_H44441004_PIP-SCONN,HA!!!F180!DQ(31)!!!!
S!M_L_DQ<33>!J1A2!97!@baseboard_fab2_lib.baseboard_fab2(sch_1):page85_i111@mstr_sconn.sconn288_h44441004(chips)!SCONN288_H44441004_PIP-SCONN,HA!!!F180!DQ(32)!!!!
S!M_L_DQ<32>!J1A2!242!@baseboard_fab2_lib.baseboard_fab2(sch_1):page85_i111@mstr_sconn.sconn288_h44441004(chips)!SCONN288_H44441004_PIP-SCONN,HA!!!F180!DQ(33)!!!!
S!M_L_DQ<35>!J1A2!104!@baseboard_fab2_lib.baseboard_fab2(sch_1):page85_i111@mstr_sconn.sconn288_h44441004(chips)!SCONN288_H44441004_PIP-SCONN,HA!!!F180!DQ(34)!!!!
S!M_L_DQ<34>!J1A2!249!@baseboard_fab2_lib.baseboard_fab2(sch_1):page85_i111@mstr_sconn.sconn288_h44441004(chips)!SCONN288_H44441004_PIP-SCONN,HA!!!F180!DQ(35)!!!!
S!M_L_DQ<37>!J1A2!95!@baseboard_fab2_lib.baseboard_fab2(sch_1):page85_i111@mstr_sconn.sconn288_h44441004(chips)!SCONN288_H44441004_PIP-SCONN,HA!!!F180!DQ(36)!!!!
S!M_L_DQ<36>!J1A2!240!@baseboard_fab2_lib.baseboard_fab2(sch_1):page85_i111@mstr_sconn.sconn288_h44441004(chips)!SCONN288_H44441004_PIP-SCONN,HA!!!F180!DQ(37)!!!!
S!M_L_DQ<39>!J1A2!102!@baseboard_fab2_lib.baseboard_fab2(sch_1):page85_i111@mstr_sconn.sconn288_h44441004(chips)!SCONN288_H44441004_PIP-SCONN,HA!!!F180!DQ(38)!!!!
S!M_L_DQ<38>!J1A2!247!@baseboard_fab2_lib.baseboard_fab2(sch_1):page85_i111@mstr_sconn.sconn288_h44441004(chips)!SCONN288_H44441004_PIP-SCONN,HA!!!F180!DQ(39)!!!!
S!M_L_DQ<2>!J1A2!157!@baseboard_fab2_lib.baseboard_fab2(sch_1):page85_i111@mstr_sconn.sconn288_h44441004(chips)!SCONN288_H44441004_PIP-SCONN,HA!!!F180!DQ(3)!!!!
S!M_L_DQ<41>!J1A2!108!@baseboard_fab2_lib.baseboard_fab2(sch_1):page85_i111@mstr_sconn.sconn288_h44441004(chips)!SCONN288_H44441004_PIP-SCONN,HA!!!F180!DQ(40)!!!!
S!M_L_DQ<40>!J1A2!253!@baseboard_fab2_lib.baseboard_fab2(sch_1):page85_i111@mstr_sconn.sconn288_h44441004(chips)!SCONN288_H44441004_PIP-SCONN,HA!!!F180!DQ(41)!!!!
S!M_L_DQ<43>!J1A2!115!@baseboard_fab2_lib.baseboard_fab2(sch_1):page85_i111@mstr_sconn.sconn288_h44441004(chips)!SCONN288_H44441004_PIP-SCONN,HA!!!F180!DQ(42)!!!!
S!M_L_DQ<42>!J1A2!260!@baseboard_fab2_lib.baseboard_fab2(sch_1):page85_i111@mstr_sconn.sconn288_h44441004(chips)!SCONN288_H44441004_PIP-SCONN,HA!!!F180!DQ(43)!!!!
S!M_L_DQ<45>!J1A2!106!@baseboard_fab2_lib.baseboard_fab2(sch_1):page85_i111@mstr_sconn.sconn288_h44441004(chips)!SCONN288_H44441004_PIP-SCONN,HA!!!F180!DQ(44)!!!!
S!M_L_DQ<44>!J1A2!251!@baseboard_fab2_lib.baseboard_fab2(sch_1):page85_i111@mstr_sconn.sconn288_h44441004(chips)!SCONN288_H44441004_PIP-SCONN,HA!!!F180!DQ(45)!!!!
S!M_L_DQ<47>!J1A2!113!@baseboard_fab2_lib.baseboard_fab2(sch_1):page85_i111@mstr_sconn.sconn288_h44441004(chips)!SCONN288_H44441004_PIP-SCONN,HA!!!F180!DQ(46)!!!!
S!M_L_DQ<46>!J1A2!258!@baseboard_fab2_lib.baseboard_fab2(sch_1):page85_i111@mstr_sconn.sconn288_h44441004(chips)!SCONN288_H44441004_PIP-SCONN,HA!!!F180!DQ(47)!!!!
S!M_L_DQ<49>!J1A2!119!@baseboard_fab2_lib.baseboard_fab2(sch_1):page85_i111@mstr_sconn.sconn288_h44441004(chips)!SCONN288_H44441004_PIP-SCONN,HA!!!F180!DQ(48)!!!!
S!M_L_DQ<48>!J1A2!264!@baseboard_fab2_lib.baseboard_fab2(sch_1):page85_i111@mstr_sconn.sconn288_h44441004(chips)!SCONN288_H44441004_PIP-SCONN,HA!!!F180!DQ(49)!!!!
S!M_L_DQ<5>!J1A2!3!@baseboard_fab2_lib.baseboard_fab2(sch_1):page85_i111@mstr_sconn.sconn288_h44441004(chips)!SCONN288_H44441004_PIP-SCONN,HA!!!F180!DQ(4)!!!!
S!M_L_DQ<51>!J1A2!126!@baseboard_fab2_lib.baseboard_fab2(sch_1):page85_i111@mstr_sconn.sconn288_h44441004(chips)!SCONN288_H44441004_PIP-SCONN,HA!!!F180!DQ(50)!!!!
S!M_L_DQ<50>!J1A2!271!@baseboard_fab2_lib.baseboard_fab2(sch_1):page85_i111@mstr_sconn.sconn288_h44441004(chips)!SCONN288_H44441004_PIP-SCONN,HA!!!F180!DQ(51)!!!!
S!M_L_DQ<53>!J1A2!117!@baseboard_fab2_lib.baseboard_fab2(sch_1):page85_i111@mstr_sconn.sconn288_h44441004(chips)!SCONN288_H44441004_PIP-SCONN,HA!!!F180!DQ(52)!!!!
S!M_L_DQ<52>!J1A2!262!@baseboard_fab2_lib.baseboard_fab2(sch_1):page85_i111@mstr_sconn.sconn288_h44441004(chips)!SCONN288_H44441004_PIP-SCONN,HA!!!F180!DQ(53)!!!!
S!M_L_DQ<55>!J1A2!124!@baseboard_fab2_lib.baseboard_fab2(sch_1):page85_i111@mstr_sconn.sconn288_h44441004(chips)!SCONN288_H44441004_PIP-SCONN,HA!!!F180!DQ(54)!!!!
S!M_L_DQ<54>!J1A2!269!@baseboard_fab2_lib.baseboard_fab2(sch_1):page85_i111@mstr_sconn.sconn288_h44441004(chips)!SCONN288_H44441004_PIP-SCONN,HA!!!F180!DQ(55)!!!!
S!M_L_DQ<57>!J1A2!130!@baseboard_fab2_lib.baseboard_fab2(sch_1):page85_i111@mstr_sconn.sconn288_h44441004(chips)!SCONN288_H44441004_PIP-SCONN,HA!!!F180!DQ(56)!!!!
S!M_L_DQ<56>!J1A2!275!@baseboard_fab2_lib.baseboard_fab2(sch_1):page85_i111@mstr_sconn.sconn288_h44441004(chips)!SCONN288_H44441004_PIP-SCONN,HA!!!F180!DQ(57)!!!!
S!M_L_DQ<59>!J1A2!137!@baseboard_fab2_lib.baseboard_fab2(sch_1):page85_i111@mstr_sconn.sconn288_h44441004(chips)!SCONN288_H44441004_PIP-SCONN,HA!!!F180!DQ(58)!!!!
S!M_L_DQ<58>!J1A2!282!@baseboard_fab2_lib.baseboard_fab2(sch_1):page85_i111@mstr_sconn.sconn288_h44441004(chips)!SCONN288_H44441004_PIP-SCONN,HA!!!F180!DQ(59)!!!!
S!M_L_DQ<4>!J1A2!148!@baseboard_fab2_lib.baseboard_fab2(sch_1):page85_i111@mstr_sconn.sconn288_h44441004(chips)!SCONN288_H44441004_PIP-SCONN,HA!!!F180!DQ(5)!!!!
S!M_L_DQ<61>!J1A2!128!@baseboard_fab2_lib.baseboard_fab2(sch_1):page85_i111@mstr_sconn.sconn288_h44441004(chips)!SCONN288_H44441004_PIP-SCONN,HA!!!F180!DQ(60)!!!!
S!M_L_DQ<60>!J1A2!273!@baseboard_fab2_lib.baseboard_fab2(sch_1):page85_i111@mstr_sconn.sconn288_h44441004(chips)!SCONN288_H44441004_PIP-SCONN,HA!!!F180!DQ(61)!!!!
S!M_L_DQ<63>!J1A2!135!@baseboard_fab2_lib.baseboard_fab2(sch_1):page85_i111@mstr_sconn.sconn288_h44441004(chips)!SCONN288_H44441004_PIP-SCONN,HA!!!F180!DQ(62)!!!!
S!M_L_DQ<62>!J1A2!280!@baseboard_fab2_lib.baseboard_fab2(sch_1):page85_i111@mstr_sconn.sconn288_h44441004(chips)!SCONN288_H44441004_PIP-SCONN,HA!!!F180!DQ(63)!!!!
S!M_L_DQ<7>!J1A2!10!@baseboard_fab2_lib.baseboard_fab2(sch_1):page85_i111@mstr_sconn.sconn288_h44441004(chips)!SCONN288_H44441004_PIP-SCONN,HA!!!F180!DQ(6)!!!!
S!M_L_DQ<6>!J1A2!155!@baseboard_fab2_lib.baseboard_fab2(sch_1):page85_i111@mstr_sconn.sconn288_h44441004(chips)!SCONN288_H44441004_PIP-SCONN,HA!!!F180!DQ(7)!!!!
S!M_L_DQ<9>!J1A2!16!@baseboard_fab2_lib.baseboard_fab2(sch_1):page85_i111@mstr_sconn.sconn288_h44441004(chips)!SCONN288_H44441004_PIP-SCONN,HA!!!F180!DQ(8)!!!!
S!M_L_DQ<8>!J1A2!161!@baseboard_fab2_lib.baseboard_fab2(sch_1):page85_i111@mstr_sconn.sconn288_h44441004(chips)!SCONN288_H44441004_PIP-SCONN,HA!!!F180!DQ(9)!!!!
S!FM_DIMM_EVENT_COD_N!J1A2!78!@baseboard_fab2_lib.baseboard_fab2(sch_1):page85_i111@mstr_sconn.sconn288_h44441004(chips)!SCONN288_H44441004_PIP-SCONN,HA!!!F180!EVENT_N!!!!
S!M_L_ODT<0>!J1A2!87!@baseboard_fab2_lib.baseboard_fab2(sch_1):page85_i111@mstr_sconn.sconn288_h44441004(chips)!SCONN288_H44441004_PIP-SCONN,HA!!!F180!ODT(0)!!!!
S!M_L_ODT<1>!J1A2!91!@baseboard_fab2_lib.baseboard_fab2(sch_1):page85_i111@mstr_sconn.sconn288_h44441004(chips)!SCONN288_H44441004_PIP-SCONN,HA!!!F180!ODT(1)!!!!
S!M_L_PAR!J1A2!222!@baseboard_fab2_lib.baseboard_fab2(sch_1):page85_i111@mstr_sconn.sconn288_h44441004(chips)!SCONN288_H44441004_PIP-SCONN,HA!!!F180!PAR!!!!
S!M_KLM_RST_N!J1A2!58!@baseboard_fab2_lib.baseboard_fab2(sch_1):page85_i111@mstr_sconn.sconn288_h44441004(chips)!SCONN288_H44441004_PIP-SCONN,HA!!!F180!RESET_N!!!!
S!TP_CH_L_DIMM_L0_RFU_0!J1A2!205!@baseboard_fab2_lib.baseboard_fab2(sch_1):page85_i111@mstr_sconn.sconn288_h44441004(chips)!SCONN288_H44441004_PIP-SCONN,HA!!!F180!RFU(0)!!!!
S!TP_CH_L_DIMM_L0_RFU_1!J1A2!227!@baseboard_fab2_lib.baseboard_fab2(sch_1):page85_i111@mstr_sconn.sconn288_h44441004(chips)!SCONN288_H44441004_PIP-SCONN,HA!!!F180!RFU(1)!!!!
S!TP_CH_L_DIMM_L0_RFU_2!J1A2!144!@baseboard_fab2_lib.baseboard_fab2(sch_1):page85_i111@mstr_sconn.sconn288_h44441004(chips)!SCONN288_H44441004_PIP-SCONN,HA!!!F180!RFU(2)!!!!
S!M_L_CS_N<0>!J1A2!84!@baseboard_fab2_lib.baseboard_fab2(sch_1):page85_i111@mstr_sconn.sconn288_h44441004(chips)!SCONN288_H44441004_PIP-SCONN,HA!!!F180!S0_N!!!!
S!M_L_CS_N<1>!J1A2!89!@baseboard_fab2_lib.baseboard_fab2(sch_1):page85_i111@mstr_sconn.sconn288_h44441004(chips)!SCONN288_H44441004_PIP-SCONN,HA!!!F180!S1_N!!!!
S!M_L_CS_N<2>!J1A2!93!@baseboard_fab2_lib.baseboard_fab2(sch_1):page85_i111@mstr_sconn.sconn288_h44441004(chips)!SCONN288_H44441004_PIP-SCONN,HA!!!F180!S2_N_C(0)!!!!
S!M_L_CS_N<3>!J1A2!237!@baseboard_fab2_lib.baseboard_fab2(sch_1):page85_i111@mstr_sconn.sconn288_h44441004(chips)!SCONN288_H44441004_PIP-SCONN,HA!!!F180!S3_N_C(1)!!!!
S!GND!J1A2!139!@baseboard_fab2_lib.baseboard_fab2(sch_1):page85_i111@mstr_sconn.sconn288_h44441004(chips)!SCONN288_H44441004_PIP-SCONN,HA!!!F180!SA(0)!!!!
S!PVPP_KLM!J1A2!140!@baseboard_fab2_lib.baseboard_fab2(sch_1):page85_i111@mstr_sconn.sconn288_h44441004(chips)!SCONN288_H44441004_PIP-SCONN,HA!!!F180!SA(1)!!!!
S!GND!J1A2!238!@baseboard_fab2_lib.baseboard_fab2(sch_1):page85_i111@mstr_sconn.sconn288_h44441004(chips)!SCONN288_H44441004_PIP-SCONN,HA!!!F180!SA(2)!!!!
S!FM_ADR_COMPLETE_KLM_N!J1A2!230!@baseboard_fab2_lib.baseboard_fab2(sch_1):page85_i111@mstr_sconn.sconn288_h44441004(chips)!SCONN288_H44441004_PIP-SCONN,HA!!!F180!SAVE_N_NC!!!!
S!SMB_DDR_KLM_VPP_SCL!J1A2!141!@baseboard_fab2_lib.baseboard_fab2(sch_1):page85_i111@mstr_sconn.sconn288_h44441004(chips)!SCONN288_H44441004_PIP-SCONN,HA!!!F180!SCL!!!!
S!SMB_DDR_KLM_VPP_SDA!J1A2!285!@baseboard_fab2_lib.baseboard_fab2(sch_1):page85_i111@mstr_sconn.sconn288_h44441004(chips)!SCONN288_H44441004_PIP-SCONN,HA!!!F180!SDA!!!!
S!PVPP_KLM!J1A2!284!@baseboard_fab2_lib.baseboard_fab2(sch_1):page85_i111@mstr_sconn.sconn288_h44441004(chips)!SCONN288_H44441004_PIP-SCONN,HA!!!F180!VDDSPD!!!!
S!M_L_VREF!J1A2!146!@baseboard_fab2_lib.baseboard_fab2(sch_1):page85_i111@mstr_sconn.sconn288_h44441004(chips)!SCONN288_H44441004_PIP-SCONN,HA!!!F180!VREFCA!!!!
S!M_L_DQS_DN<0>!J1A2!152!@baseboard_fab2_lib.baseboard_fab2(sch_1):page85_i66@mstr_sconn.sconn288_h44441004(chips)!SCONN288_H44441004_PIP-SCONN,HA!!!F179!DQS0N!!!!
S!M_L_DQS_DP<0>!J1A2!153!@baseboard_fab2_lib.baseboard_fab2(sch_1):page85_i66@mstr_sconn.sconn288_h44441004(chips)!SCONN288_H44441004_PIP-SCONN,HA!!!F179!DQS0P!!!!
S!M_L_DQS_DN<10>!J1A2!19!@baseboard_fab2_lib.baseboard_fab2(sch_1):page85_i66@mstr_sconn.sconn288_h44441004(chips)!SCONN288_H44441004_PIP-SCONN,HA!!!F179!DQS10N!!!!
S!M_L_DQS_DP<10>!J1A2!18!@baseboard_fab2_lib.baseboard_fab2(sch_1):page85_i66@mstr_sconn.sconn288_h44441004(chips)!SCONN288_H44441004_PIP-SCONN,HA!!!F179!DQS10P!!!!
S!M_L_DQS_DN<11>!J1A2!30!@baseboard_fab2_lib.baseboard_fab2(sch_1):page85_i66@mstr_sconn.sconn288_h44441004(chips)!SCONN288_H44441004_PIP-SCONN,HA!!!F179!DQS11N!!!!
S!M_L_DQS_DP<11>!J1A2!29!@baseboard_fab2_lib.baseboard_fab2(sch_1):page85_i66@mstr_sconn.sconn288_h44441004(chips)!SCONN288_H44441004_PIP-SCONN,HA!!!F179!DQS11P!!!!
S!M_L_DQS_DN<12>!J1A2!41!@baseboard_fab2_lib.baseboard_fab2(sch_1):page85_i66@mstr_sconn.sconn288_h44441004(chips)!SCONN288_H44441004_PIP-SCONN,HA!!!F179!DQS12N!!!!
S!M_L_DQS_DP<12>!J1A2!40!@baseboard_fab2_lib.baseboard_fab2(sch_1):page85_i66@mstr_sconn.sconn288_h44441004(chips)!SCONN288_H44441004_PIP-SCONN,HA!!!F179!DQS12P!!!!
S!M_L_DQS_DN<13>!J1A2!100!@baseboard_fab2_lib.baseboard_fab2(sch_1):page85_i66@mstr_sconn.sconn288_h44441004(chips)!SCONN288_H44441004_PIP-SCONN,HA!!!F179!DQS13N!!!!
S!M_L_DQS_DP<13>!J1A2!99!@baseboard_fab2_lib.baseboard_fab2(sch_1):page85_i66@mstr_sconn.sconn288_h44441004(chips)!SCONN288_H44441004_PIP-SCONN,HA!!!F179!DQS13P!!!!
S!M_L_DQS_DN<14>!J1A2!111!@baseboard_fab2_lib.baseboard_fab2(sch_1):page85_i66@mstr_sconn.sconn288_h44441004(chips)!SCONN288_H44441004_PIP-SCONN,HA!!!F179!DQS14N!!!!
S!M_L_DQS_DP<14>!J1A2!110!@baseboard_fab2_lib.baseboard_fab2(sch_1):page85_i66@mstr_sconn.sconn288_h44441004(chips)!SCONN288_H44441004_PIP-SCONN,HA!!!F179!DQS14P!!!!
S!M_L_DQS_DN<15>!J1A2!122!@baseboard_fab2_lib.baseboard_fab2(sch_1):page85_i66@mstr_sconn.sconn288_h44441004(chips)!SCONN288_H44441004_PIP-SCONN,HA!!!F179!DQS15N!!!!
S!M_L_DQS_DP<15>!J1A2!121!@baseboard_fab2_lib.baseboard_fab2(sch_1):page85_i66@mstr_sconn.sconn288_h44441004(chips)!SCONN288_H44441004_PIP-SCONN,HA!!!F179!DQS15P!!!!
S!M_L_DQS_DN<16>!J1A2!133!@baseboard_fab2_lib.baseboard_fab2(sch_1):page85_i66@mstr_sconn.sconn288_h44441004(chips)!SCONN288_H44441004_PIP-SCONN,HA!!!F179!DQS16N!!!!
S!M_L_DQS_DP<16>!J1A2!132!@baseboard_fab2_lib.baseboard_fab2(sch_1):page85_i66@mstr_sconn.sconn288_h44441004(chips)!SCONN288_H44441004_PIP-SCONN,HA!!!F179!DQS16P!!!!
S!M_L_DQS_DN<17>!J1A2!52!@baseboard_fab2_lib.baseboard_fab2(sch_1):page85_i66@mstr_sconn.sconn288_h44441004(chips)!SCONN288_H44441004_PIP-SCONN,HA!!!F179!DQS17N!!!!
S!M_L_DQS_DP<17>!J1A2!51!@baseboard_fab2_lib.baseboard_fab2(sch_1):page85_i66@mstr_sconn.sconn288_h44441004(chips)!SCONN288_H44441004_PIP-SCONN,HA!!!F179!DQS17P!!!!
S!M_L_DQS_DN<1>!J1A2!163!@baseboard_fab2_lib.baseboard_fab2(sch_1):page85_i66@mstr_sconn.sconn288_h44441004(chips)!SCONN288_H44441004_PIP-SCONN,HA!!!F179!DQS1N!!!!
S!M_L_DQS_DP<1>!J1A2!164!@baseboard_fab2_lib.baseboard_fab2(sch_1):page85_i66@mstr_sconn.sconn288_h44441004(chips)!SCONN288_H44441004_PIP-SCONN,HA!!!F179!DQS1P!!!!
S!M_L_DQS_DN<2>!J1A2!174!@baseboard_fab2_lib.baseboard_fab2(sch_1):page85_i66@mstr_sconn.sconn288_h44441004(chips)!SCONN288_H44441004_PIP-SCONN,HA!!!F179!DQS2N!!!!
S!M_L_DQS_DP<2>!J1A2!175!@baseboard_fab2_lib.baseboard_fab2(sch_1):page85_i66@mstr_sconn.sconn288_h44441004(chips)!SCONN288_H44441004_PIP-SCONN,HA!!!F179!DQS2P!!!!
S!M_L_DQS_DN<3>!J1A2!185!@baseboard_fab2_lib.baseboard_fab2(sch_1):page85_i66@mstr_sconn.sconn288_h44441004(chips)!SCONN288_H44441004_PIP-SCONN,HA!!!F179!DQS3N!!!!
S!M_L_DQS_DP<3>!J1A2!186!@baseboard_fab2_lib.baseboard_fab2(sch_1):page85_i66@mstr_sconn.sconn288_h44441004(chips)!SCONN288_H44441004_PIP-SCONN,HA!!!F179!DQS3P!!!!
S!M_L_DQS_DN<4>!J1A2!244!@baseboard_fab2_lib.baseboard_fab2(sch_1):page85_i66@mstr_sconn.sconn288_h44441004(chips)!SCONN288_H44441004_PIP-SCONN,HA!!!F179!DQS4N!!!!
S!M_L_DQS_DP<4>!J1A2!245!@baseboard_fab2_lib.baseboard_fab2(sch_1):page85_i66@mstr_sconn.sconn288_h44441004(chips)!SCONN288_H44441004_PIP-SCONN,HA!!!F179!DQS4P!!!!
S!M_L_DQS_DN<5>!J1A2!255!@baseboard_fab2_lib.baseboard_fab2(sch_1):page85_i66@mstr_sconn.sconn288_h44441004(chips)!SCONN288_H44441004_PIP-SCONN,HA!!!F179!DQS5N!!!!
S!M_L_DQS_DP<5>!J1A2!256!@baseboard_fab2_lib.baseboard_fab2(sch_1):page85_i66@mstr_sconn.sconn288_h44441004(chips)!SCONN288_H44441004_PIP-SCONN,HA!!!F179!DQS5P!!!!
S!M_L_DQS_DN<6>!J1A2!266!@baseboard_fab2_lib.baseboard_fab2(sch_1):page85_i66@mstr_sconn.sconn288_h44441004(chips)!SCONN288_H44441004_PIP-SCONN,HA!!!F179!DQS6N!!!!
S!M_L_DQS_DP<6>!J1A2!267!@baseboard_fab2_lib.baseboard_fab2(sch_1):page85_i66@mstr_sconn.sconn288_h44441004(chips)!SCONN288_H44441004_PIP-SCONN,HA!!!F179!DQS6P!!!!
S!M_L_DQS_DN<7>!J1A2!277!@baseboard_fab2_lib.baseboard_fab2(sch_1):page85_i66@mstr_sconn.sconn288_h44441004(chips)!SCONN288_H44441004_PIP-SCONN,HA!!!F179!DQS7N!!!!
S!M_L_DQS_DP<7>!J1A2!278!@baseboard_fab2_lib.baseboard_fab2(sch_1):page85_i66@mstr_sconn.sconn288_h44441004(chips)!SCONN288_H44441004_PIP-SCONN,HA!!!F179!DQS7P!!!!
S!M_L_DQS_DN<8>!J1A2!196!@baseboard_fab2_lib.baseboard_fab2(sch_1):page85_i66@mstr_sconn.sconn288_h44441004(chips)!SCONN288_H44441004_PIP-SCONN,HA!!!F179!DQS8N!!!!
S!M_L_DQS_DP<8>!J1A2!197!@baseboard_fab2_lib.baseboard_fab2(sch_1):page85_i66@mstr_sconn.sconn288_h44441004(chips)!SCONN288_H44441004_PIP-SCONN,HA!!!F179!DQS8P!!!!
S!M_L_DQS_DN<9>!J1A2!8!@baseboard_fab2_lib.baseboard_fab2(sch_1):page85_i66@mstr_sconn.sconn288_h44441004(chips)!SCONN288_H44441004_PIP-SCONN,HA!!!F179!DQS9N!!!!
S!M_L_DQS_DP<9>!J1A2!7!@baseboard_fab2_lib.baseboard_fab2(sch_1):page85_i66@mstr_sconn.sconn288_h44441004(chips)!SCONN288_H44441004_PIP-SCONN,HA!!!F179!DQS9P!!!!
S!GND!J1A2!283!@baseboard_fab2_lib.baseboard_fab2(sch_1):page85_i43@mstr_sconn.sconn288_h44441004(chips)!SCONN288_H44441004_PIP-SCONN,HA!!!F178!VSS(0)!!!!
S!GND!J1A2!261!@baseboard_fab2_lib.baseboard_fab2(sch_1):page85_i43@mstr_sconn.sconn288_h44441004(chips)!SCONN288_H44441004_PIP-SCONN,HA!!!F178!VSS(10)!!!!
S!GND!J1A2!259!@baseboard_fab2_lib.baseboard_fab2(sch_1):page85_i43@mstr_sconn.sconn288_h44441004(chips)!SCONN288_H44441004_PIP-SCONN,HA!!!F178!VSS(11)!!!!
S!GND!J1A2!257!@baseboard_fab2_lib.baseboard_fab2(sch_1):page85_i43@mstr_sconn.sconn288_h44441004(chips)!SCONN288_H44441004_PIP-SCONN,HA!!!F178!VSS(12)!!!!
S!GND!J1A2!254!@baseboard_fab2_lib.baseboard_fab2(sch_1):page85_i43@mstr_sconn.sconn288_h44441004(chips)!SCONN288_H44441004_PIP-SCONN,HA!!!F178!VSS(13)!!!!
S!GND!J1A2!252!@baseboard_fab2_lib.baseboard_fab2(sch_1):page85_i43@mstr_sconn.sconn288_h44441004(chips)!SCONN288_H44441004_PIP-SCONN,HA!!!F178!VSS(14)!!!!
S!GND!J1A2!250!@baseboard_fab2_lib.baseboard_fab2(sch_1):page85_i43@mstr_sconn.sconn288_h44441004(chips)!SCONN288_H44441004_PIP-SCONN,HA!!!F178!VSS(15)!!!!
S!GND!J1A2!248!@baseboard_fab2_lib.baseboard_fab2(sch_1):page85_i43@mstr_sconn.sconn288_h44441004(chips)!SCONN288_H44441004_PIP-SCONN,HA!!!F178!VSS(16)!!!!
S!GND!J1A2!246!@baseboard_fab2_lib.baseboard_fab2(sch_1):page85_i43@mstr_sconn.sconn288_h44441004(chips)!SCONN288_H44441004_PIP-SCONN,HA!!!F178!VSS(17)!!!!
S!GND!J1A2!243!@baseboard_fab2_lib.baseboard_fab2(sch_1):page85_i43@mstr_sconn.sconn288_h44441004(chips)!SCONN288_H44441004_PIP-SCONN,HA!!!F178!VSS(18)!!!!
S!GND!J1A2!241!@baseboard_fab2_lib.baseboard_fab2(sch_1):page85_i43@mstr_sconn.sconn288_h44441004(chips)!SCONN288_H44441004_PIP-SCONN,HA!!!F178!VSS(19)!!!!
S!GND!J1A2!281!@baseboard_fab2_lib.baseboard_fab2(sch_1):page85_i43@mstr_sconn.sconn288_h44441004(chips)!SCONN288_H44441004_PIP-SCONN,HA!!!F178!VSS(1)!!!!
S!GND!J1A2!239!@baseboard_fab2_lib.baseboard_fab2(sch_1):page85_i43@mstr_sconn.sconn288_h44441004(chips)!SCONN288_H44441004_PIP-SCONN,HA!!!F178!VSS(20)!!!!
S!GND!J1A2!202!@baseboard_fab2_lib.baseboard_fab2(sch_1):page85_i43@mstr_sconn.sconn288_h44441004(chips)!SCONN288_H44441004_PIP-SCONN,HA!!!F178!VSS(21)!!!!
S!GND!J1A2!200!@baseboard_fab2_lib.baseboard_fab2(sch_1):page85_i43@mstr_sconn.sconn288_h44441004(chips)!SCONN288_H44441004_PIP-SCONN,HA!!!F178!VSS(22)!!!!
S!GND!J1A2!198!@baseboard_fab2_lib.baseboard_fab2(sch_1):page85_i43@mstr_sconn.sconn288_h44441004(chips)!SCONN288_H44441004_PIP-SCONN,HA!!!F178!VSS(23)!!!!
S!GND!J1A2!195!@baseboard_fab2_lib.baseboard_fab2(sch_1):page85_i43@mstr_sconn.sconn288_h44441004(chips)!SCONN288_H44441004_PIP-SCONN,HA!!!F178!VSS(24)!!!!
S!GND!J1A2!193!@baseboard_fab2_lib.baseboard_fab2(sch_1):page85_i43@mstr_sconn.sconn288_h44441004(chips)!SCONN288_H44441004_PIP-SCONN,HA!!!F178!VSS(25)!!!!
S!GND!J1A2!191!@baseboard_fab2_lib.baseboard_fab2(sch_1):page85_i43@mstr_sconn.sconn288_h44441004(chips)!SCONN288_H44441004_PIP-SCONN,HA!!!F178!VSS(26)!!!!
S!GND!J1A2!189!@baseboard_fab2_lib.baseboard_fab2(sch_1):page85_i43@mstr_sconn.sconn288_h44441004(chips)!SCONN288_H44441004_PIP-SCONN,HA!!!F178!VSS(27)!!!!
S!GND!J1A2!187!@baseboard_fab2_lib.baseboard_fab2(sch_1):page85_i43@mstr_sconn.sconn288_h44441004(chips)!SCONN288_H44441004_PIP-SCONN,HA!!!F178!VSS(28)!!!!
S!GND!J1A2!184!@baseboard_fab2_lib.baseboard_fab2(sch_1):page85_i43@mstr_sconn.sconn288_h44441004(chips)!SCONN288_H44441004_PIP-SCONN,HA!!!F178!VSS(29)!!!!
S!GND!J1A2!279!@baseboard_fab2_lib.baseboard_fab2(sch_1):page85_i43@mstr_sconn.sconn288_h44441004(chips)!SCONN288_H44441004_PIP-SCONN,HA!!!F178!VSS(2)!!!!
S!GND!J1A2!182!@baseboard_fab2_lib.baseboard_fab2(sch_1):page85_i43@mstr_sconn.sconn288_h44441004(chips)!SCONN288_H44441004_PIP-SCONN,HA!!!F178!VSS(30)!!!!
S!GND!J1A2!180!@baseboard_fab2_lib.baseboard_fab2(sch_1):page85_i43@mstr_sconn.sconn288_h44441004(chips)!SCONN288_H44441004_PIP-SCONN,HA!!!F178!VSS(31)!!!!
S!GND!J1A2!178!@baseboard_fab2_lib.baseboard_fab2(sch_1):page85_i43@mstr_sconn.sconn288_h44441004(chips)!SCONN288_H44441004_PIP-SCONN,HA!!!F178!VSS(32)!!!!
S!GND!J1A2!176!@baseboard_fab2_lib.baseboard_fab2(sch_1):page85_i43@mstr_sconn.sconn288_h44441004(chips)!SCONN288_H44441004_PIP-SCONN,HA!!!F178!VSS(33)!!!!
S!GND!J1A2!173!@baseboard_fab2_lib.baseboard_fab2(sch_1):page85_i43@mstr_sconn.sconn288_h44441004(chips)!SCONN288_H44441004_PIP-SCONN,HA!!!F178!VSS(34)!!!!
S!GND!J1A2!171!@baseboard_fab2_lib.baseboard_fab2(sch_1):page85_i43@mstr_sconn.sconn288_h44441004(chips)!SCONN288_H44441004_PIP-SCONN,HA!!!F178!VSS(35)!!!!
S!GND!J1A2!169!@baseboard_fab2_lib.baseboard_fab2(sch_1):page85_i43@mstr_sconn.sconn288_h44441004(chips)!SCONN288_H44441004_PIP-SCONN,HA!!!F178!VSS(36)!!!!
S!GND!J1A2!167!@baseboard_fab2_lib.baseboard_fab2(sch_1):page85_i43@mstr_sconn.sconn288_h44441004(chips)!SCONN288_H44441004_PIP-SCONN,HA!!!F178!VSS(37)!!!!
S!GND!J1A2!165!@baseboard_fab2_lib.baseboard_fab2(sch_1):page85_i43@mstr_sconn.sconn288_h44441004(chips)!SCONN288_H44441004_PIP-SCONN,HA!!!F178!VSS(38)!!!!
S!GND!J1A2!162!@baseboard_fab2_lib.baseboard_fab2(sch_1):page85_i43@mstr_sconn.sconn288_h44441004(chips)!SCONN288_H44441004_PIP-SCONN,HA!!!F178!VSS(39)!!!!
S!GND!J1A2!276!@baseboard_fab2_lib.baseboard_fab2(sch_1):page85_i43@mstr_sconn.sconn288_h44441004(chips)!SCONN288_H44441004_PIP-SCONN,HA!!!F178!VSS(3)!!!!
S!GND!J1A2!160!@baseboard_fab2_lib.baseboard_fab2(sch_1):page85_i43@mstr_sconn.sconn288_h44441004(chips)!SCONN288_H44441004_PIP-SCONN,HA!!!F178!VSS(40)!!!!
S!GND!J1A2!158!@baseboard_fab2_lib.baseboard_fab2(sch_1):page85_i43@mstr_sconn.sconn288_h44441004(chips)!SCONN288_H44441004_PIP-SCONN,HA!!!F178!VSS(41)!!!!
S!GND!J1A2!156!@baseboard_fab2_lib.baseboard_fab2(sch_1):page85_i43@mstr_sconn.sconn288_h44441004(chips)!SCONN288_H44441004_PIP-SCONN,HA!!!F178!VSS(42)!!!!
S!GND!J1A2!154!@baseboard_fab2_lib.baseboard_fab2(sch_1):page85_i43@mstr_sconn.sconn288_h44441004(chips)!SCONN288_H44441004_PIP-SCONN,HA!!!F178!VSS(43)!!!!
S!GND!J1A2!151!@baseboard_fab2_lib.baseboard_fab2(sch_1):page85_i43@mstr_sconn.sconn288_h44441004(chips)!SCONN288_H44441004_PIP-SCONN,HA!!!F178!VSS(44)!!!!
S!GND!J1A2!149!@baseboard_fab2_lib.baseboard_fab2(sch_1):page85_i43@mstr_sconn.sconn288_h44441004(chips)!SCONN288_H44441004_PIP-SCONN,HA!!!F178!VSS(45)!!!!
S!GND!J1A2!147!@baseboard_fab2_lib.baseboard_fab2(sch_1):page85_i43@mstr_sconn.sconn288_h44441004(chips)!SCONN288_H44441004_PIP-SCONN,HA!!!F178!VSS(46)!!!!
S!GND!J1A2!138!@baseboard_fab2_lib.baseboard_fab2(sch_1):page85_i43@mstr_sconn.sconn288_h44441004(chips)!SCONN288_H44441004_PIP-SCONN,HA!!!F178!VSS(47)!!!!
S!GND!J1A2!136!@baseboard_fab2_lib.baseboard_fab2(sch_1):page85_i43@mstr_sconn.sconn288_h44441004(chips)!SCONN288_H44441004_PIP-SCONN,HA!!!F178!VSS(48)!!!!
S!GND!J1A2!134!@baseboard_fab2_lib.baseboard_fab2(sch_1):page85_i43@mstr_sconn.sconn288_h44441004(chips)!SCONN288_H44441004_PIP-SCONN,HA!!!F178!VSS(49)!!!!
S!GND!J1A2!274!@baseboard_fab2_lib.baseboard_fab2(sch_1):page85_i43@mstr_sconn.sconn288_h44441004(chips)!SCONN288_H44441004_PIP-SCONN,HA!!!F178!VSS(4)!!!!
S!GND!J1A2!131!@baseboard_fab2_lib.baseboard_fab2(sch_1):page85_i43@mstr_sconn.sconn288_h44441004(chips)!SCONN288_H44441004_PIP-SCONN,HA!!!F178!VSS(50)!!!!
S!GND!J1A2!129!@baseboard_fab2_lib.baseboard_fab2(sch_1):page85_i43@mstr_sconn.sconn288_h44441004(chips)!SCONN288_H44441004_PIP-SCONN,HA!!!F178!VSS(51)!!!!
S!GND!J1A2!127!@baseboard_fab2_lib.baseboard_fab2(sch_1):page85_i43@mstr_sconn.sconn288_h44441004(chips)!SCONN288_H44441004_PIP-SCONN,HA!!!F178!VSS(52)!!!!
S!GND!J1A2!125!@baseboard_fab2_lib.baseboard_fab2(sch_1):page85_i43@mstr_sconn.sconn288_h44441004(chips)!SCONN288_H44441004_PIP-SCONN,HA!!!F178!VSS(53)!!!!
S!GND!J1A2!123!@baseboard_fab2_lib.baseboard_fab2(sch_1):page85_i43@mstr_sconn.sconn288_h44441004(chips)!SCONN288_H44441004_PIP-SCONN,HA!!!F178!VSS(54)!!!!
S!GND!J1A2!120!@baseboard_fab2_lib.baseboard_fab2(sch_1):page85_i43@mstr_sconn.sconn288_h44441004(chips)!SCONN288_H44441004_PIP-SCONN,HA!!!F178!VSS(55)!!!!
S!GND!J1A2!118!@baseboard_fab2_lib.baseboard_fab2(sch_1):page85_i43@mstr_sconn.sconn288_h44441004(chips)!SCONN288_H44441004_PIP-SCONN,HA!!!F178!VSS(56)!!!!
S!GND!J1A2!116!@baseboard_fab2_lib.baseboard_fab2(sch_1):page85_i43@mstr_sconn.sconn288_h44441004(chips)!SCONN288_H44441004_PIP-SCONN,HA!!!F178!VSS(57)!!!!
S!GND!J1A2!114!@baseboard_fab2_lib.baseboard_fab2(sch_1):page85_i43@mstr_sconn.sconn288_h44441004(chips)!SCONN288_H44441004_PIP-SCONN,HA!!!F178!VSS(58)!!!!
S!GND!J1A2!112!@baseboard_fab2_lib.baseboard_fab2(sch_1):page85_i43@mstr_sconn.sconn288_h44441004(chips)!SCONN288_H44441004_PIP-SCONN,HA!!!F178!VSS(59)!!!!
S!GND!J1A2!272!@baseboard_fab2_lib.baseboard_fab2(sch_1):page85_i43@mstr_sconn.sconn288_h44441004(chips)!SCONN288_H44441004_PIP-SCONN,HA!!!F178!VSS(5)!!!!
S!GND!J1A2!109!@baseboard_fab2_lib.baseboard_fab2(sch_1):page85_i43@mstr_sconn.sconn288_h44441004(chips)!SCONN288_H44441004_PIP-SCONN,HA!!!F178!VSS(60)!!!!
S!GND!J1A2!107!@baseboard_fab2_lib.baseboard_fab2(sch_1):page85_i43@mstr_sconn.sconn288_h44441004(chips)!SCONN288_H44441004_PIP-SCONN,HA!!!F178!VSS(61)!!!!
S!GND!J1A2!105!@baseboard_fab2_lib.baseboard_fab2(sch_1):page85_i43@mstr_sconn.sconn288_h44441004(chips)!SCONN288_H44441004_PIP-SCONN,HA!!!F178!VSS(62)!!!!
S!GND!J1A2!103!@baseboard_fab2_lib.baseboard_fab2(sch_1):page85_i43@mstr_sconn.sconn288_h44441004(chips)!SCONN288_H44441004_PIP-SCONN,HA!!!F178!VSS(63)!!!!
S!GND!J1A2!101!@baseboard_fab2_lib.baseboard_fab2(sch_1):page85_i43@mstr_sconn.sconn288_h44441004(chips)!SCONN288_H44441004_PIP-SCONN,HA!!!F178!VSS(64)!!!!
S!GND!J1A2!98!@baseboard_fab2_lib.baseboard_fab2(sch_1):page85_i43@mstr_sconn.sconn288_h44441004(chips)!SCONN288_H44441004_PIP-SCONN,HA!!!F178!VSS(65)!!!!
S!GND!J1A2!96!@baseboard_fab2_lib.baseboard_fab2(sch_1):page85_i43@mstr_sconn.sconn288_h44441004(chips)!SCONN288_H44441004_PIP-SCONN,HA!!!F178!VSS(66)!!!!
S!GND!J1A2!94!@baseboard_fab2_lib.baseboard_fab2(sch_1):page85_i43@mstr_sconn.sconn288_h44441004(chips)!SCONN288_H44441004_PIP-SCONN,HA!!!F178!VSS(67)!!!!
S!GND!J1A2!57!@baseboard_fab2_lib.baseboard_fab2(sch_1):page85_i43@mstr_sconn.sconn288_h44441004(chips)!SCONN288_H44441004_PIP-SCONN,HA!!!F178!VSS(68)!!!!
S!GND!J1A2!55!@baseboard_fab2_lib.baseboard_fab2(sch_1):page85_i43@mstr_sconn.sconn288_h44441004(chips)!SCONN288_H44441004_PIP-SCONN,HA!!!F178!VSS(69)!!!!
S!GND!J1A2!270!@baseboard_fab2_lib.baseboard_fab2(sch_1):page85_i43@mstr_sconn.sconn288_h44441004(chips)!SCONN288_H44441004_PIP-SCONN,HA!!!F178!VSS(6)!!!!
S!GND!J1A2!53!@baseboard_fab2_lib.baseboard_fab2(sch_1):page85_i43@mstr_sconn.sconn288_h44441004(chips)!SCONN288_H44441004_PIP-SCONN,HA!!!F178!VSS(70)!!!!
S!GND!J1A2!50!@baseboard_fab2_lib.baseboard_fab2(sch_1):page85_i43@mstr_sconn.sconn288_h44441004(chips)!SCONN288_H44441004_PIP-SCONN,HA!!!F178!VSS(71)!!!!
S!GND!J1A2!48!@baseboard_fab2_lib.baseboard_fab2(sch_1):page85_i43@mstr_sconn.sconn288_h44441004(chips)!SCONN288_H44441004_PIP-SCONN,HA!!!F178!VSS(72)!!!!
S!GND!J1A2!46!@baseboard_fab2_lib.baseboard_fab2(sch_1):page85_i43@mstr_sconn.sconn288_h44441004(chips)!SCONN288_H44441004_PIP-SCONN,HA!!!F178!VSS(73)!!!!
S!GND!J1A2!44!@baseboard_fab2_lib.baseboard_fab2(sch_1):page85_i43@mstr_sconn.sconn288_h44441004(chips)!SCONN288_H44441004_PIP-SCONN,HA!!!F178!VSS(74)!!!!
S!GND!J1A2!42!@baseboard_fab2_lib.baseboard_fab2(sch_1):page85_i43@mstr_sconn.sconn288_h44441004(chips)!SCONN288_H44441004_PIP-SCONN,HA!!!F178!VSS(75)!!!!
S!GND!J1A2!39!@baseboard_fab2_lib.baseboard_fab2(sch_1):page85_i43@mstr_sconn.sconn288_h44441004(chips)!SCONN288_H44441004_PIP-SCONN,HA!!!F178!VSS(76)!!!!
S!GND!J1A2!37!@baseboard_fab2_lib.baseboard_fab2(sch_1):page85_i43@mstr_sconn.sconn288_h44441004(chips)!SCONN288_H44441004_PIP-SCONN,HA!!!F178!VSS(77)!!!!
S!GND!J1A2!35!@baseboard_fab2_lib.baseboard_fab2(sch_1):page85_i43@mstr_sconn.sconn288_h44441004(chips)!SCONN288_H44441004_PIP-SCONN,HA!!!F178!VSS(78)!!!!
S!GND!J1A2!33!@baseboard_fab2_lib.baseboard_fab2(sch_1):page85_i43@mstr_sconn.sconn288_h44441004(chips)!SCONN288_H44441004_PIP-SCONN,HA!!!F178!VSS(79)!!!!
S!GND!J1A2!268!@baseboard_fab2_lib.baseboard_fab2(sch_1):page85_i43@mstr_sconn.sconn288_h44441004(chips)!SCONN288_H44441004_PIP-SCONN,HA!!!F178!VSS(7)!!!!
S!GND!J1A2!31!@baseboard_fab2_lib.baseboard_fab2(sch_1):page85_i43@mstr_sconn.sconn288_h44441004(chips)!SCONN288_H44441004_PIP-SCONN,HA!!!F178!VSS(80)!!!!
S!GND!J1A2!28!@baseboard_fab2_lib.baseboard_fab2(sch_1):page85_i43@mstr_sconn.sconn288_h44441004(chips)!SCONN288_H44441004_PIP-SCONN,HA!!!F178!VSS(81)!!!!
S!GND!J1A2!26!@baseboard_fab2_lib.baseboard_fab2(sch_1):page85_i43@mstr_sconn.sconn288_h44441004(chips)!SCONN288_H44441004_PIP-SCONN,HA!!!F178!VSS(82)!!!!
S!GND!J1A2!24!@baseboard_fab2_lib.baseboard_fab2(sch_1):page85_i43@mstr_sconn.sconn288_h44441004(chips)!SCONN288_H44441004_PIP-SCONN,HA!!!F178!VSS(83)!!!!
S!GND!J1A2!22!@baseboard_fab2_lib.baseboard_fab2(sch_1):page85_i43@mstr_sconn.sconn288_h44441004(chips)!SCONN288_H44441004_PIP-SCONN,HA!!!F178!VSS(84)!!!!
S!GND!J1A2!20!@baseboard_fab2_lib.baseboard_fab2(sch_1):page85_i43@mstr_sconn.sconn288_h44441004(chips)!SCONN288_H44441004_PIP-SCONN,HA!!!F178!VSS(85)!!!!
S!GND!J1A2!17!@baseboard_fab2_lib.baseboard_fab2(sch_1):page85_i43@mstr_sconn.sconn288_h44441004(chips)!SCONN288_H44441004_PIP-SCONN,HA!!!F178!VSS(86)!!!!
S!GND!J1A2!15!@baseboard_fab2_lib.baseboard_fab2(sch_1):page85_i43@mstr_sconn.sconn288_h44441004(chips)!SCONN288_H44441004_PIP-SCONN,HA!!!F178!VSS(87)!!!!
S!GND!J1A2!13!@baseboard_fab2_lib.baseboard_fab2(sch_1):page85_i43@mstr_sconn.sconn288_h44441004(chips)!SCONN288_H44441004_PIP-SCONN,HA!!!F178!VSS(88)!!!!
S!GND!J1A2!11!@baseboard_fab2_lib.baseboard_fab2(sch_1):page85_i43@mstr_sconn.sconn288_h44441004(chips)!SCONN288_H44441004_PIP-SCONN,HA!!!F178!VSS(89)!!!!
S!GND!J1A2!265!@baseboard_fab2_lib.baseboard_fab2(sch_1):page85_i43@mstr_sconn.sconn288_h44441004(chips)!SCONN288_H44441004_PIP-SCONN,HA!!!F178!VSS(8)!!!!
S!GND!J1A2!9!@baseboard_fab2_lib.baseboard_fab2(sch_1):page85_i43@mstr_sconn.sconn288_h44441004(chips)!SCONN288_H44441004_PIP-SCONN,HA!!!F178!VSS(90)!!!!
S!GND!J1A2!6!@baseboard_fab2_lib.baseboard_fab2(sch_1):page85_i43@mstr_sconn.sconn288_h44441004(chips)!SCONN288_H44441004_PIP-SCONN,HA!!!F178!VSS(91)!!!!
S!GND!J1A2!4!@baseboard_fab2_lib.baseboard_fab2(sch_1):page85_i43@mstr_sconn.sconn288_h44441004(chips)!SCONN288_H44441004_PIP-SCONN,HA!!!F178!VSS(92)!!!!
S!GND!J1A2!2!@baseboard_fab2_lib.baseboard_fab2(sch_1):page85_i43@mstr_sconn.sconn288_h44441004(chips)!SCONN288_H44441004_PIP-SCONN,HA!!!F178!VSS(93)!!!!
S!GND!J1A2!263!@baseboard_fab2_lib.baseboard_fab2(sch_1):page85_i43@mstr_sconn.sconn288_h44441004(chips)!SCONN288_H44441004_PIP-SCONN,HA!!!F178!VSS(9)!!!!
S!P12V_NVDIMM_KLM!J1A2!145!@baseboard_fab2_lib.baseboard_fab2(sch_1):page85_i172@mstr_sconn.sconn288_h44441004(chips)!SCONN288_H44441004_PIP-SCONN,HA!!!F177!\12v\(0)!!!!
S!P12V_NVDIMM_KLM!J1A2!1!@baseboard_fab2_lib.baseboard_fab2(sch_1):page85_i172@mstr_sconn.sconn288_h44441004(chips)!SCONN288_H44441004_PIP-SCONN,HA!!!F177!\12v\(1)!!!!
S!PVDDQ_KLM!J1A2!236!@baseboard_fab2_lib.baseboard_fab2(sch_1):page85_i172@mstr_sconn.sconn288_h44441004(chips)!SCONN288_H44441004_PIP-SCONN,HA!!!F177!VDD(0)!!!!
S!PVDDQ_KLM!J1A2!209!@baseboard_fab2_lib.baseboard_fab2(sch_1):page85_i172@mstr_sconn.sconn288_h44441004(chips)!SCONN288_H44441004_PIP-SCONN,HA!!!F177!VDD(10)!!!!
S!PVDDQ_KLM!J1A2!206!@baseboard_fab2_lib.baseboard_fab2(sch_1):page85_i172@mstr_sconn.sconn288_h44441004(chips)!SCONN288_H44441004_PIP-SCONN,HA!!!F177!VDD(11)!!!!
S!PVDDQ_KLM!J1A2!204!@baseboard_fab2_lib.baseboard_fab2(sch_1):page85_i172@mstr_sconn.sconn288_h44441004(chips)!SCONN288_H44441004_PIP-SCONN,HA!!!F177!VDD(12)!!!!
S!PVDDQ_KLM!J1A2!92!@baseboard_fab2_lib.baseboard_fab2(sch_1):page85_i172@mstr_sconn.sconn288_h44441004(chips)!SCONN288_H44441004_PIP-SCONN,HA!!!F177!VDD(13)!!!!
S!PVDDQ_KLM!J1A2!90!@baseboard_fab2_lib.baseboard_fab2(sch_1):page85_i172@mstr_sconn.sconn288_h44441004(chips)!SCONN288_H44441004_PIP-SCONN,HA!!!F177!VDD(14)!!!!
S!PVDDQ_KLM!J1A2!88!@baseboard_fab2_lib.baseboard_fab2(sch_1):page85_i172@mstr_sconn.sconn288_h44441004(chips)!SCONN288_H44441004_PIP-SCONN,HA!!!F177!VDD(15)!!!!
S!PVDDQ_KLM!J1A2!85!@baseboard_fab2_lib.baseboard_fab2(sch_1):page85_i172@mstr_sconn.sconn288_h44441004(chips)!SCONN288_H44441004_PIP-SCONN,HA!!!F177!VDD(16)!!!!
S!PVDDQ_KLM!J1A2!83!@baseboard_fab2_lib.baseboard_fab2(sch_1):page85_i172@mstr_sconn.sconn288_h44441004(chips)!SCONN288_H44441004_PIP-SCONN,HA!!!F177!VDD(17)!!!!
S!PVDDQ_KLM!J1A2!80!@baseboard_fab2_lib.baseboard_fab2(sch_1):page85_i172@mstr_sconn.sconn288_h44441004(chips)!SCONN288_H44441004_PIP-SCONN,HA!!!F177!VDD(18)!!!!
S!PVDDQ_KLM!J1A2!76!@baseboard_fab2_lib.baseboard_fab2(sch_1):page85_i172@mstr_sconn.sconn288_h44441004(chips)!SCONN288_H44441004_PIP-SCONN,HA!!!F177!VDD(19)!!!!
S!PVDDQ_KLM!J1A2!233!@baseboard_fab2_lib.baseboard_fab2(sch_1):page85_i172@mstr_sconn.sconn288_h44441004(chips)!SCONN288_H44441004_PIP-SCONN,HA!!!F177!VDD(1)!!!!
S!PVDDQ_KLM!J1A2!73!@baseboard_fab2_lib.baseboard_fab2(sch_1):page85_i172@mstr_sconn.sconn288_h44441004(chips)!SCONN288_H44441004_PIP-SCONN,HA!!!F177!VDD(20)!!!!
S!PVDDQ_KLM!J1A2!70!@baseboard_fab2_lib.baseboard_fab2(sch_1):page85_i172@mstr_sconn.sconn288_h44441004(chips)!SCONN288_H44441004_PIP-SCONN,HA!!!F177!VDD(21)!!!!
S!PVDDQ_KLM!J1A2!67!@baseboard_fab2_lib.baseboard_fab2(sch_1):page85_i172@mstr_sconn.sconn288_h44441004(chips)!SCONN288_H44441004_PIP-SCONN,HA!!!F177!VDD(22)!!!!
S!PVDDQ_KLM!J1A2!64!@baseboard_fab2_lib.baseboard_fab2(sch_1):page85_i172@mstr_sconn.sconn288_h44441004(chips)!SCONN288_H44441004_PIP-SCONN,HA!!!F177!VDD(23)!!!!
S!PVDDQ_KLM!J1A2!61!@baseboard_fab2_lib.baseboard_fab2(sch_1):page85_i172@mstr_sconn.sconn288_h44441004(chips)!SCONN288_H44441004_PIP-SCONN,HA!!!F177!VDD(24)!!!!
S!PVDDQ_KLM!J1A2!59!@baseboard_fab2_lib.baseboard_fab2(sch_1):page85_i172@mstr_sconn.sconn288_h44441004(chips)!SCONN288_H44441004_PIP-SCONN,HA!!!F177!VDD(25)!!!!
S!PVDDQ_KLM!J1A2!231!@baseboard_fab2_lib.baseboard_fab2(sch_1):page85_i172@mstr_sconn.sconn288_h44441004(chips)!SCONN288_H44441004_PIP-SCONN,HA!!!F177!VDD(2)!!!!
S!PVDDQ_KLM!J1A2!229!@baseboard_fab2_lib.baseboard_fab2(sch_1):page85_i172@mstr_sconn.sconn288_h44441004(chips)!SCONN288_H44441004_PIP-SCONN,HA!!!F177!VDD(3)!!!!
S!PVDDQ_KLM!J1A2!226!@baseboard_fab2_lib.baseboard_fab2(sch_1):page85_i172@mstr_sconn.sconn288_h44441004(chips)!SCONN288_H44441004_PIP-SCONN,HA!!!F177!VDD(4)!!!!
S!PVDDQ_KLM!J1A2!223!@baseboard_fab2_lib.baseboard_fab2(sch_1):page85_i172@mstr_sconn.sconn288_h44441004(chips)!SCONN288_H44441004_PIP-SCONN,HA!!!F177!VDD(5)!!!!
S!PVDDQ_KLM!J1A2!220!@baseboard_fab2_lib.baseboard_fab2(sch_1):page85_i172@mstr_sconn.sconn288_h44441004(chips)!SCONN288_H44441004_PIP-SCONN,HA!!!F177!VDD(6)!!!!
S!PVDDQ_KLM!J1A2!217!@baseboard_fab2_lib.baseboard_fab2(sch_1):page85_i172@mstr_sconn.sconn288_h44441004(chips)!SCONN288_H44441004_PIP-SCONN,HA!!!F177!VDD(7)!!!!
S!PVDDQ_KLM!J1A2!215!@baseboard_fab2_lib.baseboard_fab2(sch_1):page85_i172@mstr_sconn.sconn288_h44441004(chips)!SCONN288_H44441004_PIP-SCONN,HA!!!F177!VDD(8)!!!!
S!PVDDQ_KLM!J1A2!212!@baseboard_fab2_lib.baseboard_fab2(sch_1):page85_i172@mstr_sconn.sconn288_h44441004(chips)!SCONN288_H44441004_PIP-SCONN,HA!!!F177!VDD(9)!!!!
S!PVPP_KLM!J1A2!287!@baseboard_fab2_lib.baseboard_fab2(sch_1):page85_i172@mstr_sconn.sconn288_h44441004(chips)!SCONN288_H44441004_PIP-SCONN,HA!!!F177!VPP(0)!!!!
S!PVPP_KLM!J1A2!286!@baseboard_fab2_lib.baseboard_fab2(sch_1):page85_i172@mstr_sconn.sconn288_h44441004(chips)!SCONN288_H44441004_PIP-SCONN,HA!!!F177!VPP(1)!!!!
S!PVPP_KLM!J1A2!288!@baseboard_fab2_lib.baseboard_fab2(sch_1):page85_i172@mstr_sconn.sconn288_h44441004(chips)!SCONN288_H44441004_PIP-SCONN,HA!!!F177!VPP(2)!!!!
S!PVPP_KLM!J1A2!143!@baseboard_fab2_lib.baseboard_fab2(sch_1):page85_i172@mstr_sconn.sconn288_h44441004(chips)!SCONN288_H44441004_PIP-SCONN,HA!!!F177!VPP(3)!!!!
S!PVPP_KLM!J1A2!142!@baseboard_fab2_lib.baseboard_fab2(sch_1):page85_i172@mstr_sconn.sconn288_h44441004(chips)!SCONN288_H44441004_PIP-SCONN,HA!!!F177!VPP(4)!!!!
S!PVTT_KLM!J1A2!221!@baseboard_fab2_lib.baseboard_fab2(sch_1):page85_i172@mstr_sconn.sconn288_h44441004(chips)!SCONN288_H44441004_PIP-SCONN,HA!!!F177!VTT(0)!!!!
S!PVTT_KLM!J1A2!77!@baseboard_fab2_lib.baseboard_fab2(sch_1):page85_i172@mstr_sconn.sconn288_h44441004(chips)!SCONN288_H44441004_PIP-SCONN,HA!!!F177!VTT(1)!!!!
S!M_M_MA<0>!J1A1!79!@baseboard_fab2_lib.baseboard_fab2(sch_1):page87_i186@mstr_sconn.sconn288_h44441004(chips)!SCONN288_H44441004_PIP-SCONN,HA!!!F184!A0!!!!
S!M_M_MA<1>!J1A1!72!@baseboard_fab2_lib.baseboard_fab2(sch_1):page87_i186@mstr_sconn.sconn288_h44441004(chips)!SCONN288_H44441004_PIP-SCONN,HA!!!F184!A1!!!!
S!M_M_MA<10>!J1A1!225!@baseboard_fab2_lib.baseboard_fab2(sch_1):page87_i186@mstr_sconn.sconn288_h44441004(chips)!SCONN288_H44441004_PIP-SCONN,HA!!!F184!A10!!!!
S!M_M_MA<11>!J1A1!210!@baseboard_fab2_lib.baseboard_fab2(sch_1):page87_i186@mstr_sconn.sconn288_h44441004(chips)!SCONN288_H44441004_PIP-SCONN,HA!!!F184!A11!!!!
S!M_M_MA<12>!J1A1!65!@baseboard_fab2_lib.baseboard_fab2(sch_1):page87_i186@mstr_sconn.sconn288_h44441004(chips)!SCONN288_H44441004_PIP-SCONN,HA!!!F184!A12!!!!
S!M_M_MA<13>!J1A1!232!@baseboard_fab2_lib.baseboard_fab2(sch_1):page87_i186@mstr_sconn.sconn288_h44441004(chips)!SCONN288_H44441004_PIP-SCONN,HA!!!F184!A13!!!!
S!M_M_MA<14>!J1A1!228!@baseboard_fab2_lib.baseboard_fab2(sch_1):page87_i186@mstr_sconn.sconn288_h44441004(chips)!SCONN288_H44441004_PIP-SCONN,HA!!!F184!A14_WE_N!!!!
S!M_M_MA<15>!J1A1!86!@baseboard_fab2_lib.baseboard_fab2(sch_1):page87_i186@mstr_sconn.sconn288_h44441004(chips)!SCONN288_H44441004_PIP-SCONN,HA!!!F184!A15_CAS_N!!!!
S!M_M_MA<16>!J1A1!82!@baseboard_fab2_lib.baseboard_fab2(sch_1):page87_i186@mstr_sconn.sconn288_h44441004(chips)!SCONN288_H44441004_PIP-SCONN,HA!!!F184!A16_RAS_N!!!!
S!M_M_MA<17>!J1A1!234!@baseboard_fab2_lib.baseboard_fab2(sch_1):page87_i186@mstr_sconn.sconn288_h44441004(chips)!SCONN288_H44441004_PIP-SCONN,HA!!!F184!A17!!!!
S!M_M_MA<2>!J1A1!216!@baseboard_fab2_lib.baseboard_fab2(sch_1):page87_i186@mstr_sconn.sconn288_h44441004(chips)!SCONN288_H44441004_PIP-SCONN,HA!!!F184!A2!!!!
S!M_M_MA<3>!J1A1!71!@baseboard_fab2_lib.baseboard_fab2(sch_1):page87_i186@mstr_sconn.sconn288_h44441004(chips)!SCONN288_H44441004_PIP-SCONN,HA!!!F184!A3!!!!
S!M_M_MA<4>!J1A1!214!@baseboard_fab2_lib.baseboard_fab2(sch_1):page87_i186@mstr_sconn.sconn288_h44441004(chips)!SCONN288_H44441004_PIP-SCONN,HA!!!F184!A4!!!!
S!M_M_MA<5>!J1A1!213!@baseboard_fab2_lib.baseboard_fab2(sch_1):page87_i186@mstr_sconn.sconn288_h44441004(chips)!SCONN288_H44441004_PIP-SCONN,HA!!!F184!A5!!!!
S!M_M_MA<6>!J1A1!69!@baseboard_fab2_lib.baseboard_fab2(sch_1):page87_i186@mstr_sconn.sconn288_h44441004(chips)!SCONN288_H44441004_PIP-SCONN,HA!!!F184!A6!!!!
S!M_M_MA<7>!J1A1!211!@baseboard_fab2_lib.baseboard_fab2(sch_1):page87_i186@mstr_sconn.sconn288_h44441004(chips)!SCONN288_H44441004_PIP-SCONN,HA!!!F184!A7!!!!
S!M_M_MA<8>!J1A1!68!@baseboard_fab2_lib.baseboard_fab2(sch_1):page87_i186@mstr_sconn.sconn288_h44441004(chips)!SCONN288_H44441004_PIP-SCONN,HA!!!F184!A8!!!!
S!M_M_MA<9>!J1A1!66!@baseboard_fab2_lib.baseboard_fab2(sch_1):page87_i186@mstr_sconn.sconn288_h44441004(chips)!SCONN288_H44441004_PIP-SCONN,HA!!!F184!A9!!!!
S!M_M_ACT_N!J1A1!62!@baseboard_fab2_lib.baseboard_fab2(sch_1):page87_i186@mstr_sconn.sconn288_h44441004(chips)!SCONN288_H44441004_PIP-SCONN,HA!!!F184!ACT_N!!!!
S!M_M_ALERT_N!J1A1!208!@baseboard_fab2_lib.baseboard_fab2(sch_1):page87_i186@mstr_sconn.sconn288_h44441004(chips)!SCONN288_H44441004_PIP-SCONN,HA!!!F184!ALERT_N!!!!
S!M_M_BA<0>!J1A1!81!@baseboard_fab2_lib.baseboard_fab2(sch_1):page87_i186@mstr_sconn.sconn288_h44441004(chips)!SCONN288_H44441004_PIP-SCONN,HA!!!F184!BA(0)!!!!
S!M_M_BA<1>!J1A1!224!@baseboard_fab2_lib.baseboard_fab2(sch_1):page87_i186@mstr_sconn.sconn288_h44441004(chips)!SCONN288_H44441004_PIP-SCONN,HA!!!F184!BA(1)!!!!
S!M_M_BG<0>!J1A1!63!@baseboard_fab2_lib.baseboard_fab2(sch_1):page87_i186@mstr_sconn.sconn288_h44441004(chips)!SCONN288_H44441004_PIP-SCONN,HA!!!F184!BG(0)!!!!
S!M_M_BG<1>!J1A1!207!@baseboard_fab2_lib.baseboard_fab2(sch_1):page87_i186@mstr_sconn.sconn288_h44441004(chips)!SCONN288_H44441004_PIP-SCONN,HA!!!F184!BG(1)!!!!
S!M_M_C<2>!J1A1!235!@baseboard_fab2_lib.baseboard_fab2(sch_1):page87_i186@mstr_sconn.sconn288_h44441004(chips)!SCONN288_H44441004_PIP-SCONN,HA!!!F184!C(2)!!!!
S!M_M_ECC<1>!J1A1!49!@baseboard_fab2_lib.baseboard_fab2(sch_1):page87_i186@mstr_sconn.sconn288_h44441004(chips)!SCONN288_H44441004_PIP-SCONN,HA!!!F184!CB(0)!!!!
S!M_M_ECC<0>!J1A1!194!@baseboard_fab2_lib.baseboard_fab2(sch_1):page87_i186@mstr_sconn.sconn288_h44441004(chips)!SCONN288_H44441004_PIP-SCONN,HA!!!F184!CB(1)!!!!
S!M_M_ECC<3>!J1A1!56!@baseboard_fab2_lib.baseboard_fab2(sch_1):page87_i186@mstr_sconn.sconn288_h44441004(chips)!SCONN288_H44441004_PIP-SCONN,HA!!!F184!CB(2)!!!!
S!M_M_ECC<2>!J1A1!201!@baseboard_fab2_lib.baseboard_fab2(sch_1):page87_i186@mstr_sconn.sconn288_h44441004(chips)!SCONN288_H44441004_PIP-SCONN,HA!!!F184!CB(3)!!!!
S!M_M_ECC<5>!J1A1!47!@baseboard_fab2_lib.baseboard_fab2(sch_1):page87_i186@mstr_sconn.sconn288_h44441004(chips)!SCONN288_H44441004_PIP-SCONN,HA!!!F184!CB(4)!!!!
S!M_M_ECC<4>!J1A1!192!@baseboard_fab2_lib.baseboard_fab2(sch_1):page87_i186@mstr_sconn.sconn288_h44441004(chips)!SCONN288_H44441004_PIP-SCONN,HA!!!F184!CB(5)!!!!
S!M_M_ECC<7>!J1A1!54!@baseboard_fab2_lib.baseboard_fab2(sch_1):page87_i186@mstr_sconn.sconn288_h44441004(chips)!SCONN288_H44441004_PIP-SCONN,HA!!!F184!CB(6)!!!!
S!M_M_ECC<6>!J1A1!199!@baseboard_fab2_lib.baseboard_fab2(sch_1):page87_i186@mstr_sconn.sconn288_h44441004(chips)!SCONN288_H44441004_PIP-SCONN,HA!!!F184!CB(7)!!!!
S!M_M_CLK_DN<0>!J1A1!75!@baseboard_fab2_lib.baseboard_fab2(sch_1):page87_i186@mstr_sconn.sconn288_h44441004(chips)!SCONN288_H44441004_PIP-SCONN,HA!!!F184!CK0N!!!!
S!M_M_CLK_DP<0>!J1A1!74!@baseboard_fab2_lib.baseboard_fab2(sch_1):page87_i186@mstr_sconn.sconn288_h44441004(chips)!SCONN288_H44441004_PIP-SCONN,HA!!!F184!CK0P!!!!
S!M_M_CLK_DN<1>!J1A1!219!@baseboard_fab2_lib.baseboard_fab2(sch_1):page87_i186@mstr_sconn.sconn288_h44441004(chips)!SCONN288_H44441004_PIP-SCONN,HA!!!F184!CK1N!!!!
S!M_M_CLK_DP<1>!J1A1!218!@baseboard_fab2_lib.baseboard_fab2(sch_1):page87_i186@mstr_sconn.sconn288_h44441004(chips)!SCONN288_H44441004_PIP-SCONN,HA!!!F184!CK1P!!!!
S!M_M_CKE<0>!J1A1!60!@baseboard_fab2_lib.baseboard_fab2(sch_1):page87_i186@mstr_sconn.sconn288_h44441004(chips)!SCONN288_H44441004_PIP-SCONN,HA!!!F184!CKE(0)!!!!
S!M_M_CKE<1>!J1A1!203!@baseboard_fab2_lib.baseboard_fab2(sch_1):page87_i186@mstr_sconn.sconn288_h44441004(chips)!SCONN288_H44441004_PIP-SCONN,HA!!!F184!CKE(1)!!!!
S!M_M_DQ<1>!J1A1!5!@baseboard_fab2_lib.baseboard_fab2(sch_1):page87_i186@mstr_sconn.sconn288_h44441004(chips)!SCONN288_H44441004_PIP-SCONN,HA!!!F184!DQ(0)!!!!
S!M_M_DQ<11>!J1A1!23!@baseboard_fab2_lib.baseboard_fab2(sch_1):page87_i186@mstr_sconn.sconn288_h44441004(chips)!SCONN288_H44441004_PIP-SCONN,HA!!!F184!DQ(10)!!!!
S!M_M_DQ<10>!J1A1!168!@baseboard_fab2_lib.baseboard_fab2(sch_1):page87_i186@mstr_sconn.sconn288_h44441004(chips)!SCONN288_H44441004_PIP-SCONN,HA!!!F184!DQ(11)!!!!
S!M_M_DQ<13>!J1A1!14!@baseboard_fab2_lib.baseboard_fab2(sch_1):page87_i186@mstr_sconn.sconn288_h44441004(chips)!SCONN288_H44441004_PIP-SCONN,HA!!!F184!DQ(12)!!!!
S!M_M_DQ<12>!J1A1!159!@baseboard_fab2_lib.baseboard_fab2(sch_1):page87_i186@mstr_sconn.sconn288_h44441004(chips)!SCONN288_H44441004_PIP-SCONN,HA!!!F184!DQ(13)!!!!
S!M_M_DQ<15>!J1A1!21!@baseboard_fab2_lib.baseboard_fab2(sch_1):page87_i186@mstr_sconn.sconn288_h44441004(chips)!SCONN288_H44441004_PIP-SCONN,HA!!!F184!DQ(14)!!!!
S!M_M_DQ<14>!J1A1!166!@baseboard_fab2_lib.baseboard_fab2(sch_1):page87_i186@mstr_sconn.sconn288_h44441004(chips)!SCONN288_H44441004_PIP-SCONN,HA!!!F184!DQ(15)!!!!
S!M_M_DQ<17>!J1A1!27!@baseboard_fab2_lib.baseboard_fab2(sch_1):page87_i186@mstr_sconn.sconn288_h44441004(chips)!SCONN288_H44441004_PIP-SCONN,HA!!!F184!DQ(16)!!!!
S!M_M_DQ<16>!J1A1!172!@baseboard_fab2_lib.baseboard_fab2(sch_1):page87_i186@mstr_sconn.sconn288_h44441004(chips)!SCONN288_H44441004_PIP-SCONN,HA!!!F184!DQ(17)!!!!
S!M_M_DQ<19>!J1A1!34!@baseboard_fab2_lib.baseboard_fab2(sch_1):page87_i186@mstr_sconn.sconn288_h44441004(chips)!SCONN288_H44441004_PIP-SCONN,HA!!!F184!DQ(18)!!!!
S!M_M_DQ<18>!J1A1!179!@baseboard_fab2_lib.baseboard_fab2(sch_1):page87_i186@mstr_sconn.sconn288_h44441004(chips)!SCONN288_H44441004_PIP-SCONN,HA!!!F184!DQ(19)!!!!
S!M_M_DQ<0>!J1A1!150!@baseboard_fab2_lib.baseboard_fab2(sch_1):page87_i186@mstr_sconn.sconn288_h44441004(chips)!SCONN288_H44441004_PIP-SCONN,HA!!!F184!DQ(1)!!!!
S!M_M_DQ<21>!J1A1!25!@baseboard_fab2_lib.baseboard_fab2(sch_1):page87_i186@mstr_sconn.sconn288_h44441004(chips)!SCONN288_H44441004_PIP-SCONN,HA!!!F184!DQ(20)!!!!
S!M_M_DQ<20>!J1A1!170!@baseboard_fab2_lib.baseboard_fab2(sch_1):page87_i186@mstr_sconn.sconn288_h44441004(chips)!SCONN288_H44441004_PIP-SCONN,HA!!!F184!DQ(21)!!!!
S!M_M_DQ<23>!J1A1!32!@baseboard_fab2_lib.baseboard_fab2(sch_1):page87_i186@mstr_sconn.sconn288_h44441004(chips)!SCONN288_H44441004_PIP-SCONN,HA!!!F184!DQ(22)!!!!
S!M_M_DQ<22>!J1A1!177!@baseboard_fab2_lib.baseboard_fab2(sch_1):page87_i186@mstr_sconn.sconn288_h44441004(chips)!SCONN288_H44441004_PIP-SCONN,HA!!!F184!DQ(23)!!!!
S!M_M_DQ<25>!J1A1!38!@baseboard_fab2_lib.baseboard_fab2(sch_1):page87_i186@mstr_sconn.sconn288_h44441004(chips)!SCONN288_H44441004_PIP-SCONN,HA!!!F184!DQ(24)!!!!
S!M_M_DQ<24>!J1A1!183!@baseboard_fab2_lib.baseboard_fab2(sch_1):page87_i186@mstr_sconn.sconn288_h44441004(chips)!SCONN288_H44441004_PIP-SCONN,HA!!!F184!DQ(25)!!!!
S!M_M_DQ<27>!J1A1!45!@baseboard_fab2_lib.baseboard_fab2(sch_1):page87_i186@mstr_sconn.sconn288_h44441004(chips)!SCONN288_H44441004_PIP-SCONN,HA!!!F184!DQ(26)!!!!
S!M_M_DQ<26>!J1A1!190!@baseboard_fab2_lib.baseboard_fab2(sch_1):page87_i186@mstr_sconn.sconn288_h44441004(chips)!SCONN288_H44441004_PIP-SCONN,HA!!!F184!DQ(27)!!!!
S!M_M_DQ<29>!J1A1!36!@baseboard_fab2_lib.baseboard_fab2(sch_1):page87_i186@mstr_sconn.sconn288_h44441004(chips)!SCONN288_H44441004_PIP-SCONN,HA!!!F184!DQ(28)!!!!
S!M_M_DQ<28>!J1A1!181!@baseboard_fab2_lib.baseboard_fab2(sch_1):page87_i186@mstr_sconn.sconn288_h44441004(chips)!SCONN288_H44441004_PIP-SCONN,HA!!!F184!DQ(29)!!!!
S!M_M_DQ<3>!J1A1!12!@baseboard_fab2_lib.baseboard_fab2(sch_1):page87_i186@mstr_sconn.sconn288_h44441004(chips)!SCONN288_H44441004_PIP-SCONN,HA!!!F184!DQ(2)!!!!
S!M_M_DQ<31>!J1A1!43!@baseboard_fab2_lib.baseboard_fab2(sch_1):page87_i186@mstr_sconn.sconn288_h44441004(chips)!SCONN288_H44441004_PIP-SCONN,HA!!!F184!DQ(30)!!!!
S!M_M_DQ<30>!J1A1!188!@baseboard_fab2_lib.baseboard_fab2(sch_1):page87_i186@mstr_sconn.sconn288_h44441004(chips)!SCONN288_H44441004_PIP-SCONN,HA!!!F184!DQ(31)!!!!
S!M_M_DQ<33>!J1A1!97!@baseboard_fab2_lib.baseboard_fab2(sch_1):page87_i186@mstr_sconn.sconn288_h44441004(chips)!SCONN288_H44441004_PIP-SCONN,HA!!!F184!DQ(32)!!!!
S!M_M_DQ<32>!J1A1!242!@baseboard_fab2_lib.baseboard_fab2(sch_1):page87_i186@mstr_sconn.sconn288_h44441004(chips)!SCONN288_H44441004_PIP-SCONN,HA!!!F184!DQ(33)!!!!
S!M_M_DQ<35>!J1A1!104!@baseboard_fab2_lib.baseboard_fab2(sch_1):page87_i186@mstr_sconn.sconn288_h44441004(chips)!SCONN288_H44441004_PIP-SCONN,HA!!!F184!DQ(34)!!!!
S!M_M_DQ<34>!J1A1!249!@baseboard_fab2_lib.baseboard_fab2(sch_1):page87_i186@mstr_sconn.sconn288_h44441004(chips)!SCONN288_H44441004_PIP-SCONN,HA!!!F184!DQ(35)!!!!
S!M_M_DQ<37>!J1A1!95!@baseboard_fab2_lib.baseboard_fab2(sch_1):page87_i186@mstr_sconn.sconn288_h44441004(chips)!SCONN288_H44441004_PIP-SCONN,HA!!!F184!DQ(36)!!!!
S!M_M_DQ<36>!J1A1!240!@baseboard_fab2_lib.baseboard_fab2(sch_1):page87_i186@mstr_sconn.sconn288_h44441004(chips)!SCONN288_H44441004_PIP-SCONN,HA!!!F184!DQ(37)!!!!
S!M_M_DQ<39>!J1A1!102!@baseboard_fab2_lib.baseboard_fab2(sch_1):page87_i186@mstr_sconn.sconn288_h44441004(chips)!SCONN288_H44441004_PIP-SCONN,HA!!!F184!DQ(38)!!!!
S!M_M_DQ<38>!J1A1!247!@baseboard_fab2_lib.baseboard_fab2(sch_1):page87_i186@mstr_sconn.sconn288_h44441004(chips)!SCONN288_H44441004_PIP-SCONN,HA!!!F184!DQ(39)!!!!
S!M_M_DQ<2>!J1A1!157!@baseboard_fab2_lib.baseboard_fab2(sch_1):page87_i186@mstr_sconn.sconn288_h44441004(chips)!SCONN288_H44441004_PIP-SCONN,HA!!!F184!DQ(3)!!!!
S!M_M_DQ<41>!J1A1!108!@baseboard_fab2_lib.baseboard_fab2(sch_1):page87_i186@mstr_sconn.sconn288_h44441004(chips)!SCONN288_H44441004_PIP-SCONN,HA!!!F184!DQ(40)!!!!
S!M_M_DQ<40>!J1A1!253!@baseboard_fab2_lib.baseboard_fab2(sch_1):page87_i186@mstr_sconn.sconn288_h44441004(chips)!SCONN288_H44441004_PIP-SCONN,HA!!!F184!DQ(41)!!!!
S!M_M_DQ<43>!J1A1!115!@baseboard_fab2_lib.baseboard_fab2(sch_1):page87_i186@mstr_sconn.sconn288_h44441004(chips)!SCONN288_H44441004_PIP-SCONN,HA!!!F184!DQ(42)!!!!
S!M_M_DQ<42>!J1A1!260!@baseboard_fab2_lib.baseboard_fab2(sch_1):page87_i186@mstr_sconn.sconn288_h44441004(chips)!SCONN288_H44441004_PIP-SCONN,HA!!!F184!DQ(43)!!!!
S!M_M_DQ<45>!J1A1!106!@baseboard_fab2_lib.baseboard_fab2(sch_1):page87_i186@mstr_sconn.sconn288_h44441004(chips)!SCONN288_H44441004_PIP-SCONN,HA!!!F184!DQ(44)!!!!
S!M_M_DQ<44>!J1A1!251!@baseboard_fab2_lib.baseboard_fab2(sch_1):page87_i186@mstr_sconn.sconn288_h44441004(chips)!SCONN288_H44441004_PIP-SCONN,HA!!!F184!DQ(45)!!!!
S!M_M_DQ<47>!J1A1!113!@baseboard_fab2_lib.baseboard_fab2(sch_1):page87_i186@mstr_sconn.sconn288_h44441004(chips)!SCONN288_H44441004_PIP-SCONN,HA!!!F184!DQ(46)!!!!
S!M_M_DQ<46>!J1A1!258!@baseboard_fab2_lib.baseboard_fab2(sch_1):page87_i186@mstr_sconn.sconn288_h44441004(chips)!SCONN288_H44441004_PIP-SCONN,HA!!!F184!DQ(47)!!!!
S!M_M_DQ<49>!J1A1!119!@baseboard_fab2_lib.baseboard_fab2(sch_1):page87_i186@mstr_sconn.sconn288_h44441004(chips)!SCONN288_H44441004_PIP-SCONN,HA!!!F184!DQ(48)!!!!
S!M_M_DQ<48>!J1A1!264!@baseboard_fab2_lib.baseboard_fab2(sch_1):page87_i186@mstr_sconn.sconn288_h44441004(chips)!SCONN288_H44441004_PIP-SCONN,HA!!!F184!DQ(49)!!!!
S!M_M_DQ<5>!J1A1!3!@baseboard_fab2_lib.baseboard_fab2(sch_1):page87_i186@mstr_sconn.sconn288_h44441004(chips)!SCONN288_H44441004_PIP-SCONN,HA!!!F184!DQ(4)!!!!
S!M_M_DQ<51>!J1A1!126!@baseboard_fab2_lib.baseboard_fab2(sch_1):page87_i186@mstr_sconn.sconn288_h44441004(chips)!SCONN288_H44441004_PIP-SCONN,HA!!!F184!DQ(50)!!!!
S!M_M_DQ<50>!J1A1!271!@baseboard_fab2_lib.baseboard_fab2(sch_1):page87_i186@mstr_sconn.sconn288_h44441004(chips)!SCONN288_H44441004_PIP-SCONN,HA!!!F184!DQ(51)!!!!
S!M_M_DQ<53>!J1A1!117!@baseboard_fab2_lib.baseboard_fab2(sch_1):page87_i186@mstr_sconn.sconn288_h44441004(chips)!SCONN288_H44441004_PIP-SCONN,HA!!!F184!DQ(52)!!!!
S!M_M_DQ<52>!J1A1!262!@baseboard_fab2_lib.baseboard_fab2(sch_1):page87_i186@mstr_sconn.sconn288_h44441004(chips)!SCONN288_H44441004_PIP-SCONN,HA!!!F184!DQ(53)!!!!
S!M_M_DQ<55>!J1A1!124!@baseboard_fab2_lib.baseboard_fab2(sch_1):page87_i186@mstr_sconn.sconn288_h44441004(chips)!SCONN288_H44441004_PIP-SCONN,HA!!!F184!DQ(54)!!!!
S!M_M_DQ<54>!J1A1!269!@baseboard_fab2_lib.baseboard_fab2(sch_1):page87_i186@mstr_sconn.sconn288_h44441004(chips)!SCONN288_H44441004_PIP-SCONN,HA!!!F184!DQ(55)!!!!
S!M_M_DQ<57>!J1A1!130!@baseboard_fab2_lib.baseboard_fab2(sch_1):page87_i186@mstr_sconn.sconn288_h44441004(chips)!SCONN288_H44441004_PIP-SCONN,HA!!!F184!DQ(56)!!!!
S!M_M_DQ<56>!J1A1!275!@baseboard_fab2_lib.baseboard_fab2(sch_1):page87_i186@mstr_sconn.sconn288_h44441004(chips)!SCONN288_H44441004_PIP-SCONN,HA!!!F184!DQ(57)!!!!
S!M_M_DQ<59>!J1A1!137!@baseboard_fab2_lib.baseboard_fab2(sch_1):page87_i186@mstr_sconn.sconn288_h44441004(chips)!SCONN288_H44441004_PIP-SCONN,HA!!!F184!DQ(58)!!!!
S!M_M_DQ<58>!J1A1!282!@baseboard_fab2_lib.baseboard_fab2(sch_1):page87_i186@mstr_sconn.sconn288_h44441004(chips)!SCONN288_H44441004_PIP-SCONN,HA!!!F184!DQ(59)!!!!
S!M_M_DQ<4>!J1A1!148!@baseboard_fab2_lib.baseboard_fab2(sch_1):page87_i186@mstr_sconn.sconn288_h44441004(chips)!SCONN288_H44441004_PIP-SCONN,HA!!!F184!DQ(5)!!!!
S!M_M_DQ<61>!J1A1!128!@baseboard_fab2_lib.baseboard_fab2(sch_1):page87_i186@mstr_sconn.sconn288_h44441004(chips)!SCONN288_H44441004_PIP-SCONN,HA!!!F184!DQ(60)!!!!
S!M_M_DQ<60>!J1A1!273!@baseboard_fab2_lib.baseboard_fab2(sch_1):page87_i186@mstr_sconn.sconn288_h44441004(chips)!SCONN288_H44441004_PIP-SCONN,HA!!!F184!DQ(61)!!!!
S!M_M_DQ<63>!J1A1!135!@baseboard_fab2_lib.baseboard_fab2(sch_1):page87_i186@mstr_sconn.sconn288_h44441004(chips)!SCONN288_H44441004_PIP-SCONN,HA!!!F184!DQ(62)!!!!
S!M_M_DQ<62>!J1A1!280!@baseboard_fab2_lib.baseboard_fab2(sch_1):page87_i186@mstr_sconn.sconn288_h44441004(chips)!SCONN288_H44441004_PIP-SCONN,HA!!!F184!DQ(63)!!!!
S!M_M_DQ<7>!J1A1!10!@baseboard_fab2_lib.baseboard_fab2(sch_1):page87_i186@mstr_sconn.sconn288_h44441004(chips)!SCONN288_H44441004_PIP-SCONN,HA!!!F184!DQ(6)!!!!
S!M_M_DQ<6>!J1A1!155!@baseboard_fab2_lib.baseboard_fab2(sch_1):page87_i186@mstr_sconn.sconn288_h44441004(chips)!SCONN288_H44441004_PIP-SCONN,HA!!!F184!DQ(7)!!!!
S!M_M_DQ<9>!J1A1!16!@baseboard_fab2_lib.baseboard_fab2(sch_1):page87_i186@mstr_sconn.sconn288_h44441004(chips)!SCONN288_H44441004_PIP-SCONN,HA!!!F184!DQ(8)!!!!
S!M_M_DQ<8>!J1A1!161!@baseboard_fab2_lib.baseboard_fab2(sch_1):page87_i186@mstr_sconn.sconn288_h44441004(chips)!SCONN288_H44441004_PIP-SCONN,HA!!!F184!DQ(9)!!!!
S!FM_DIMM_EVENT_COD_N!J1A1!78!@baseboard_fab2_lib.baseboard_fab2(sch_1):page87_i186@mstr_sconn.sconn288_h44441004(chips)!SCONN288_H44441004_PIP-SCONN,HA!!!F184!EVENT_N!!!!
S!M_M_ODT<0>!J1A1!87!@baseboard_fab2_lib.baseboard_fab2(sch_1):page87_i186@mstr_sconn.sconn288_h44441004(chips)!SCONN288_H44441004_PIP-SCONN,HA!!!F184!ODT(0)!!!!
S!M_M_ODT<1>!J1A1!91!@baseboard_fab2_lib.baseboard_fab2(sch_1):page87_i186@mstr_sconn.sconn288_h44441004(chips)!SCONN288_H44441004_PIP-SCONN,HA!!!F184!ODT(1)!!!!
S!M_M_PAR!J1A1!222!@baseboard_fab2_lib.baseboard_fab2(sch_1):page87_i186@mstr_sconn.sconn288_h44441004(chips)!SCONN288_H44441004_PIP-SCONN,HA!!!F184!PAR!!!!
S!M_KLM_RST_N!J1A1!58!@baseboard_fab2_lib.baseboard_fab2(sch_1):page87_i186@mstr_sconn.sconn288_h44441004(chips)!SCONN288_H44441004_PIP-SCONN,HA!!!F184!RESET_N!!!!
S!TP_CH_M_DIMM_M0_RFU_0!J1A1!205!@baseboard_fab2_lib.baseboard_fab2(sch_1):page87_i186@mstr_sconn.sconn288_h44441004(chips)!SCONN288_H44441004_PIP-SCONN,HA!!!F184!RFU(0)!!!!
S!TP_CH_M_DIMM_M0_RFU_1!J1A1!227!@baseboard_fab2_lib.baseboard_fab2(sch_1):page87_i186@mstr_sconn.sconn288_h44441004(chips)!SCONN288_H44441004_PIP-SCONN,HA!!!F184!RFU(1)!!!!
S!TP_CH_M_DIMM_M0_RFU_2!J1A1!144!@baseboard_fab2_lib.baseboard_fab2(sch_1):page87_i186@mstr_sconn.sconn288_h44441004(chips)!SCONN288_H44441004_PIP-SCONN,HA!!!F184!RFU(2)!!!!
S!M_M_CS_N<0>!J1A1!84!@baseboard_fab2_lib.baseboard_fab2(sch_1):page87_i186@mstr_sconn.sconn288_h44441004(chips)!SCONN288_H44441004_PIP-SCONN,HA!!!F184!S0_N!!!!
S!M_M_CS_N<1>!J1A1!89!@baseboard_fab2_lib.baseboard_fab2(sch_1):page87_i186@mstr_sconn.sconn288_h44441004(chips)!SCONN288_H44441004_PIP-SCONN,HA!!!F184!S1_N!!!!
S!M_M_CS_N<2>!J1A1!93!@baseboard_fab2_lib.baseboard_fab2(sch_1):page87_i186@mstr_sconn.sconn288_h44441004(chips)!SCONN288_H44441004_PIP-SCONN,HA!!!F184!S2_N_C(0)!!!!
S!M_M_CS_N<3>!J1A1!237!@baseboard_fab2_lib.baseboard_fab2(sch_1):page87_i186@mstr_sconn.sconn288_h44441004(chips)!SCONN288_H44441004_PIP-SCONN,HA!!!F184!S3_N_C(1)!!!!
S!GND!J1A1!139!@baseboard_fab2_lib.baseboard_fab2(sch_1):page87_i186@mstr_sconn.sconn288_h44441004(chips)!SCONN288_H44441004_PIP-SCONN,HA!!!F184!SA(0)!!!!
S!GND!J1A1!140!@baseboard_fab2_lib.baseboard_fab2(sch_1):page87_i186@mstr_sconn.sconn288_h44441004(chips)!SCONN288_H44441004_PIP-SCONN,HA!!!F184!SA(1)!!!!
S!PVPP_KLM!J1A1!238!@baseboard_fab2_lib.baseboard_fab2(sch_1):page87_i186@mstr_sconn.sconn288_h44441004(chips)!SCONN288_H44441004_PIP-SCONN,HA!!!F184!SA(2)!!!!
S!FM_ADR_COMPLETE_KLM_N!J1A1!230!@baseboard_fab2_lib.baseboard_fab2(sch_1):page87_i186@mstr_sconn.sconn288_h44441004(chips)!SCONN288_H44441004_PIP-SCONN,HA!!!F184!SAVE_N_NC!!!!
S!SMB_DDR_KLM_VPP_SCL!J1A1!141!@baseboard_fab2_lib.baseboard_fab2(sch_1):page87_i186@mstr_sconn.sconn288_h44441004(chips)!SCONN288_H44441004_PIP-SCONN,HA!!!F184!SCL!!!!
S!SMB_DDR_KLM_VPP_SDA!J1A1!285!@baseboard_fab2_lib.baseboard_fab2(sch_1):page87_i186@mstr_sconn.sconn288_h44441004(chips)!SCONN288_H44441004_PIP-SCONN,HA!!!F184!SDA!!!!
S!PVPP_KLM!J1A1!284!@baseboard_fab2_lib.baseboard_fab2(sch_1):page87_i186@mstr_sconn.sconn288_h44441004(chips)!SCONN288_H44441004_PIP-SCONN,HA!!!F184!VDDSPD!!!!
S!M_M_VREF!J1A1!146!@baseboard_fab2_lib.baseboard_fab2(sch_1):page87_i186@mstr_sconn.sconn288_h44441004(chips)!SCONN288_H44441004_PIP-SCONN,HA!!!F184!VREFCA!!!!
S!M_M_DQS_DN<0>!J1A1!152!@baseboard_fab2_lib.baseboard_fab2(sch_1):page87_i187@mstr_sconn.sconn288_h44441004(chips)!SCONN288_H44441004_PIP-SCONN,HA!!!F183!DQS0N!!!!
S!M_M_DQS_DP<0>!J1A1!153!@baseboard_fab2_lib.baseboard_fab2(sch_1):page87_i187@mstr_sconn.sconn288_h44441004(chips)!SCONN288_H44441004_PIP-SCONN,HA!!!F183!DQS0P!!!!
S!M_M_DQS_DN<10>!J1A1!19!@baseboard_fab2_lib.baseboard_fab2(sch_1):page87_i187@mstr_sconn.sconn288_h44441004(chips)!SCONN288_H44441004_PIP-SCONN,HA!!!F183!DQS10N!!!!
S!M_M_DQS_DP<10>!J1A1!18!@baseboard_fab2_lib.baseboard_fab2(sch_1):page87_i187@mstr_sconn.sconn288_h44441004(chips)!SCONN288_H44441004_PIP-SCONN,HA!!!F183!DQS10P!!!!
S!M_M_DQS_DN<11>!J1A1!30!@baseboard_fab2_lib.baseboard_fab2(sch_1):page87_i187@mstr_sconn.sconn288_h44441004(chips)!SCONN288_H44441004_PIP-SCONN,HA!!!F183!DQS11N!!!!
S!M_M_DQS_DP<11>!J1A1!29!@baseboard_fab2_lib.baseboard_fab2(sch_1):page87_i187@mstr_sconn.sconn288_h44441004(chips)!SCONN288_H44441004_PIP-SCONN,HA!!!F183!DQS11P!!!!
S!M_M_DQS_DN<12>!J1A1!41!@baseboard_fab2_lib.baseboard_fab2(sch_1):page87_i187@mstr_sconn.sconn288_h44441004(chips)!SCONN288_H44441004_PIP-SCONN,HA!!!F183!DQS12N!!!!
S!M_M_DQS_DP<12>!J1A1!40!@baseboard_fab2_lib.baseboard_fab2(sch_1):page87_i187@mstr_sconn.sconn288_h44441004(chips)!SCONN288_H44441004_PIP-SCONN,HA!!!F183!DQS12P!!!!
S!M_M_DQS_DN<13>!J1A1!100!@baseboard_fab2_lib.baseboard_fab2(sch_1):page87_i187@mstr_sconn.sconn288_h44441004(chips)!SCONN288_H44441004_PIP-SCONN,HA!!!F183!DQS13N!!!!
S!M_M_DQS_DP<13>!J1A1!99!@baseboard_fab2_lib.baseboard_fab2(sch_1):page87_i187@mstr_sconn.sconn288_h44441004(chips)!SCONN288_H44441004_PIP-SCONN,HA!!!F183!DQS13P!!!!
S!M_M_DQS_DN<14>!J1A1!111!@baseboard_fab2_lib.baseboard_fab2(sch_1):page87_i187@mstr_sconn.sconn288_h44441004(chips)!SCONN288_H44441004_PIP-SCONN,HA!!!F183!DQS14N!!!!
S!M_M_DQS_DP<14>!J1A1!110!@baseboard_fab2_lib.baseboard_fab2(sch_1):page87_i187@mstr_sconn.sconn288_h44441004(chips)!SCONN288_H44441004_PIP-SCONN,HA!!!F183!DQS14P!!!!
S!M_M_DQS_DN<15>!J1A1!122!@baseboard_fab2_lib.baseboard_fab2(sch_1):page87_i187@mstr_sconn.sconn288_h44441004(chips)!SCONN288_H44441004_PIP-SCONN,HA!!!F183!DQS15N!!!!
S!M_M_DQS_DP<15>!J1A1!121!@baseboard_fab2_lib.baseboard_fab2(sch_1):page87_i187@mstr_sconn.sconn288_h44441004(chips)!SCONN288_H44441004_PIP-SCONN,HA!!!F183!DQS15P!!!!
S!M_M_DQS_DN<16>!J1A1!133!@baseboard_fab2_lib.baseboard_fab2(sch_1):page87_i187@mstr_sconn.sconn288_h44441004(chips)!SCONN288_H44441004_PIP-SCONN,HA!!!F183!DQS16N!!!!
S!M_M_DQS_DP<16>!J1A1!132!@baseboard_fab2_lib.baseboard_fab2(sch_1):page87_i187@mstr_sconn.sconn288_h44441004(chips)!SCONN288_H44441004_PIP-SCONN,HA!!!F183!DQS16P!!!!
S!M_M_DQS_DN<17>!J1A1!52!@baseboard_fab2_lib.baseboard_fab2(sch_1):page87_i187@mstr_sconn.sconn288_h44441004(chips)!SCONN288_H44441004_PIP-SCONN,HA!!!F183!DQS17N!!!!
S!M_M_DQS_DP<17>!J1A1!51!@baseboard_fab2_lib.baseboard_fab2(sch_1):page87_i187@mstr_sconn.sconn288_h44441004(chips)!SCONN288_H44441004_PIP-SCONN,HA!!!F183!DQS17P!!!!
S!M_M_DQS_DN<1>!J1A1!163!@baseboard_fab2_lib.baseboard_fab2(sch_1):page87_i187@mstr_sconn.sconn288_h44441004(chips)!SCONN288_H44441004_PIP-SCONN,HA!!!F183!DQS1N!!!!
S!M_M_DQS_DP<1>!J1A1!164!@baseboard_fab2_lib.baseboard_fab2(sch_1):page87_i187@mstr_sconn.sconn288_h44441004(chips)!SCONN288_H44441004_PIP-SCONN,HA!!!F183!DQS1P!!!!
S!M_M_DQS_DN<2>!J1A1!174!@baseboard_fab2_lib.baseboard_fab2(sch_1):page87_i187@mstr_sconn.sconn288_h44441004(chips)!SCONN288_H44441004_PIP-SCONN,HA!!!F183!DQS2N!!!!
S!M_M_DQS_DP<2>!J1A1!175!@baseboard_fab2_lib.baseboard_fab2(sch_1):page87_i187@mstr_sconn.sconn288_h44441004(chips)!SCONN288_H44441004_PIP-SCONN,HA!!!F183!DQS2P!!!!
S!M_M_DQS_DN<3>!J1A1!185!@baseboard_fab2_lib.baseboard_fab2(sch_1):page87_i187@mstr_sconn.sconn288_h44441004(chips)!SCONN288_H44441004_PIP-SCONN,HA!!!F183!DQS3N!!!!
S!M_M_DQS_DP<3>!J1A1!186!@baseboard_fab2_lib.baseboard_fab2(sch_1):page87_i187@mstr_sconn.sconn288_h44441004(chips)!SCONN288_H44441004_PIP-SCONN,HA!!!F183!DQS3P!!!!
S!M_M_DQS_DN<4>!J1A1!244!@baseboard_fab2_lib.baseboard_fab2(sch_1):page87_i187@mstr_sconn.sconn288_h44441004(chips)!SCONN288_H44441004_PIP-SCONN,HA!!!F183!DQS4N!!!!
S!M_M_DQS_DP<4>!J1A1!245!@baseboard_fab2_lib.baseboard_fab2(sch_1):page87_i187@mstr_sconn.sconn288_h44441004(chips)!SCONN288_H44441004_PIP-SCONN,HA!!!F183!DQS4P!!!!
S!M_M_DQS_DN<5>!J1A1!255!@baseboard_fab2_lib.baseboard_fab2(sch_1):page87_i187@mstr_sconn.sconn288_h44441004(chips)!SCONN288_H44441004_PIP-SCONN,HA!!!F183!DQS5N!!!!
S!M_M_DQS_DP<5>!J1A1!256!@baseboard_fab2_lib.baseboard_fab2(sch_1):page87_i187@mstr_sconn.sconn288_h44441004(chips)!SCONN288_H44441004_PIP-SCONN,HA!!!F183!DQS5P!!!!
S!M_M_DQS_DN<6>!J1A1!266!@baseboard_fab2_lib.baseboard_fab2(sch_1):page87_i187@mstr_sconn.sconn288_h44441004(chips)!SCONN288_H44441004_PIP-SCONN,HA!!!F183!DQS6N!!!!
S!M_M_DQS_DP<6>!J1A1!267!@baseboard_fab2_lib.baseboard_fab2(sch_1):page87_i187@mstr_sconn.sconn288_h44441004(chips)!SCONN288_H44441004_PIP-SCONN,HA!!!F183!DQS6P!!!!
S!M_M_DQS_DN<7>!J1A1!277!@baseboard_fab2_lib.baseboard_fab2(sch_1):page87_i187@mstr_sconn.sconn288_h44441004(chips)!SCONN288_H44441004_PIP-SCONN,HA!!!F183!DQS7N!!!!
S!M_M_DQS_DP<7>!J1A1!278!@baseboard_fab2_lib.baseboard_fab2(sch_1):page87_i187@mstr_sconn.sconn288_h44441004(chips)!SCONN288_H44441004_PIP-SCONN,HA!!!F183!DQS7P!!!!
S!M_M_DQS_DN<8>!J1A1!196!@baseboard_fab2_lib.baseboard_fab2(sch_1):page87_i187@mstr_sconn.sconn288_h44441004(chips)!SCONN288_H44441004_PIP-SCONN,HA!!!F183!DQS8N!!!!
S!M_M_DQS_DP<8>!J1A1!197!@baseboard_fab2_lib.baseboard_fab2(sch_1):page87_i187@mstr_sconn.sconn288_h44441004(chips)!SCONN288_H44441004_PIP-SCONN,HA!!!F183!DQS8P!!!!
S!M_M_DQS_DN<9>!J1A1!8!@baseboard_fab2_lib.baseboard_fab2(sch_1):page87_i187@mstr_sconn.sconn288_h44441004(chips)!SCONN288_H44441004_PIP-SCONN,HA!!!F183!DQS9N!!!!
S!M_M_DQS_DP<9>!J1A1!7!@baseboard_fab2_lib.baseboard_fab2(sch_1):page87_i187@mstr_sconn.sconn288_h44441004(chips)!SCONN288_H44441004_PIP-SCONN,HA!!!F183!DQS9P!!!!
S!GND!J1A1!283!@baseboard_fab2_lib.baseboard_fab2(sch_1):page87_i185@mstr_sconn.sconn288_h44441004(chips)!SCONN288_H44441004_PIP-SCONN,HA!!!F182!VSS(0)!!!!
S!GND!J1A1!261!@baseboard_fab2_lib.baseboard_fab2(sch_1):page87_i185@mstr_sconn.sconn288_h44441004(chips)!SCONN288_H44441004_PIP-SCONN,HA!!!F182!VSS(10)!!!!
S!GND!J1A1!259!@baseboard_fab2_lib.baseboard_fab2(sch_1):page87_i185@mstr_sconn.sconn288_h44441004(chips)!SCONN288_H44441004_PIP-SCONN,HA!!!F182!VSS(11)!!!!
S!GND!J1A1!257!@baseboard_fab2_lib.baseboard_fab2(sch_1):page87_i185@mstr_sconn.sconn288_h44441004(chips)!SCONN288_H44441004_PIP-SCONN,HA!!!F182!VSS(12)!!!!
S!GND!J1A1!254!@baseboard_fab2_lib.baseboard_fab2(sch_1):page87_i185@mstr_sconn.sconn288_h44441004(chips)!SCONN288_H44441004_PIP-SCONN,HA!!!F182!VSS(13)!!!!
S!GND!J1A1!252!@baseboard_fab2_lib.baseboard_fab2(sch_1):page87_i185@mstr_sconn.sconn288_h44441004(chips)!SCONN288_H44441004_PIP-SCONN,HA!!!F182!VSS(14)!!!!
S!GND!J1A1!250!@baseboard_fab2_lib.baseboard_fab2(sch_1):page87_i185@mstr_sconn.sconn288_h44441004(chips)!SCONN288_H44441004_PIP-SCONN,HA!!!F182!VSS(15)!!!!
S!GND!J1A1!248!@baseboard_fab2_lib.baseboard_fab2(sch_1):page87_i185@mstr_sconn.sconn288_h44441004(chips)!SCONN288_H44441004_PIP-SCONN,HA!!!F182!VSS(16)!!!!
S!GND!J1A1!246!@baseboard_fab2_lib.baseboard_fab2(sch_1):page87_i185@mstr_sconn.sconn288_h44441004(chips)!SCONN288_H44441004_PIP-SCONN,HA!!!F182!VSS(17)!!!!
S!GND!J1A1!243!@baseboard_fab2_lib.baseboard_fab2(sch_1):page87_i185@mstr_sconn.sconn288_h44441004(chips)!SCONN288_H44441004_PIP-SCONN,HA!!!F182!VSS(18)!!!!
S!GND!J1A1!241!@baseboard_fab2_lib.baseboard_fab2(sch_1):page87_i185@mstr_sconn.sconn288_h44441004(chips)!SCONN288_H44441004_PIP-SCONN,HA!!!F182!VSS(19)!!!!
S!GND!J1A1!281!@baseboard_fab2_lib.baseboard_fab2(sch_1):page87_i185@mstr_sconn.sconn288_h44441004(chips)!SCONN288_H44441004_PIP-SCONN,HA!!!F182!VSS(1)!!!!
S!GND!J1A1!239!@baseboard_fab2_lib.baseboard_fab2(sch_1):page87_i185@mstr_sconn.sconn288_h44441004(chips)!SCONN288_H44441004_PIP-SCONN,HA!!!F182!VSS(20)!!!!
S!GND!J1A1!202!@baseboard_fab2_lib.baseboard_fab2(sch_1):page87_i185@mstr_sconn.sconn288_h44441004(chips)!SCONN288_H44441004_PIP-SCONN,HA!!!F182!VSS(21)!!!!
S!GND!J1A1!200!@baseboard_fab2_lib.baseboard_fab2(sch_1):page87_i185@mstr_sconn.sconn288_h44441004(chips)!SCONN288_H44441004_PIP-SCONN,HA!!!F182!VSS(22)!!!!
S!GND!J1A1!198!@baseboard_fab2_lib.baseboard_fab2(sch_1):page87_i185@mstr_sconn.sconn288_h44441004(chips)!SCONN288_H44441004_PIP-SCONN,HA!!!F182!VSS(23)!!!!
S!GND!J1A1!195!@baseboard_fab2_lib.baseboard_fab2(sch_1):page87_i185@mstr_sconn.sconn288_h44441004(chips)!SCONN288_H44441004_PIP-SCONN,HA!!!F182!VSS(24)!!!!
S!GND!J1A1!193!@baseboard_fab2_lib.baseboard_fab2(sch_1):page87_i185@mstr_sconn.sconn288_h44441004(chips)!SCONN288_H44441004_PIP-SCONN,HA!!!F182!VSS(25)!!!!
S!GND!J1A1!191!@baseboard_fab2_lib.baseboard_fab2(sch_1):page87_i185@mstr_sconn.sconn288_h44441004(chips)!SCONN288_H44441004_PIP-SCONN,HA!!!F182!VSS(26)!!!!
S!GND!J1A1!189!@baseboard_fab2_lib.baseboard_fab2(sch_1):page87_i185@mstr_sconn.sconn288_h44441004(chips)!SCONN288_H44441004_PIP-SCONN,HA!!!F182!VSS(27)!!!!
S!GND!J1A1!187!@baseboard_fab2_lib.baseboard_fab2(sch_1):page87_i185@mstr_sconn.sconn288_h44441004(chips)!SCONN288_H44441004_PIP-SCONN,HA!!!F182!VSS(28)!!!!
S!GND!J1A1!184!@baseboard_fab2_lib.baseboard_fab2(sch_1):page87_i185@mstr_sconn.sconn288_h44441004(chips)!SCONN288_H44441004_PIP-SCONN,HA!!!F182!VSS(29)!!!!
S!GND!J1A1!279!@baseboard_fab2_lib.baseboard_fab2(sch_1):page87_i185@mstr_sconn.sconn288_h44441004(chips)!SCONN288_H44441004_PIP-SCONN,HA!!!F182!VSS(2)!!!!
S!GND!J1A1!182!@baseboard_fab2_lib.baseboard_fab2(sch_1):page87_i185@mstr_sconn.sconn288_h44441004(chips)!SCONN288_H44441004_PIP-SCONN,HA!!!F182!VSS(30)!!!!
S!GND!J1A1!180!@baseboard_fab2_lib.baseboard_fab2(sch_1):page87_i185@mstr_sconn.sconn288_h44441004(chips)!SCONN288_H44441004_PIP-SCONN,HA!!!F182!VSS(31)!!!!
S!GND!J1A1!178!@baseboard_fab2_lib.baseboard_fab2(sch_1):page87_i185@mstr_sconn.sconn288_h44441004(chips)!SCONN288_H44441004_PIP-SCONN,HA!!!F182!VSS(32)!!!!
S!GND!J1A1!176!@baseboard_fab2_lib.baseboard_fab2(sch_1):page87_i185@mstr_sconn.sconn288_h44441004(chips)!SCONN288_H44441004_PIP-SCONN,HA!!!F182!VSS(33)!!!!
S!GND!J1A1!173!@baseboard_fab2_lib.baseboard_fab2(sch_1):page87_i185@mstr_sconn.sconn288_h44441004(chips)!SCONN288_H44441004_PIP-SCONN,HA!!!F182!VSS(34)!!!!
S!GND!J1A1!171!@baseboard_fab2_lib.baseboard_fab2(sch_1):page87_i185@mstr_sconn.sconn288_h44441004(chips)!SCONN288_H44441004_PIP-SCONN,HA!!!F182!VSS(35)!!!!
S!GND!J1A1!169!@baseboard_fab2_lib.baseboard_fab2(sch_1):page87_i185@mstr_sconn.sconn288_h44441004(chips)!SCONN288_H44441004_PIP-SCONN,HA!!!F182!VSS(36)!!!!
S!GND!J1A1!167!@baseboard_fab2_lib.baseboard_fab2(sch_1):page87_i185@mstr_sconn.sconn288_h44441004(chips)!SCONN288_H44441004_PIP-SCONN,HA!!!F182!VSS(37)!!!!
S!GND!J1A1!165!@baseboard_fab2_lib.baseboard_fab2(sch_1):page87_i185@mstr_sconn.sconn288_h44441004(chips)!SCONN288_H44441004_PIP-SCONN,HA!!!F182!VSS(38)!!!!
S!GND!J1A1!162!@baseboard_fab2_lib.baseboard_fab2(sch_1):page87_i185@mstr_sconn.sconn288_h44441004(chips)!SCONN288_H44441004_PIP-SCONN,HA!!!F182!VSS(39)!!!!
S!GND!J1A1!276!@baseboard_fab2_lib.baseboard_fab2(sch_1):page87_i185@mstr_sconn.sconn288_h44441004(chips)!SCONN288_H44441004_PIP-SCONN,HA!!!F182!VSS(3)!!!!
S!GND!J1A1!160!@baseboard_fab2_lib.baseboard_fab2(sch_1):page87_i185@mstr_sconn.sconn288_h44441004(chips)!SCONN288_H44441004_PIP-SCONN,HA!!!F182!VSS(40)!!!!
S!GND!J1A1!158!@baseboard_fab2_lib.baseboard_fab2(sch_1):page87_i185@mstr_sconn.sconn288_h44441004(chips)!SCONN288_H44441004_PIP-SCONN,HA!!!F182!VSS(41)!!!!
S!GND!J1A1!156!@baseboard_fab2_lib.baseboard_fab2(sch_1):page87_i185@mstr_sconn.sconn288_h44441004(chips)!SCONN288_H44441004_PIP-SCONN,HA!!!F182!VSS(42)!!!!
S!GND!J1A1!154!@baseboard_fab2_lib.baseboard_fab2(sch_1):page87_i185@mstr_sconn.sconn288_h44441004(chips)!SCONN288_H44441004_PIP-SCONN,HA!!!F182!VSS(43)!!!!
S!GND!J1A1!151!@baseboard_fab2_lib.baseboard_fab2(sch_1):page87_i185@mstr_sconn.sconn288_h44441004(chips)!SCONN288_H44441004_PIP-SCONN,HA!!!F182!VSS(44)!!!!
S!GND!J1A1!149!@baseboard_fab2_lib.baseboard_fab2(sch_1):page87_i185@mstr_sconn.sconn288_h44441004(chips)!SCONN288_H44441004_PIP-SCONN,HA!!!F182!VSS(45)!!!!
S!GND!J1A1!147!@baseboard_fab2_lib.baseboard_fab2(sch_1):page87_i185@mstr_sconn.sconn288_h44441004(chips)!SCONN288_H44441004_PIP-SCONN,HA!!!F182!VSS(46)!!!!
S!GND!J1A1!138!@baseboard_fab2_lib.baseboard_fab2(sch_1):page87_i185@mstr_sconn.sconn288_h44441004(chips)!SCONN288_H44441004_PIP-SCONN,HA!!!F182!VSS(47)!!!!
S!GND!J1A1!136!@baseboard_fab2_lib.baseboard_fab2(sch_1):page87_i185@mstr_sconn.sconn288_h44441004(chips)!SCONN288_H44441004_PIP-SCONN,HA!!!F182!VSS(48)!!!!
S!GND!J1A1!134!@baseboard_fab2_lib.baseboard_fab2(sch_1):page87_i185@mstr_sconn.sconn288_h44441004(chips)!SCONN288_H44441004_PIP-SCONN,HA!!!F182!VSS(49)!!!!
S!GND!J1A1!274!@baseboard_fab2_lib.baseboard_fab2(sch_1):page87_i185@mstr_sconn.sconn288_h44441004(chips)!SCONN288_H44441004_PIP-SCONN,HA!!!F182!VSS(4)!!!!
S!GND!J1A1!131!@baseboard_fab2_lib.baseboard_fab2(sch_1):page87_i185@mstr_sconn.sconn288_h44441004(chips)!SCONN288_H44441004_PIP-SCONN,HA!!!F182!VSS(50)!!!!
S!GND!J1A1!129!@baseboard_fab2_lib.baseboard_fab2(sch_1):page87_i185@mstr_sconn.sconn288_h44441004(chips)!SCONN288_H44441004_PIP-SCONN,HA!!!F182!VSS(51)!!!!
S!GND!J1A1!127!@baseboard_fab2_lib.baseboard_fab2(sch_1):page87_i185@mstr_sconn.sconn288_h44441004(chips)!SCONN288_H44441004_PIP-SCONN,HA!!!F182!VSS(52)!!!!
S!GND!J1A1!125!@baseboard_fab2_lib.baseboard_fab2(sch_1):page87_i185@mstr_sconn.sconn288_h44441004(chips)!SCONN288_H44441004_PIP-SCONN,HA!!!F182!VSS(53)!!!!
S!GND!J1A1!123!@baseboard_fab2_lib.baseboard_fab2(sch_1):page87_i185@mstr_sconn.sconn288_h44441004(chips)!SCONN288_H44441004_PIP-SCONN,HA!!!F182!VSS(54)!!!!
S!GND!J1A1!120!@baseboard_fab2_lib.baseboard_fab2(sch_1):page87_i185@mstr_sconn.sconn288_h44441004(chips)!SCONN288_H44441004_PIP-SCONN,HA!!!F182!VSS(55)!!!!
S!GND!J1A1!118!@baseboard_fab2_lib.baseboard_fab2(sch_1):page87_i185@mstr_sconn.sconn288_h44441004(chips)!SCONN288_H44441004_PIP-SCONN,HA!!!F182!VSS(56)!!!!
S!GND!J1A1!116!@baseboard_fab2_lib.baseboard_fab2(sch_1):page87_i185@mstr_sconn.sconn288_h44441004(chips)!SCONN288_H44441004_PIP-SCONN,HA!!!F182!VSS(57)!!!!
S!GND!J1A1!114!@baseboard_fab2_lib.baseboard_fab2(sch_1):page87_i185@mstr_sconn.sconn288_h44441004(chips)!SCONN288_H44441004_PIP-SCONN,HA!!!F182!VSS(58)!!!!
S!GND!J1A1!112!@baseboard_fab2_lib.baseboard_fab2(sch_1):page87_i185@mstr_sconn.sconn288_h44441004(chips)!SCONN288_H44441004_PIP-SCONN,HA!!!F182!VSS(59)!!!!
S!GND!J1A1!272!@baseboard_fab2_lib.baseboard_fab2(sch_1):page87_i185@mstr_sconn.sconn288_h44441004(chips)!SCONN288_H44441004_PIP-SCONN,HA!!!F182!VSS(5)!!!!
S!GND!J1A1!109!@baseboard_fab2_lib.baseboard_fab2(sch_1):page87_i185@mstr_sconn.sconn288_h44441004(chips)!SCONN288_H44441004_PIP-SCONN,HA!!!F182!VSS(60)!!!!
S!GND!J1A1!107!@baseboard_fab2_lib.baseboard_fab2(sch_1):page87_i185@mstr_sconn.sconn288_h44441004(chips)!SCONN288_H44441004_PIP-SCONN,HA!!!F182!VSS(61)!!!!
S!GND!J1A1!105!@baseboard_fab2_lib.baseboard_fab2(sch_1):page87_i185@mstr_sconn.sconn288_h44441004(chips)!SCONN288_H44441004_PIP-SCONN,HA!!!F182!VSS(62)!!!!
S!GND!J1A1!103!@baseboard_fab2_lib.baseboard_fab2(sch_1):page87_i185@mstr_sconn.sconn288_h44441004(chips)!SCONN288_H44441004_PIP-SCONN,HA!!!F182!VSS(63)!!!!
S!GND!J1A1!101!@baseboard_fab2_lib.baseboard_fab2(sch_1):page87_i185@mstr_sconn.sconn288_h44441004(chips)!SCONN288_H44441004_PIP-SCONN,HA!!!F182!VSS(64)!!!!
S!GND!J1A1!98!@baseboard_fab2_lib.baseboard_fab2(sch_1):page87_i185@mstr_sconn.sconn288_h44441004(chips)!SCONN288_H44441004_PIP-SCONN,HA!!!F182!VSS(65)!!!!
S!GND!J1A1!96!@baseboard_fab2_lib.baseboard_fab2(sch_1):page87_i185@mstr_sconn.sconn288_h44441004(chips)!SCONN288_H44441004_PIP-SCONN,HA!!!F182!VSS(66)!!!!
S!GND!J1A1!94!@baseboard_fab2_lib.baseboard_fab2(sch_1):page87_i185@mstr_sconn.sconn288_h44441004(chips)!SCONN288_H44441004_PIP-SCONN,HA!!!F182!VSS(67)!!!!
S!GND!J1A1!57!@baseboard_fab2_lib.baseboard_fab2(sch_1):page87_i185@mstr_sconn.sconn288_h44441004(chips)!SCONN288_H44441004_PIP-SCONN,HA!!!F182!VSS(68)!!!!
S!GND!J1A1!55!@baseboard_fab2_lib.baseboard_fab2(sch_1):page87_i185@mstr_sconn.sconn288_h44441004(chips)!SCONN288_H44441004_PIP-SCONN,HA!!!F182!VSS(69)!!!!
S!GND!J1A1!270!@baseboard_fab2_lib.baseboard_fab2(sch_1):page87_i185@mstr_sconn.sconn288_h44441004(chips)!SCONN288_H44441004_PIP-SCONN,HA!!!F182!VSS(6)!!!!
S!GND!J1A1!53!@baseboard_fab2_lib.baseboard_fab2(sch_1):page87_i185@mstr_sconn.sconn288_h44441004(chips)!SCONN288_H44441004_PIP-SCONN,HA!!!F182!VSS(70)!!!!
S!GND!J1A1!50!@baseboard_fab2_lib.baseboard_fab2(sch_1):page87_i185@mstr_sconn.sconn288_h44441004(chips)!SCONN288_H44441004_PIP-SCONN,HA!!!F182!VSS(71)!!!!
S!GND!J1A1!48!@baseboard_fab2_lib.baseboard_fab2(sch_1):page87_i185@mstr_sconn.sconn288_h44441004(chips)!SCONN288_H44441004_PIP-SCONN,HA!!!F182!VSS(72)!!!!
S!GND!J1A1!46!@baseboard_fab2_lib.baseboard_fab2(sch_1):page87_i185@mstr_sconn.sconn288_h44441004(chips)!SCONN288_H44441004_PIP-SCONN,HA!!!F182!VSS(73)!!!!
S!GND!J1A1!44!@baseboard_fab2_lib.baseboard_fab2(sch_1):page87_i185@mstr_sconn.sconn288_h44441004(chips)!SCONN288_H44441004_PIP-SCONN,HA!!!F182!VSS(74)!!!!
S!GND!J1A1!42!@baseboard_fab2_lib.baseboard_fab2(sch_1):page87_i185@mstr_sconn.sconn288_h44441004(chips)!SCONN288_H44441004_PIP-SCONN,HA!!!F182!VSS(75)!!!!
S!GND!J1A1!39!@baseboard_fab2_lib.baseboard_fab2(sch_1):page87_i185@mstr_sconn.sconn288_h44441004(chips)!SCONN288_H44441004_PIP-SCONN,HA!!!F182!VSS(76)!!!!
S!GND!J1A1!37!@baseboard_fab2_lib.baseboard_fab2(sch_1):page87_i185@mstr_sconn.sconn288_h44441004(chips)!SCONN288_H44441004_PIP-SCONN,HA!!!F182!VSS(77)!!!!
S!GND!J1A1!35!@baseboard_fab2_lib.baseboard_fab2(sch_1):page87_i185@mstr_sconn.sconn288_h44441004(chips)!SCONN288_H44441004_PIP-SCONN,HA!!!F182!VSS(78)!!!!
S!GND!J1A1!33!@baseboard_fab2_lib.baseboard_fab2(sch_1):page87_i185@mstr_sconn.sconn288_h44441004(chips)!SCONN288_H44441004_PIP-SCONN,HA!!!F182!VSS(79)!!!!
S!GND!J1A1!268!@baseboard_fab2_lib.baseboard_fab2(sch_1):page87_i185@mstr_sconn.sconn288_h44441004(chips)!SCONN288_H44441004_PIP-SCONN,HA!!!F182!VSS(7)!!!!
S!GND!J1A1!31!@baseboard_fab2_lib.baseboard_fab2(sch_1):page87_i185@mstr_sconn.sconn288_h44441004(chips)!SCONN288_H44441004_PIP-SCONN,HA!!!F182!VSS(80)!!!!
S!GND!J1A1!28!@baseboard_fab2_lib.baseboard_fab2(sch_1):page87_i185@mstr_sconn.sconn288_h44441004(chips)!SCONN288_H44441004_PIP-SCONN,HA!!!F182!VSS(81)!!!!
S!GND!J1A1!26!@baseboard_fab2_lib.baseboard_fab2(sch_1):page87_i185@mstr_sconn.sconn288_h44441004(chips)!SCONN288_H44441004_PIP-SCONN,HA!!!F182!VSS(82)!!!!
S!GND!J1A1!24!@baseboard_fab2_lib.baseboard_fab2(sch_1):page87_i185@mstr_sconn.sconn288_h44441004(chips)!SCONN288_H44441004_PIP-SCONN,HA!!!F182!VSS(83)!!!!
S!GND!J1A1!22!@baseboard_fab2_lib.baseboard_fab2(sch_1):page87_i185@mstr_sconn.sconn288_h44441004(chips)!SCONN288_H44441004_PIP-SCONN,HA!!!F182!VSS(84)!!!!
S!GND!J1A1!20!@baseboard_fab2_lib.baseboard_fab2(sch_1):page87_i185@mstr_sconn.sconn288_h44441004(chips)!SCONN288_H44441004_PIP-SCONN,HA!!!F182!VSS(85)!!!!
S!GND!J1A1!17!@baseboard_fab2_lib.baseboard_fab2(sch_1):page87_i185@mstr_sconn.sconn288_h44441004(chips)!SCONN288_H44441004_PIP-SCONN,HA!!!F182!VSS(86)!!!!
S!GND!J1A1!15!@baseboard_fab2_lib.baseboard_fab2(sch_1):page87_i185@mstr_sconn.sconn288_h44441004(chips)!SCONN288_H44441004_PIP-SCONN,HA!!!F182!VSS(87)!!!!
S!GND!J1A1!13!@baseboard_fab2_lib.baseboard_fab2(sch_1):page87_i185@mstr_sconn.sconn288_h44441004(chips)!SCONN288_H44441004_PIP-SCONN,HA!!!F182!VSS(88)!!!!
S!GND!J1A1!11!@baseboard_fab2_lib.baseboard_fab2(sch_1):page87_i185@mstr_sconn.sconn288_h44441004(chips)!SCONN288_H44441004_PIP-SCONN,HA!!!F182!VSS(89)!!!!
S!GND!J1A1!265!@baseboard_fab2_lib.baseboard_fab2(sch_1):page87_i185@mstr_sconn.sconn288_h44441004(chips)!SCONN288_H44441004_PIP-SCONN,HA!!!F182!VSS(8)!!!!
S!GND!J1A1!9!@baseboard_fab2_lib.baseboard_fab2(sch_1):page87_i185@mstr_sconn.sconn288_h44441004(chips)!SCONN288_H44441004_PIP-SCONN,HA!!!F182!VSS(90)!!!!
S!GND!J1A1!6!@baseboard_fab2_lib.baseboard_fab2(sch_1):page87_i185@mstr_sconn.sconn288_h44441004(chips)!SCONN288_H44441004_PIP-SCONN,HA!!!F182!VSS(91)!!!!
S!GND!J1A1!4!@baseboard_fab2_lib.baseboard_fab2(sch_1):page87_i185@mstr_sconn.sconn288_h44441004(chips)!SCONN288_H44441004_PIP-SCONN,HA!!!F182!VSS(92)!!!!
S!GND!J1A1!2!@baseboard_fab2_lib.baseboard_fab2(sch_1):page87_i185@mstr_sconn.sconn288_h44441004(chips)!SCONN288_H44441004_PIP-SCONN,HA!!!F182!VSS(93)!!!!
S!GND!J1A1!263!@baseboard_fab2_lib.baseboard_fab2(sch_1):page87_i185@mstr_sconn.sconn288_h44441004(chips)!SCONN288_H44441004_PIP-SCONN,HA!!!F182!VSS(9)!!!!
S!P12V_NVDIMM_KLM!J1A1!145!@baseboard_fab2_lib.baseboard_fab2(sch_1):page87_i169@mstr_sconn.sconn288_h44441004(chips)!SCONN288_H44441004_PIP-SCONN,HA!!!F181!\12v\(0)!!!!
S!P12V_NVDIMM_KLM!J1A1!1!@baseboard_fab2_lib.baseboard_fab2(sch_1):page87_i169@mstr_sconn.sconn288_h44441004(chips)!SCONN288_H44441004_PIP-SCONN,HA!!!F181!\12v\(1)!!!!
S!PVDDQ_KLM!J1A1!236!@baseboard_fab2_lib.baseboard_fab2(sch_1):page87_i169@mstr_sconn.sconn288_h44441004(chips)!SCONN288_H44441004_PIP-SCONN,HA!!!F181!VDD(0)!!!!
S!PVDDQ_KLM!J1A1!209!@baseboard_fab2_lib.baseboard_fab2(sch_1):page87_i169@mstr_sconn.sconn288_h44441004(chips)!SCONN288_H44441004_PIP-SCONN,HA!!!F181!VDD(10)!!!!
S!PVDDQ_KLM!J1A1!206!@baseboard_fab2_lib.baseboard_fab2(sch_1):page87_i169@mstr_sconn.sconn288_h44441004(chips)!SCONN288_H44441004_PIP-SCONN,HA!!!F181!VDD(11)!!!!
S!PVDDQ_KLM!J1A1!204!@baseboard_fab2_lib.baseboard_fab2(sch_1):page87_i169@mstr_sconn.sconn288_h44441004(chips)!SCONN288_H44441004_PIP-SCONN,HA!!!F181!VDD(12)!!!!
S!PVDDQ_KLM!J1A1!92!@baseboard_fab2_lib.baseboard_fab2(sch_1):page87_i169@mstr_sconn.sconn288_h44441004(chips)!SCONN288_H44441004_PIP-SCONN,HA!!!F181!VDD(13)!!!!
S!PVDDQ_KLM!J1A1!90!@baseboard_fab2_lib.baseboard_fab2(sch_1):page87_i169@mstr_sconn.sconn288_h44441004(chips)!SCONN288_H44441004_PIP-SCONN,HA!!!F181!VDD(14)!!!!
S!PVDDQ_KLM!J1A1!88!@baseboard_fab2_lib.baseboard_fab2(sch_1):page87_i169@mstr_sconn.sconn288_h44441004(chips)!SCONN288_H44441004_PIP-SCONN,HA!!!F181!VDD(15)!!!!
S!PVDDQ_KLM!J1A1!85!@baseboard_fab2_lib.baseboard_fab2(sch_1):page87_i169@mstr_sconn.sconn288_h44441004(chips)!SCONN288_H44441004_PIP-SCONN,HA!!!F181!VDD(16)!!!!
S!PVDDQ_KLM!J1A1!83!@baseboard_fab2_lib.baseboard_fab2(sch_1):page87_i169@mstr_sconn.sconn288_h44441004(chips)!SCONN288_H44441004_PIP-SCONN,HA!!!F181!VDD(17)!!!!
S!PVDDQ_KLM!J1A1!80!@baseboard_fab2_lib.baseboard_fab2(sch_1):page87_i169@mstr_sconn.sconn288_h44441004(chips)!SCONN288_H44441004_PIP-SCONN,HA!!!F181!VDD(18)!!!!
S!PVDDQ_KLM!J1A1!76!@baseboard_fab2_lib.baseboard_fab2(sch_1):page87_i169@mstr_sconn.sconn288_h44441004(chips)!SCONN288_H44441004_PIP-SCONN,HA!!!F181!VDD(19)!!!!
S!PVDDQ_KLM!J1A1!233!@baseboard_fab2_lib.baseboard_fab2(sch_1):page87_i169@mstr_sconn.sconn288_h44441004(chips)!SCONN288_H44441004_PIP-SCONN,HA!!!F181!VDD(1)!!!!
S!PVDDQ_KLM!J1A1!73!@baseboard_fab2_lib.baseboard_fab2(sch_1):page87_i169@mstr_sconn.sconn288_h44441004(chips)!SCONN288_H44441004_PIP-SCONN,HA!!!F181!VDD(20)!!!!
S!PVDDQ_KLM!J1A1!70!@baseboard_fab2_lib.baseboard_fab2(sch_1):page87_i169@mstr_sconn.sconn288_h44441004(chips)!SCONN288_H44441004_PIP-SCONN,HA!!!F181!VDD(21)!!!!
S!PVDDQ_KLM!J1A1!67!@baseboard_fab2_lib.baseboard_fab2(sch_1):page87_i169@mstr_sconn.sconn288_h44441004(chips)!SCONN288_H44441004_PIP-SCONN,HA!!!F181!VDD(22)!!!!
S!PVDDQ_KLM!J1A1!64!@baseboard_fab2_lib.baseboard_fab2(sch_1):page87_i169@mstr_sconn.sconn288_h44441004(chips)!SCONN288_H44441004_PIP-SCONN,HA!!!F181!VDD(23)!!!!
S!PVDDQ_KLM!J1A1!61!@baseboard_fab2_lib.baseboard_fab2(sch_1):page87_i169@mstr_sconn.sconn288_h44441004(chips)!SCONN288_H44441004_PIP-SCONN,HA!!!F181!VDD(24)!!!!
S!PVDDQ_KLM!J1A1!59!@baseboard_fab2_lib.baseboard_fab2(sch_1):page87_i169@mstr_sconn.sconn288_h44441004(chips)!SCONN288_H44441004_PIP-SCONN,HA!!!F181!VDD(25)!!!!
S!PVDDQ_KLM!J1A1!231!@baseboard_fab2_lib.baseboard_fab2(sch_1):page87_i169@mstr_sconn.sconn288_h44441004(chips)!SCONN288_H44441004_PIP-SCONN,HA!!!F181!VDD(2)!!!!
S!PVDDQ_KLM!J1A1!229!@baseboard_fab2_lib.baseboard_fab2(sch_1):page87_i169@mstr_sconn.sconn288_h44441004(chips)!SCONN288_H44441004_PIP-SCONN,HA!!!F181!VDD(3)!!!!
S!PVDDQ_KLM!J1A1!226!@baseboard_fab2_lib.baseboard_fab2(sch_1):page87_i169@mstr_sconn.sconn288_h44441004(chips)!SCONN288_H44441004_PIP-SCONN,HA!!!F181!VDD(4)!!!!
S!PVDDQ_KLM!J1A1!223!@baseboard_fab2_lib.baseboard_fab2(sch_1):page87_i169@mstr_sconn.sconn288_h44441004(chips)!SCONN288_H44441004_PIP-SCONN,HA!!!F181!VDD(5)!!!!
S!PVDDQ_KLM!J1A1!220!@baseboard_fab2_lib.baseboard_fab2(sch_1):page87_i169@mstr_sconn.sconn288_h44441004(chips)!SCONN288_H44441004_PIP-SCONN,HA!!!F181!VDD(6)!!!!
S!PVDDQ_KLM!J1A1!217!@baseboard_fab2_lib.baseboard_fab2(sch_1):page87_i169@mstr_sconn.sconn288_h44441004(chips)!SCONN288_H44441004_PIP-SCONN,HA!!!F181!VDD(7)!!!!
S!PVDDQ_KLM!J1A1!215!@baseboard_fab2_lib.baseboard_fab2(sch_1):page87_i169@mstr_sconn.sconn288_h44441004(chips)!SCONN288_H44441004_PIP-SCONN,HA!!!F181!VDD(8)!!!!
S!PVDDQ_KLM!J1A1!212!@baseboard_fab2_lib.baseboard_fab2(sch_1):page87_i169@mstr_sconn.sconn288_h44441004(chips)!SCONN288_H44441004_PIP-SCONN,HA!!!F181!VDD(9)!!!!
S!PVPP_KLM!J1A1!287!@baseboard_fab2_lib.baseboard_fab2(sch_1):page87_i169@mstr_sconn.sconn288_h44441004(chips)!SCONN288_H44441004_PIP-SCONN,HA!!!F181!VPP(0)!!!!
S!PVPP_KLM!J1A1!286!@baseboard_fab2_lib.baseboard_fab2(sch_1):page87_i169@mstr_sconn.sconn288_h44441004(chips)!SCONN288_H44441004_PIP-SCONN,HA!!!F181!VPP(1)!!!!
S!PVPP_KLM!J1A1!288!@baseboard_fab2_lib.baseboard_fab2(sch_1):page87_i169@mstr_sconn.sconn288_h44441004(chips)!SCONN288_H44441004_PIP-SCONN,HA!!!F181!VPP(2)!!!!
S!PVPP_KLM!J1A1!143!@baseboard_fab2_lib.baseboard_fab2(sch_1):page87_i169@mstr_sconn.sconn288_h44441004(chips)!SCONN288_H44441004_PIP-SCONN,HA!!!F181!VPP(3)!!!!
S!PVPP_KLM!J1A1!142!@baseboard_fab2_lib.baseboard_fab2(sch_1):page87_i169@mstr_sconn.sconn288_h44441004(chips)!SCONN288_H44441004_PIP-SCONN,HA!!!F181!VPP(4)!!!!
S!PVTT_KLM!J1A1!221!@baseboard_fab2_lib.baseboard_fab2(sch_1):page87_i169@mstr_sconn.sconn288_h44441004(chips)!SCONN288_H44441004_PIP-SCONN,HA!!!F181!VTT(0)!!!!
S!PVTT_KLM!J1A1!77!@baseboard_fab2_lib.baseboard_fab2(sch_1):page87_i169@mstr_sconn.sconn288_h44441004(chips)!SCONN288_H44441004_PIP-SCONN,HA!!!F181!VTT(1)!!!!
S!SMB_LAN_STBY_LVC3_SDA!R2U12!1!@baseboard_fab2_lib.baseboard_fab2(sch_1):page138_i159@mstr_discrete.res(chips)!RES_0402-20.0,1%,1/16W,EMPTY,GA!!!F912!A!!!!
S!SMB_OCP_FRU_STBY_LVC3_SDA!R2U12!2!@baseboard_fab2_lib.baseboard_fab2(sch_1):page138_i159@mstr_discrete.res(chips)!RES_0402-20.0,1%,1/16W,EMPTY,GA!!!F912!B!!!!
S!SMB_LAN_STBY_LVC3_SCL!R2U8!1!@baseboard_fab2_lib.baseboard_fab2(sch_1):page138_i158@mstr_discrete.res(chips)!RES_0402-20.0,1%,1/16W,EMPTY,GA!!!F913!A!!!!
S!SMB_OCP_FRU_STBY_LVC3_SCL!R2U8!2!@baseboard_fab2_lib.baseboard_fab2(sch_1):page138_i158@mstr_discrete.res(chips)!RES_0402-20.0,1%,1/16W,EMPTY,GA!!!F913!B!!!!
S!SMB_SLOTX24_PCH_STBY_LVC3_SDA!R2U35!1!@baseboard_fab2_lib.baseboard_fab2(sch_1):page108_i320@mstr_discrete.res(chips)!RES_0402-20.0,1%,1/16W,EMPTY,GA!!!F911!A!!!!
S!SMB_SLOTX24_STBY_LVC3_SDA_R2!R2U35!2!@baseboard_fab2_lib.baseboard_fab2(sch_1):page108_i320@mstr_discrete.res(chips)!RES_0402-20.0,1%,1/16W,EMPTY,GA!!!F911!B!!!!
S!SMB_SLOTX24_PCH_STBY_LVC3_SCL!R2U36!1!@baseboard_fab2_lib.baseboard_fab2(sch_1):page108_i340@mstr_discrete.res(chips)!RES_0402-20.0,1%,1/16W,EMPTY,GA!!!F910!A!!!!
S!SMB_SLOTX24_STBY_LVC3_SCL_R2!R2U36!2!@baseboard_fab2_lib.baseboard_fab2(sch_1):page108_i340@mstr_discrete.res(chips)!RES_0402-20.0,1%,1/16W,EMPTY,GA!!!F910!B!!!!
S!M_A_MA<0>!J6T1!79!@baseboard_fab2_lib.baseboard_fab2(sch_1):page44_i13@mstr_sconn.sconn288_h44441003(chips)!SCONN288_H44441003_PIP-SCONN,HA!!!F220!A0!!!!
S!M_A_MA<1>!J6T1!72!@baseboard_fab2_lib.baseboard_fab2(sch_1):page44_i13@mstr_sconn.sconn288_h44441003(chips)!SCONN288_H44441003_PIP-SCONN,HA!!!F220!A1!!!!
S!M_A_MA<10>!J6T1!225!@baseboard_fab2_lib.baseboard_fab2(sch_1):page44_i13@mstr_sconn.sconn288_h44441003(chips)!SCONN288_H44441003_PIP-SCONN,HA!!!F220!A10!!!!
S!M_A_MA<11>!J6T1!210!@baseboard_fab2_lib.baseboard_fab2(sch_1):page44_i13@mstr_sconn.sconn288_h44441003(chips)!SCONN288_H44441003_PIP-SCONN,HA!!!F220!A11!!!!
S!M_A_MA<12>!J6T1!65!@baseboard_fab2_lib.baseboard_fab2(sch_1):page44_i13@mstr_sconn.sconn288_h44441003(chips)!SCONN288_H44441003_PIP-SCONN,HA!!!F220!A12!!!!
S!M_A_MA<13>!J6T1!232!@baseboard_fab2_lib.baseboard_fab2(sch_1):page44_i13@mstr_sconn.sconn288_h44441003(chips)!SCONN288_H44441003_PIP-SCONN,HA!!!F220!A13!!!!
S!M_A_MA<14>!J6T1!228!@baseboard_fab2_lib.baseboard_fab2(sch_1):page44_i13@mstr_sconn.sconn288_h44441003(chips)!SCONN288_H44441003_PIP-SCONN,HA!!!F220!A14_WE_N!!!!
S!M_A_MA<15>!J6T1!86!@baseboard_fab2_lib.baseboard_fab2(sch_1):page44_i13@mstr_sconn.sconn288_h44441003(chips)!SCONN288_H44441003_PIP-SCONN,HA!!!F220!A15_CAS_N!!!!
S!M_A_MA<16>!J6T1!82!@baseboard_fab2_lib.baseboard_fab2(sch_1):page44_i13@mstr_sconn.sconn288_h44441003(chips)!SCONN288_H44441003_PIP-SCONN,HA!!!F220!A16_RAS_N!!!!
S!M_A_MA<17>!J6T1!234!@baseboard_fab2_lib.baseboard_fab2(sch_1):page44_i13@mstr_sconn.sconn288_h44441003(chips)!SCONN288_H44441003_PIP-SCONN,HA!!!F220!A17!!!!
S!M_A_MA<2>!J6T1!216!@baseboard_fab2_lib.baseboard_fab2(sch_1):page44_i13@mstr_sconn.sconn288_h44441003(chips)!SCONN288_H44441003_PIP-SCONN,HA!!!F220!A2!!!!
S!M_A_MA<3>!J6T1!71!@baseboard_fab2_lib.baseboard_fab2(sch_1):page44_i13@mstr_sconn.sconn288_h44441003(chips)!SCONN288_H44441003_PIP-SCONN,HA!!!F220!A3!!!!
S!M_A_MA<4>!J6T1!214!@baseboard_fab2_lib.baseboard_fab2(sch_1):page44_i13@mstr_sconn.sconn288_h44441003(chips)!SCONN288_H44441003_PIP-SCONN,HA!!!F220!A4!!!!
S!M_A_MA<5>!J6T1!213!@baseboard_fab2_lib.baseboard_fab2(sch_1):page44_i13@mstr_sconn.sconn288_h44441003(chips)!SCONN288_H44441003_PIP-SCONN,HA!!!F220!A5!!!!
S!M_A_MA<6>!J6T1!69!@baseboard_fab2_lib.baseboard_fab2(sch_1):page44_i13@mstr_sconn.sconn288_h44441003(chips)!SCONN288_H44441003_PIP-SCONN,HA!!!F220!A6!!!!
S!M_A_MA<7>!J6T1!211!@baseboard_fab2_lib.baseboard_fab2(sch_1):page44_i13@mstr_sconn.sconn288_h44441003(chips)!SCONN288_H44441003_PIP-SCONN,HA!!!F220!A7!!!!
S!M_A_MA<8>!J6T1!68!@baseboard_fab2_lib.baseboard_fab2(sch_1):page44_i13@mstr_sconn.sconn288_h44441003(chips)!SCONN288_H44441003_PIP-SCONN,HA!!!F220!A8!!!!
S!M_A_MA<9>!J6T1!66!@baseboard_fab2_lib.baseboard_fab2(sch_1):page44_i13@mstr_sconn.sconn288_h44441003(chips)!SCONN288_H44441003_PIP-SCONN,HA!!!F220!A9!!!!
S!M_A_ACT_N!J6T1!62!@baseboard_fab2_lib.baseboard_fab2(sch_1):page44_i13@mstr_sconn.sconn288_h44441003(chips)!SCONN288_H44441003_PIP-SCONN,HA!!!F220!ACT_N!!!!
S!M_A_ALERT_N!J6T1!208!@baseboard_fab2_lib.baseboard_fab2(sch_1):page44_i13@mstr_sconn.sconn288_h44441003(chips)!SCONN288_H44441003_PIP-SCONN,HA!!!F220!ALERT_N!!!!
S!M_A_BA<0>!J6T1!81!@baseboard_fab2_lib.baseboard_fab2(sch_1):page44_i13@mstr_sconn.sconn288_h44441003(chips)!SCONN288_H44441003_PIP-SCONN,HA!!!F220!BA(0)!!!!
S!M_A_BA<1>!J6T1!224!@baseboard_fab2_lib.baseboard_fab2(sch_1):page44_i13@mstr_sconn.sconn288_h44441003(chips)!SCONN288_H44441003_PIP-SCONN,HA!!!F220!BA(1)!!!!
S!M_A_BG<0>!J6T1!63!@baseboard_fab2_lib.baseboard_fab2(sch_1):page44_i13@mstr_sconn.sconn288_h44441003(chips)!SCONN288_H44441003_PIP-SCONN,HA!!!F220!BG(0)!!!!
S!M_A_BG<1>!J6T1!207!@baseboard_fab2_lib.baseboard_fab2(sch_1):page44_i13@mstr_sconn.sconn288_h44441003(chips)!SCONN288_H44441003_PIP-SCONN,HA!!!F220!BG(1)!!!!
S!M_A_C<2>!J6T1!235!@baseboard_fab2_lib.baseboard_fab2(sch_1):page44_i13@mstr_sconn.sconn288_h44441003(chips)!SCONN288_H44441003_PIP-SCONN,HA!!!F220!C(2)!!!!
S!M_A_ECC<0>!J6T1!49!@baseboard_fab2_lib.baseboard_fab2(sch_1):page44_i13@mstr_sconn.sconn288_h44441003(chips)!SCONN288_H44441003_PIP-SCONN,HA!!!F220!CB(0)!!!!
S!M_A_ECC<1>!J6T1!194!@baseboard_fab2_lib.baseboard_fab2(sch_1):page44_i13@mstr_sconn.sconn288_h44441003(chips)!SCONN288_H44441003_PIP-SCONN,HA!!!F220!CB(1)!!!!
S!M_A_ECC<2>!J6T1!56!@baseboard_fab2_lib.baseboard_fab2(sch_1):page44_i13@mstr_sconn.sconn288_h44441003(chips)!SCONN288_H44441003_PIP-SCONN,HA!!!F220!CB(2)!!!!
S!M_A_ECC<3>!J6T1!201!@baseboard_fab2_lib.baseboard_fab2(sch_1):page44_i13@mstr_sconn.sconn288_h44441003(chips)!SCONN288_H44441003_PIP-SCONN,HA!!!F220!CB(3)!!!!
S!M_A_ECC<4>!J6T1!47!@baseboard_fab2_lib.baseboard_fab2(sch_1):page44_i13@mstr_sconn.sconn288_h44441003(chips)!SCONN288_H44441003_PIP-SCONN,HA!!!F220!CB(4)!!!!
S!M_A_ECC<5>!J6T1!192!@baseboard_fab2_lib.baseboard_fab2(sch_1):page44_i13@mstr_sconn.sconn288_h44441003(chips)!SCONN288_H44441003_PIP-SCONN,HA!!!F220!CB(5)!!!!
S!M_A_ECC<6>!J6T1!54!@baseboard_fab2_lib.baseboard_fab2(sch_1):page44_i13@mstr_sconn.sconn288_h44441003(chips)!SCONN288_H44441003_PIP-SCONN,HA!!!F220!CB(6)!!!!
S!M_A_ECC<7>!J6T1!199!@baseboard_fab2_lib.baseboard_fab2(sch_1):page44_i13@mstr_sconn.sconn288_h44441003(chips)!SCONN288_H44441003_PIP-SCONN,HA!!!F220!CB(7)!!!!
S!M_A_CLK_DN<2>!J6T1!75!@baseboard_fab2_lib.baseboard_fab2(sch_1):page44_i13@mstr_sconn.sconn288_h44441003(chips)!SCONN288_H44441003_PIP-SCONN,HA!!!F220!CK0N!!!!
S!M_A_CLK_DP<2>!J6T1!74!@baseboard_fab2_lib.baseboard_fab2(sch_1):page44_i13@mstr_sconn.sconn288_h44441003(chips)!SCONN288_H44441003_PIP-SCONN,HA!!!F220!CK0P!!!!
S!M_A_CLK_DN<3>!J6T1!219!@baseboard_fab2_lib.baseboard_fab2(sch_1):page44_i13@mstr_sconn.sconn288_h44441003(chips)!SCONN288_H44441003_PIP-SCONN,HA!!!F220!CK1N!!!!
S!M_A_CLK_DP<3>!J6T1!218!@baseboard_fab2_lib.baseboard_fab2(sch_1):page44_i13@mstr_sconn.sconn288_h44441003(chips)!SCONN288_H44441003_PIP-SCONN,HA!!!F220!CK1P!!!!
S!M_A_CKE<2>!J6T1!60!@baseboard_fab2_lib.baseboard_fab2(sch_1):page44_i13@mstr_sconn.sconn288_h44441003(chips)!SCONN288_H44441003_PIP-SCONN,HA!!!F220!CKE(0)!!!!
S!M_A_CKE<3>!J6T1!203!@baseboard_fab2_lib.baseboard_fab2(sch_1):page44_i13@mstr_sconn.sconn288_h44441003(chips)!SCONN288_H44441003_PIP-SCONN,HA!!!F220!CKE(1)!!!!
S!M_A_DQ<0>!J6T1!5!@baseboard_fab2_lib.baseboard_fab2(sch_1):page44_i13@mstr_sconn.sconn288_h44441003(chips)!SCONN288_H44441003_PIP-SCONN,HA!!!F220!DQ(0)!!!!
S!M_A_DQ<10>!J6T1!23!@baseboard_fab2_lib.baseboard_fab2(sch_1):page44_i13@mstr_sconn.sconn288_h44441003(chips)!SCONN288_H44441003_PIP-SCONN,HA!!!F220!DQ(10)!!!!
S!M_A_DQ<11>!J6T1!168!@baseboard_fab2_lib.baseboard_fab2(sch_1):page44_i13@mstr_sconn.sconn288_h44441003(chips)!SCONN288_H44441003_PIP-SCONN,HA!!!F220!DQ(11)!!!!
S!M_A_DQ<12>!J6T1!14!@baseboard_fab2_lib.baseboard_fab2(sch_1):page44_i13@mstr_sconn.sconn288_h44441003(chips)!SCONN288_H44441003_PIP-SCONN,HA!!!F220!DQ(12)!!!!
S!M_A_DQ<13>!J6T1!159!@baseboard_fab2_lib.baseboard_fab2(sch_1):page44_i13@mstr_sconn.sconn288_h44441003(chips)!SCONN288_H44441003_PIP-SCONN,HA!!!F220!DQ(13)!!!!
S!M_A_DQ<14>!J6T1!21!@baseboard_fab2_lib.baseboard_fab2(sch_1):page44_i13@mstr_sconn.sconn288_h44441003(chips)!SCONN288_H44441003_PIP-SCONN,HA!!!F220!DQ(14)!!!!
S!M_A_DQ<15>!J6T1!166!@baseboard_fab2_lib.baseboard_fab2(sch_1):page44_i13@mstr_sconn.sconn288_h44441003(chips)!SCONN288_H44441003_PIP-SCONN,HA!!!F220!DQ(15)!!!!
S!M_A_DQ<16>!J6T1!27!@baseboard_fab2_lib.baseboard_fab2(sch_1):page44_i13@mstr_sconn.sconn288_h44441003(chips)!SCONN288_H44441003_PIP-SCONN,HA!!!F220!DQ(16)!!!!
S!M_A_DQ<17>!J6T1!172!@baseboard_fab2_lib.baseboard_fab2(sch_1):page44_i13@mstr_sconn.sconn288_h44441003(chips)!SCONN288_H44441003_PIP-SCONN,HA!!!F220!DQ(17)!!!!
S!M_A_DQ<18>!J6T1!34!@baseboard_fab2_lib.baseboard_fab2(sch_1):page44_i13@mstr_sconn.sconn288_h44441003(chips)!SCONN288_H44441003_PIP-SCONN,HA!!!F220!DQ(18)!!!!
S!M_A_DQ<19>!J6T1!179!@baseboard_fab2_lib.baseboard_fab2(sch_1):page44_i13@mstr_sconn.sconn288_h44441003(chips)!SCONN288_H44441003_PIP-SCONN,HA!!!F220!DQ(19)!!!!
S!M_A_DQ<1>!J6T1!150!@baseboard_fab2_lib.baseboard_fab2(sch_1):page44_i13@mstr_sconn.sconn288_h44441003(chips)!SCONN288_H44441003_PIP-SCONN,HA!!!F220!DQ(1)!!!!
S!M_A_DQ<20>!J6T1!25!@baseboard_fab2_lib.baseboard_fab2(sch_1):page44_i13@mstr_sconn.sconn288_h44441003(chips)!SCONN288_H44441003_PIP-SCONN,HA!!!F220!DQ(20)!!!!
S!M_A_DQ<21>!J6T1!170!@baseboard_fab2_lib.baseboard_fab2(sch_1):page44_i13@mstr_sconn.sconn288_h44441003(chips)!SCONN288_H44441003_PIP-SCONN,HA!!!F220!DQ(21)!!!!
S!M_A_DQ<22>!J6T1!32!@baseboard_fab2_lib.baseboard_fab2(sch_1):page44_i13@mstr_sconn.sconn288_h44441003(chips)!SCONN288_H44441003_PIP-SCONN,HA!!!F220!DQ(22)!!!!
S!M_A_DQ<23>!J6T1!177!@baseboard_fab2_lib.baseboard_fab2(sch_1):page44_i13@mstr_sconn.sconn288_h44441003(chips)!SCONN288_H44441003_PIP-SCONN,HA!!!F220!DQ(23)!!!!
S!M_A_DQ<24>!J6T1!38!@baseboard_fab2_lib.baseboard_fab2(sch_1):page44_i13@mstr_sconn.sconn288_h44441003(chips)!SCONN288_H44441003_PIP-SCONN,HA!!!F220!DQ(24)!!!!
S!M_A_DQ<25>!J6T1!183!@baseboard_fab2_lib.baseboard_fab2(sch_1):page44_i13@mstr_sconn.sconn288_h44441003(chips)!SCONN288_H44441003_PIP-SCONN,HA!!!F220!DQ(25)!!!!
S!M_A_DQ<26>!J6T1!45!@baseboard_fab2_lib.baseboard_fab2(sch_1):page44_i13@mstr_sconn.sconn288_h44441003(chips)!SCONN288_H44441003_PIP-SCONN,HA!!!F220!DQ(26)!!!!
S!M_A_DQ<27>!J6T1!190!@baseboard_fab2_lib.baseboard_fab2(sch_1):page44_i13@mstr_sconn.sconn288_h44441003(chips)!SCONN288_H44441003_PIP-SCONN,HA!!!F220!DQ(27)!!!!
S!M_A_DQ<28>!J6T1!36!@baseboard_fab2_lib.baseboard_fab2(sch_1):page44_i13@mstr_sconn.sconn288_h44441003(chips)!SCONN288_H44441003_PIP-SCONN,HA!!!F220!DQ(28)!!!!
S!M_A_DQ<29>!J6T1!181!@baseboard_fab2_lib.baseboard_fab2(sch_1):page44_i13@mstr_sconn.sconn288_h44441003(chips)!SCONN288_H44441003_PIP-SCONN,HA!!!F220!DQ(29)!!!!
S!M_A_DQ<2>!J6T1!12!@baseboard_fab2_lib.baseboard_fab2(sch_1):page44_i13@mstr_sconn.sconn288_h44441003(chips)!SCONN288_H44441003_PIP-SCONN,HA!!!F220!DQ(2)!!!!
S!M_A_DQ<30>!J6T1!43!@baseboard_fab2_lib.baseboard_fab2(sch_1):page44_i13@mstr_sconn.sconn288_h44441003(chips)!SCONN288_H44441003_PIP-SCONN,HA!!!F220!DQ(30)!!!!
S!M_A_DQ<31>!J6T1!188!@baseboard_fab2_lib.baseboard_fab2(sch_1):page44_i13@mstr_sconn.sconn288_h44441003(chips)!SCONN288_H44441003_PIP-SCONN,HA!!!F220!DQ(31)!!!!
S!M_A_DQ<32>!J6T1!97!@baseboard_fab2_lib.baseboard_fab2(sch_1):page44_i13@mstr_sconn.sconn288_h44441003(chips)!SCONN288_H44441003_PIP-SCONN,HA!!!F220!DQ(32)!!!!
S!M_A_DQ<33>!J6T1!242!@baseboard_fab2_lib.baseboard_fab2(sch_1):page44_i13@mstr_sconn.sconn288_h44441003(chips)!SCONN288_H44441003_PIP-SCONN,HA!!!F220!DQ(33)!!!!
S!M_A_DQ<34>!J6T1!104!@baseboard_fab2_lib.baseboard_fab2(sch_1):page44_i13@mstr_sconn.sconn288_h44441003(chips)!SCONN288_H44441003_PIP-SCONN,HA!!!F220!DQ(34)!!!!
S!M_A_DQ<35>!J6T1!249!@baseboard_fab2_lib.baseboard_fab2(sch_1):page44_i13@mstr_sconn.sconn288_h44441003(chips)!SCONN288_H44441003_PIP-SCONN,HA!!!F220!DQ(35)!!!!
S!M_A_DQ<36>!J6T1!95!@baseboard_fab2_lib.baseboard_fab2(sch_1):page44_i13@mstr_sconn.sconn288_h44441003(chips)!SCONN288_H44441003_PIP-SCONN,HA!!!F220!DQ(36)!!!!
S!M_A_DQ<37>!J6T1!240!@baseboard_fab2_lib.baseboard_fab2(sch_1):page44_i13@mstr_sconn.sconn288_h44441003(chips)!SCONN288_H44441003_PIP-SCONN,HA!!!F220!DQ(37)!!!!
S!M_A_DQ<38>!J6T1!102!@baseboard_fab2_lib.baseboard_fab2(sch_1):page44_i13@mstr_sconn.sconn288_h44441003(chips)!SCONN288_H44441003_PIP-SCONN,HA!!!F220!DQ(38)!!!!
S!M_A_DQ<39>!J6T1!247!@baseboard_fab2_lib.baseboard_fab2(sch_1):page44_i13@mstr_sconn.sconn288_h44441003(chips)!SCONN288_H44441003_PIP-SCONN,HA!!!F220!DQ(39)!!!!
S!M_A_DQ<3>!J6T1!157!@baseboard_fab2_lib.baseboard_fab2(sch_1):page44_i13@mstr_sconn.sconn288_h44441003(chips)!SCONN288_H44441003_PIP-SCONN,HA!!!F220!DQ(3)!!!!
S!M_A_DQ<40>!J6T1!108!@baseboard_fab2_lib.baseboard_fab2(sch_1):page44_i13@mstr_sconn.sconn288_h44441003(chips)!SCONN288_H44441003_PIP-SCONN,HA!!!F220!DQ(40)!!!!
S!M_A_DQ<41>!J6T1!253!@baseboard_fab2_lib.baseboard_fab2(sch_1):page44_i13@mstr_sconn.sconn288_h44441003(chips)!SCONN288_H44441003_PIP-SCONN,HA!!!F220!DQ(41)!!!!
S!M_A_DQ<42>!J6T1!115!@baseboard_fab2_lib.baseboard_fab2(sch_1):page44_i13@mstr_sconn.sconn288_h44441003(chips)!SCONN288_H44441003_PIP-SCONN,HA!!!F220!DQ(42)!!!!
S!M_A_DQ<43>!J6T1!260!@baseboard_fab2_lib.baseboard_fab2(sch_1):page44_i13@mstr_sconn.sconn288_h44441003(chips)!SCONN288_H44441003_PIP-SCONN,HA!!!F220!DQ(43)!!!!
S!M_A_DQ<44>!J6T1!106!@baseboard_fab2_lib.baseboard_fab2(sch_1):page44_i13@mstr_sconn.sconn288_h44441003(chips)!SCONN288_H44441003_PIP-SCONN,HA!!!F220!DQ(44)!!!!
S!M_A_DQ<45>!J6T1!251!@baseboard_fab2_lib.baseboard_fab2(sch_1):page44_i13@mstr_sconn.sconn288_h44441003(chips)!SCONN288_H44441003_PIP-SCONN,HA!!!F220!DQ(45)!!!!
S!M_A_DQ<46>!J6T1!113!@baseboard_fab2_lib.baseboard_fab2(sch_1):page44_i13@mstr_sconn.sconn288_h44441003(chips)!SCONN288_H44441003_PIP-SCONN,HA!!!F220!DQ(46)!!!!
S!M_A_DQ<47>!J6T1!258!@baseboard_fab2_lib.baseboard_fab2(sch_1):page44_i13@mstr_sconn.sconn288_h44441003(chips)!SCONN288_H44441003_PIP-SCONN,HA!!!F220!DQ(47)!!!!
S!M_A_DQ<48>!J6T1!119!@baseboard_fab2_lib.baseboard_fab2(sch_1):page44_i13@mstr_sconn.sconn288_h44441003(chips)!SCONN288_H44441003_PIP-SCONN,HA!!!F220!DQ(48)!!!!
S!M_A_DQ<49>!J6T1!264!@baseboard_fab2_lib.baseboard_fab2(sch_1):page44_i13@mstr_sconn.sconn288_h44441003(chips)!SCONN288_H44441003_PIP-SCONN,HA!!!F220!DQ(49)!!!!
S!M_A_DQ<4>!J6T1!3!@baseboard_fab2_lib.baseboard_fab2(sch_1):page44_i13@mstr_sconn.sconn288_h44441003(chips)!SCONN288_H44441003_PIP-SCONN,HA!!!F220!DQ(4)!!!!
S!M_A_DQ<50>!J6T1!126!@baseboard_fab2_lib.baseboard_fab2(sch_1):page44_i13@mstr_sconn.sconn288_h44441003(chips)!SCONN288_H44441003_PIP-SCONN,HA!!!F220!DQ(50)!!!!
S!M_A_DQ<51>!J6T1!271!@baseboard_fab2_lib.baseboard_fab2(sch_1):page44_i13@mstr_sconn.sconn288_h44441003(chips)!SCONN288_H44441003_PIP-SCONN,HA!!!F220!DQ(51)!!!!
S!M_A_DQ<52>!J6T1!117!@baseboard_fab2_lib.baseboard_fab2(sch_1):page44_i13@mstr_sconn.sconn288_h44441003(chips)!SCONN288_H44441003_PIP-SCONN,HA!!!F220!DQ(52)!!!!
S!M_A_DQ<53>!J6T1!262!@baseboard_fab2_lib.baseboard_fab2(sch_1):page44_i13@mstr_sconn.sconn288_h44441003(chips)!SCONN288_H44441003_PIP-SCONN,HA!!!F220!DQ(53)!!!!
S!M_A_DQ<54>!J6T1!124!@baseboard_fab2_lib.baseboard_fab2(sch_1):page44_i13@mstr_sconn.sconn288_h44441003(chips)!SCONN288_H44441003_PIP-SCONN,HA!!!F220!DQ(54)!!!!
S!M_A_DQ<55>!J6T1!269!@baseboard_fab2_lib.baseboard_fab2(sch_1):page44_i13@mstr_sconn.sconn288_h44441003(chips)!SCONN288_H44441003_PIP-SCONN,HA!!!F220!DQ(55)!!!!
S!M_A_DQ<56>!J6T1!130!@baseboard_fab2_lib.baseboard_fab2(sch_1):page44_i13@mstr_sconn.sconn288_h44441003(chips)!SCONN288_H44441003_PIP-SCONN,HA!!!F220!DQ(56)!!!!
S!M_A_DQ<57>!J6T1!275!@baseboard_fab2_lib.baseboard_fab2(sch_1):page44_i13@mstr_sconn.sconn288_h44441003(chips)!SCONN288_H44441003_PIP-SCONN,HA!!!F220!DQ(57)!!!!
S!M_A_DQ<58>!J6T1!137!@baseboard_fab2_lib.baseboard_fab2(sch_1):page44_i13@mstr_sconn.sconn288_h44441003(chips)!SCONN288_H44441003_PIP-SCONN,HA!!!F220!DQ(58)!!!!
S!M_A_DQ<59>!J6T1!282!@baseboard_fab2_lib.baseboard_fab2(sch_1):page44_i13@mstr_sconn.sconn288_h44441003(chips)!SCONN288_H44441003_PIP-SCONN,HA!!!F220!DQ(59)!!!!
S!M_A_DQ<5>!J6T1!148!@baseboard_fab2_lib.baseboard_fab2(sch_1):page44_i13@mstr_sconn.sconn288_h44441003(chips)!SCONN288_H44441003_PIP-SCONN,HA!!!F220!DQ(5)!!!!
S!M_A_DQ<60>!J6T1!128!@baseboard_fab2_lib.baseboard_fab2(sch_1):page44_i13@mstr_sconn.sconn288_h44441003(chips)!SCONN288_H44441003_PIP-SCONN,HA!!!F220!DQ(60)!!!!
S!M_A_DQ<61>!J6T1!273!@baseboard_fab2_lib.baseboard_fab2(sch_1):page44_i13@mstr_sconn.sconn288_h44441003(chips)!SCONN288_H44441003_PIP-SCONN,HA!!!F220!DQ(61)!!!!
S!M_A_DQ<62>!J6T1!135!@baseboard_fab2_lib.baseboard_fab2(sch_1):page44_i13@mstr_sconn.sconn288_h44441003(chips)!SCONN288_H44441003_PIP-SCONN,HA!!!F220!DQ(62)!!!!
S!M_A_DQ<63>!J6T1!280!@baseboard_fab2_lib.baseboard_fab2(sch_1):page44_i13@mstr_sconn.sconn288_h44441003(chips)!SCONN288_H44441003_PIP-SCONN,HA!!!F220!DQ(63)!!!!
S!M_A_DQ<6>!J6T1!10!@baseboard_fab2_lib.baseboard_fab2(sch_1):page44_i13@mstr_sconn.sconn288_h44441003(chips)!SCONN288_H44441003_PIP-SCONN,HA!!!F220!DQ(6)!!!!
S!M_A_DQ<7>!J6T1!155!@baseboard_fab2_lib.baseboard_fab2(sch_1):page44_i13@mstr_sconn.sconn288_h44441003(chips)!SCONN288_H44441003_PIP-SCONN,HA!!!F220!DQ(7)!!!!
S!M_A_DQ<8>!J6T1!16!@baseboard_fab2_lib.baseboard_fab2(sch_1):page44_i13@mstr_sconn.sconn288_h44441003(chips)!SCONN288_H44441003_PIP-SCONN,HA!!!F220!DQ(8)!!!!
S!M_A_DQ<9>!J6T1!161!@baseboard_fab2_lib.baseboard_fab2(sch_1):page44_i13@mstr_sconn.sconn288_h44441003(chips)!SCONN288_H44441003_PIP-SCONN,HA!!!F220!DQ(9)!!!!
S!FM_DIMM_EVENT_COD_N!J6T1!78!@baseboard_fab2_lib.baseboard_fab2(sch_1):page44_i13@mstr_sconn.sconn288_h44441003(chips)!SCONN288_H44441003_PIP-SCONN,HA!!!F220!EVENT_N!!!!
S!M_A_ODT<2>!J6T1!87!@baseboard_fab2_lib.baseboard_fab2(sch_1):page44_i13@mstr_sconn.sconn288_h44441003(chips)!SCONN288_H44441003_PIP-SCONN,HA!!!F220!ODT(0)!!!!
S!M_A_ODT<3>!J6T1!91!@baseboard_fab2_lib.baseboard_fab2(sch_1):page44_i13@mstr_sconn.sconn288_h44441003(chips)!SCONN288_H44441003_PIP-SCONN,HA!!!F220!ODT(1)!!!!
S!M_A_PAR!J6T1!222!@baseboard_fab2_lib.baseboard_fab2(sch_1):page44_i13@mstr_sconn.sconn288_h44441003(chips)!SCONN288_H44441003_PIP-SCONN,HA!!!F220!PAR!!!!
S!M_ABC_RST_N!J6T1!58!@baseboard_fab2_lib.baseboard_fab2(sch_1):page44_i13@mstr_sconn.sconn288_h44441003(chips)!SCONN288_H44441003_PIP-SCONN,HA!!!F220!RESET_N!!!!
S!TP_CH_A_DIMM_A1_RFU_0!J6T1!205!@baseboard_fab2_lib.baseboard_fab2(sch_1):page44_i13@mstr_sconn.sconn288_h44441003(chips)!SCONN288_H44441003_PIP-SCONN,HA!!!F220!RFU(0)!!!!
S!TP_CH_A_DIMM_A1_RFU_1!J6T1!227!@baseboard_fab2_lib.baseboard_fab2(sch_1):page44_i13@mstr_sconn.sconn288_h44441003(chips)!SCONN288_H44441003_PIP-SCONN,HA!!!F220!RFU(1)!!!!
S!TP_CH_A_DIMM_A1_RFU_2!J6T1!144!@baseboard_fab2_lib.baseboard_fab2(sch_1):page44_i13@mstr_sconn.sconn288_h44441003(chips)!SCONN288_H44441003_PIP-SCONN,HA!!!F220!RFU(2)!!!!
S!M_A_CS_N<4>!J6T1!84!@baseboard_fab2_lib.baseboard_fab2(sch_1):page44_i13@mstr_sconn.sconn288_h44441003(chips)!SCONN288_H44441003_PIP-SCONN,HA!!!F220!S0_N!!!!
S!M_A_CS_N<5>!J6T1!89!@baseboard_fab2_lib.baseboard_fab2(sch_1):page44_i13@mstr_sconn.sconn288_h44441003(chips)!SCONN288_H44441003_PIP-SCONN,HA!!!F220!S1_N!!!!
S!M_A_CS_N<6>!J6T1!93!@baseboard_fab2_lib.baseboard_fab2(sch_1):page44_i13@mstr_sconn.sconn288_h44441003(chips)!SCONN288_H44441003_PIP-SCONN,HA!!!F220!S2_N_C(0)!!!!
S!M_A_CS_N<7>!J6T1!237!@baseboard_fab2_lib.baseboard_fab2(sch_1):page44_i13@mstr_sconn.sconn288_h44441003(chips)!SCONN288_H44441003_PIP-SCONN,HA!!!F220!S3_N_C(1)!!!!
S!PVPP_ABC!J6T1!139!@baseboard_fab2_lib.baseboard_fab2(sch_1):page44_i13@mstr_sconn.sconn288_h44441003(chips)!SCONN288_H44441003_PIP-SCONN,HA!!!F220!SA(0)!!!!
S!GND!J6T1!140!@baseboard_fab2_lib.baseboard_fab2(sch_1):page44_i13@mstr_sconn.sconn288_h44441003(chips)!SCONN288_H44441003_PIP-SCONN,HA!!!F220!SA(1)!!!!
S!GND!J6T1!238!@baseboard_fab2_lib.baseboard_fab2(sch_1):page44_i13@mstr_sconn.sconn288_h44441003(chips)!SCONN288_H44441003_PIP-SCONN,HA!!!F220!SA(2)!!!!
S!FM_ADR_COMPLETE_ABC_N!J6T1!230!@baseboard_fab2_lib.baseboard_fab2(sch_1):page44_i13@mstr_sconn.sconn288_h44441003(chips)!SCONN288_H44441003_PIP-SCONN,HA!!!F220!SAVE_N_NC!!!!
S!SMB_DDR_ABC_VPP_SCL!J6T1!141!@baseboard_fab2_lib.baseboard_fab2(sch_1):page44_i13@mstr_sconn.sconn288_h44441003(chips)!SCONN288_H44441003_PIP-SCONN,HA!!!F220!SCL!!!!
S!SMB_DDR_ABC_VPP_SDA!J6T1!285!@baseboard_fab2_lib.baseboard_fab2(sch_1):page44_i13@mstr_sconn.sconn288_h44441003(chips)!SCONN288_H44441003_PIP-SCONN,HA!!!F220!SDA!!!!
S!PVPP_ABC!J6T1!284!@baseboard_fab2_lib.baseboard_fab2(sch_1):page44_i13@mstr_sconn.sconn288_h44441003(chips)!SCONN288_H44441003_PIP-SCONN,HA!!!F220!VDDSPD!!!!
S!M_A_VREF!J6T1!146!@baseboard_fab2_lib.baseboard_fab2(sch_1):page44_i13@mstr_sconn.sconn288_h44441003(chips)!SCONN288_H44441003_PIP-SCONN,HA!!!F220!VREFCA!!!!
S!M_A_DQS_DN<0>!J6T1!152!@baseboard_fab2_lib.baseboard_fab2(sch_1):page44_i120@mstr_sconn.sconn288_h44441003(chips)!SCONN288_H44441003_PIP-SCONN,HA!!!F219!DQS0N!!!!
S!M_A_DQS_DP<0>!J6T1!153!@baseboard_fab2_lib.baseboard_fab2(sch_1):page44_i120@mstr_sconn.sconn288_h44441003(chips)!SCONN288_H44441003_PIP-SCONN,HA!!!F219!DQS0P!!!!
S!M_A_DQS_DN<10>!J6T1!19!@baseboard_fab2_lib.baseboard_fab2(sch_1):page44_i120@mstr_sconn.sconn288_h44441003(chips)!SCONN288_H44441003_PIP-SCONN,HA!!!F219!DQS10N!!!!
S!M_A_DQS_DP<10>!J6T1!18!@baseboard_fab2_lib.baseboard_fab2(sch_1):page44_i120@mstr_sconn.sconn288_h44441003(chips)!SCONN288_H44441003_PIP-SCONN,HA!!!F219!DQS10P!!!!
S!M_A_DQS_DN<11>!J6T1!30!@baseboard_fab2_lib.baseboard_fab2(sch_1):page44_i120@mstr_sconn.sconn288_h44441003(chips)!SCONN288_H44441003_PIP-SCONN,HA!!!F219!DQS11N!!!!
S!M_A_DQS_DP<11>!J6T1!29!@baseboard_fab2_lib.baseboard_fab2(sch_1):page44_i120@mstr_sconn.sconn288_h44441003(chips)!SCONN288_H44441003_PIP-SCONN,HA!!!F219!DQS11P!!!!
S!M_A_DQS_DN<12>!J6T1!41!@baseboard_fab2_lib.baseboard_fab2(sch_1):page44_i120@mstr_sconn.sconn288_h44441003(chips)!SCONN288_H44441003_PIP-SCONN,HA!!!F219!DQS12N!!!!
S!M_A_DQS_DP<12>!J6T1!40!@baseboard_fab2_lib.baseboard_fab2(sch_1):page44_i120@mstr_sconn.sconn288_h44441003(chips)!SCONN288_H44441003_PIP-SCONN,HA!!!F219!DQS12P!!!!
S!M_A_DQS_DN<13>!J6T1!100!@baseboard_fab2_lib.baseboard_fab2(sch_1):page44_i120@mstr_sconn.sconn288_h44441003(chips)!SCONN288_H44441003_PIP-SCONN,HA!!!F219!DQS13N!!!!
S!M_A_DQS_DP<13>!J6T1!99!@baseboard_fab2_lib.baseboard_fab2(sch_1):page44_i120@mstr_sconn.sconn288_h44441003(chips)!SCONN288_H44441003_PIP-SCONN,HA!!!F219!DQS13P!!!!
S!M_A_DQS_DN<14>!J6T1!111!@baseboard_fab2_lib.baseboard_fab2(sch_1):page44_i120@mstr_sconn.sconn288_h44441003(chips)!SCONN288_H44441003_PIP-SCONN,HA!!!F219!DQS14N!!!!
S!M_A_DQS_DP<14>!J6T1!110!@baseboard_fab2_lib.baseboard_fab2(sch_1):page44_i120@mstr_sconn.sconn288_h44441003(chips)!SCONN288_H44441003_PIP-SCONN,HA!!!F219!DQS14P!!!!
S!M_A_DQS_DN<15>!J6T1!122!@baseboard_fab2_lib.baseboard_fab2(sch_1):page44_i120@mstr_sconn.sconn288_h44441003(chips)!SCONN288_H44441003_PIP-SCONN,HA!!!F219!DQS15N!!!!
S!M_A_DQS_DP<15>!J6T1!121!@baseboard_fab2_lib.baseboard_fab2(sch_1):page44_i120@mstr_sconn.sconn288_h44441003(chips)!SCONN288_H44441003_PIP-SCONN,HA!!!F219!DQS15P!!!!
S!M_A_DQS_DN<16>!J6T1!133!@baseboard_fab2_lib.baseboard_fab2(sch_1):page44_i120@mstr_sconn.sconn288_h44441003(chips)!SCONN288_H44441003_PIP-SCONN,HA!!!F219!DQS16N!!!!
S!M_A_DQS_DP<16>!J6T1!132!@baseboard_fab2_lib.baseboard_fab2(sch_1):page44_i120@mstr_sconn.sconn288_h44441003(chips)!SCONN288_H44441003_PIP-SCONN,HA!!!F219!DQS16P!!!!
S!M_A_DQS_DN<17>!J6T1!52!@baseboard_fab2_lib.baseboard_fab2(sch_1):page44_i120@mstr_sconn.sconn288_h44441003(chips)!SCONN288_H44441003_PIP-SCONN,HA!!!F219!DQS17N!!!!
S!M_A_DQS_DP<17>!J6T1!51!@baseboard_fab2_lib.baseboard_fab2(sch_1):page44_i120@mstr_sconn.sconn288_h44441003(chips)!SCONN288_H44441003_PIP-SCONN,HA!!!F219!DQS17P!!!!
S!M_A_DQS_DN<1>!J6T1!163!@baseboard_fab2_lib.baseboard_fab2(sch_1):page44_i120@mstr_sconn.sconn288_h44441003(chips)!SCONN288_H44441003_PIP-SCONN,HA!!!F219!DQS1N!!!!
S!M_A_DQS_DP<1>!J6T1!164!@baseboard_fab2_lib.baseboard_fab2(sch_1):page44_i120@mstr_sconn.sconn288_h44441003(chips)!SCONN288_H44441003_PIP-SCONN,HA!!!F219!DQS1P!!!!
S!M_A_DQS_DN<2>!J6T1!174!@baseboard_fab2_lib.baseboard_fab2(sch_1):page44_i120@mstr_sconn.sconn288_h44441003(chips)!SCONN288_H44441003_PIP-SCONN,HA!!!F219!DQS2N!!!!
S!M_A_DQS_DP<2>!J6T1!175!@baseboard_fab2_lib.baseboard_fab2(sch_1):page44_i120@mstr_sconn.sconn288_h44441003(chips)!SCONN288_H44441003_PIP-SCONN,HA!!!F219!DQS2P!!!!
S!M_A_DQS_DN<3>!J6T1!185!@baseboard_fab2_lib.baseboard_fab2(sch_1):page44_i120@mstr_sconn.sconn288_h44441003(chips)!SCONN288_H44441003_PIP-SCONN,HA!!!F219!DQS3N!!!!
S!M_A_DQS_DP<3>!J6T1!186!@baseboard_fab2_lib.baseboard_fab2(sch_1):page44_i120@mstr_sconn.sconn288_h44441003(chips)!SCONN288_H44441003_PIP-SCONN,HA!!!F219!DQS3P!!!!
S!M_A_DQS_DN<4>!J6T1!244!@baseboard_fab2_lib.baseboard_fab2(sch_1):page44_i120@mstr_sconn.sconn288_h44441003(chips)!SCONN288_H44441003_PIP-SCONN,HA!!!F219!DQS4N!!!!
S!M_A_DQS_DP<4>!J6T1!245!@baseboard_fab2_lib.baseboard_fab2(sch_1):page44_i120@mstr_sconn.sconn288_h44441003(chips)!SCONN288_H44441003_PIP-SCONN,HA!!!F219!DQS4P!!!!
S!M_A_DQS_DN<5>!J6T1!255!@baseboard_fab2_lib.baseboard_fab2(sch_1):page44_i120@mstr_sconn.sconn288_h44441003(chips)!SCONN288_H44441003_PIP-SCONN,HA!!!F219!DQS5N!!!!
S!M_A_DQS_DP<5>!J6T1!256!@baseboard_fab2_lib.baseboard_fab2(sch_1):page44_i120@mstr_sconn.sconn288_h44441003(chips)!SCONN288_H44441003_PIP-SCONN,HA!!!F219!DQS5P!!!!
S!M_A_DQS_DN<6>!J6T1!266!@baseboard_fab2_lib.baseboard_fab2(sch_1):page44_i120@mstr_sconn.sconn288_h44441003(chips)!SCONN288_H44441003_PIP-SCONN,HA!!!F219!DQS6N!!!!
S!M_A_DQS_DP<6>!J6T1!267!@baseboard_fab2_lib.baseboard_fab2(sch_1):page44_i120@mstr_sconn.sconn288_h44441003(chips)!SCONN288_H44441003_PIP-SCONN,HA!!!F219!DQS6P!!!!
S!M_A_DQS_DN<7>!J6T1!277!@baseboard_fab2_lib.baseboard_fab2(sch_1):page44_i120@mstr_sconn.sconn288_h44441003(chips)!SCONN288_H44441003_PIP-SCONN,HA!!!F219!DQS7N!!!!
S!M_A_DQS_DP<7>!J6T1!278!@baseboard_fab2_lib.baseboard_fab2(sch_1):page44_i120@mstr_sconn.sconn288_h44441003(chips)!SCONN288_H44441003_PIP-SCONN,HA!!!F219!DQS7P!!!!
S!M_A_DQS_DN<8>!J6T1!196!@baseboard_fab2_lib.baseboard_fab2(sch_1):page44_i120@mstr_sconn.sconn288_h44441003(chips)!SCONN288_H44441003_PIP-SCONN,HA!!!F219!DQS8N!!!!
S!M_A_DQS_DP<8>!J6T1!197!@baseboard_fab2_lib.baseboard_fab2(sch_1):page44_i120@mstr_sconn.sconn288_h44441003(chips)!SCONN288_H44441003_PIP-SCONN,HA!!!F219!DQS8P!!!!
S!M_A_DQS_DN<9>!J6T1!8!@baseboard_fab2_lib.baseboard_fab2(sch_1):page44_i120@mstr_sconn.sconn288_h44441003(chips)!SCONN288_H44441003_PIP-SCONN,HA!!!F219!DQS9N!!!!
S!M_A_DQS_DP<9>!J6T1!7!@baseboard_fab2_lib.baseboard_fab2(sch_1):page44_i120@mstr_sconn.sconn288_h44441003(chips)!SCONN288_H44441003_PIP-SCONN,HA!!!F219!DQS9P!!!!
S!GND!J6T1!283!@baseboard_fab2_lib.baseboard_fab2(sch_1):page44_i139@mstr_sconn.sconn288_h44441003(chips)!SCONN288_H44441003_PIP-SCONN,HA!!!F218!VSS(0)!!!!
S!GND!J6T1!261!@baseboard_fab2_lib.baseboard_fab2(sch_1):page44_i139@mstr_sconn.sconn288_h44441003(chips)!SCONN288_H44441003_PIP-SCONN,HA!!!F218!VSS(10)!!!!
S!GND!J6T1!259!@baseboard_fab2_lib.baseboard_fab2(sch_1):page44_i139@mstr_sconn.sconn288_h44441003(chips)!SCONN288_H44441003_PIP-SCONN,HA!!!F218!VSS(11)!!!!
S!GND!J6T1!257!@baseboard_fab2_lib.baseboard_fab2(sch_1):page44_i139@mstr_sconn.sconn288_h44441003(chips)!SCONN288_H44441003_PIP-SCONN,HA!!!F218!VSS(12)!!!!
S!GND!J6T1!254!@baseboard_fab2_lib.baseboard_fab2(sch_1):page44_i139@mstr_sconn.sconn288_h44441003(chips)!SCONN288_H44441003_PIP-SCONN,HA!!!F218!VSS(13)!!!!
S!GND!J6T1!252!@baseboard_fab2_lib.baseboard_fab2(sch_1):page44_i139@mstr_sconn.sconn288_h44441003(chips)!SCONN288_H44441003_PIP-SCONN,HA!!!F218!VSS(14)!!!!
S!GND!J6T1!250!@baseboard_fab2_lib.baseboard_fab2(sch_1):page44_i139@mstr_sconn.sconn288_h44441003(chips)!SCONN288_H44441003_PIP-SCONN,HA!!!F218!VSS(15)!!!!
S!GND!J6T1!248!@baseboard_fab2_lib.baseboard_fab2(sch_1):page44_i139@mstr_sconn.sconn288_h44441003(chips)!SCONN288_H44441003_PIP-SCONN,HA!!!F218!VSS(16)!!!!
S!GND!J6T1!246!@baseboard_fab2_lib.baseboard_fab2(sch_1):page44_i139@mstr_sconn.sconn288_h44441003(chips)!SCONN288_H44441003_PIP-SCONN,HA!!!F218!VSS(17)!!!!
S!GND!J6T1!243!@baseboard_fab2_lib.baseboard_fab2(sch_1):page44_i139@mstr_sconn.sconn288_h44441003(chips)!SCONN288_H44441003_PIP-SCONN,HA!!!F218!VSS(18)!!!!
S!GND!J6T1!241!@baseboard_fab2_lib.baseboard_fab2(sch_1):page44_i139@mstr_sconn.sconn288_h44441003(chips)!SCONN288_H44441003_PIP-SCONN,HA!!!F218!VSS(19)!!!!
S!GND!J6T1!281!@baseboard_fab2_lib.baseboard_fab2(sch_1):page44_i139@mstr_sconn.sconn288_h44441003(chips)!SCONN288_H44441003_PIP-SCONN,HA!!!F218!VSS(1)!!!!
S!GND!J6T1!239!@baseboard_fab2_lib.baseboard_fab2(sch_1):page44_i139@mstr_sconn.sconn288_h44441003(chips)!SCONN288_H44441003_PIP-SCONN,HA!!!F218!VSS(20)!!!!
S!GND!J6T1!202!@baseboard_fab2_lib.baseboard_fab2(sch_1):page44_i139@mstr_sconn.sconn288_h44441003(chips)!SCONN288_H44441003_PIP-SCONN,HA!!!F218!VSS(21)!!!!
S!GND!J6T1!200!@baseboard_fab2_lib.baseboard_fab2(sch_1):page44_i139@mstr_sconn.sconn288_h44441003(chips)!SCONN288_H44441003_PIP-SCONN,HA!!!F218!VSS(22)!!!!
S!GND!J6T1!198!@baseboard_fab2_lib.baseboard_fab2(sch_1):page44_i139@mstr_sconn.sconn288_h44441003(chips)!SCONN288_H44441003_PIP-SCONN,HA!!!F218!VSS(23)!!!!
S!GND!J6T1!195!@baseboard_fab2_lib.baseboard_fab2(sch_1):page44_i139@mstr_sconn.sconn288_h44441003(chips)!SCONN288_H44441003_PIP-SCONN,HA!!!F218!VSS(24)!!!!
S!GND!J6T1!193!@baseboard_fab2_lib.baseboard_fab2(sch_1):page44_i139@mstr_sconn.sconn288_h44441003(chips)!SCONN288_H44441003_PIP-SCONN,HA!!!F218!VSS(25)!!!!
S!GND!J6T1!191!@baseboard_fab2_lib.baseboard_fab2(sch_1):page44_i139@mstr_sconn.sconn288_h44441003(chips)!SCONN288_H44441003_PIP-SCONN,HA!!!F218!VSS(26)!!!!
S!GND!J6T1!189!@baseboard_fab2_lib.baseboard_fab2(sch_1):page44_i139@mstr_sconn.sconn288_h44441003(chips)!SCONN288_H44441003_PIP-SCONN,HA!!!F218!VSS(27)!!!!
S!GND!J6T1!187!@baseboard_fab2_lib.baseboard_fab2(sch_1):page44_i139@mstr_sconn.sconn288_h44441003(chips)!SCONN288_H44441003_PIP-SCONN,HA!!!F218!VSS(28)!!!!
S!GND!J6T1!184!@baseboard_fab2_lib.baseboard_fab2(sch_1):page44_i139@mstr_sconn.sconn288_h44441003(chips)!SCONN288_H44441003_PIP-SCONN,HA!!!F218!VSS(29)!!!!
S!GND!J6T1!279!@baseboard_fab2_lib.baseboard_fab2(sch_1):page44_i139@mstr_sconn.sconn288_h44441003(chips)!SCONN288_H44441003_PIP-SCONN,HA!!!F218!VSS(2)!!!!
S!GND!J6T1!182!@baseboard_fab2_lib.baseboard_fab2(sch_1):page44_i139@mstr_sconn.sconn288_h44441003(chips)!SCONN288_H44441003_PIP-SCONN,HA!!!F218!VSS(30)!!!!
S!GND!J6T1!180!@baseboard_fab2_lib.baseboard_fab2(sch_1):page44_i139@mstr_sconn.sconn288_h44441003(chips)!SCONN288_H44441003_PIP-SCONN,HA!!!F218!VSS(31)!!!!
S!GND!J6T1!178!@baseboard_fab2_lib.baseboard_fab2(sch_1):page44_i139@mstr_sconn.sconn288_h44441003(chips)!SCONN288_H44441003_PIP-SCONN,HA!!!F218!VSS(32)!!!!
S!GND!J6T1!176!@baseboard_fab2_lib.baseboard_fab2(sch_1):page44_i139@mstr_sconn.sconn288_h44441003(chips)!SCONN288_H44441003_PIP-SCONN,HA!!!F218!VSS(33)!!!!
S!GND!J6T1!173!@baseboard_fab2_lib.baseboard_fab2(sch_1):page44_i139@mstr_sconn.sconn288_h44441003(chips)!SCONN288_H44441003_PIP-SCONN,HA!!!F218!VSS(34)!!!!
S!GND!J6T1!171!@baseboard_fab2_lib.baseboard_fab2(sch_1):page44_i139@mstr_sconn.sconn288_h44441003(chips)!SCONN288_H44441003_PIP-SCONN,HA!!!F218!VSS(35)!!!!
S!GND!J6T1!169!@baseboard_fab2_lib.baseboard_fab2(sch_1):page44_i139@mstr_sconn.sconn288_h44441003(chips)!SCONN288_H44441003_PIP-SCONN,HA!!!F218!VSS(36)!!!!
S!GND!J6T1!167!@baseboard_fab2_lib.baseboard_fab2(sch_1):page44_i139@mstr_sconn.sconn288_h44441003(chips)!SCONN288_H44441003_PIP-SCONN,HA!!!F218!VSS(37)!!!!
S!GND!J6T1!165!@baseboard_fab2_lib.baseboard_fab2(sch_1):page44_i139@mstr_sconn.sconn288_h44441003(chips)!SCONN288_H44441003_PIP-SCONN,HA!!!F218!VSS(38)!!!!
S!GND!J6T1!162!@baseboard_fab2_lib.baseboard_fab2(sch_1):page44_i139@mstr_sconn.sconn288_h44441003(chips)!SCONN288_H44441003_PIP-SCONN,HA!!!F218!VSS(39)!!!!
S!GND!J6T1!276!@baseboard_fab2_lib.baseboard_fab2(sch_1):page44_i139@mstr_sconn.sconn288_h44441003(chips)!SCONN288_H44441003_PIP-SCONN,HA!!!F218!VSS(3)!!!!
S!GND!J6T1!160!@baseboard_fab2_lib.baseboard_fab2(sch_1):page44_i139@mstr_sconn.sconn288_h44441003(chips)!SCONN288_H44441003_PIP-SCONN,HA!!!F218!VSS(40)!!!!
S!GND!J6T1!158!@baseboard_fab2_lib.baseboard_fab2(sch_1):page44_i139@mstr_sconn.sconn288_h44441003(chips)!SCONN288_H44441003_PIP-SCONN,HA!!!F218!VSS(41)!!!!
S!GND!J6T1!156!@baseboard_fab2_lib.baseboard_fab2(sch_1):page44_i139@mstr_sconn.sconn288_h44441003(chips)!SCONN288_H44441003_PIP-SCONN,HA!!!F218!VSS(42)!!!!
S!GND!J6T1!154!@baseboard_fab2_lib.baseboard_fab2(sch_1):page44_i139@mstr_sconn.sconn288_h44441003(chips)!SCONN288_H44441003_PIP-SCONN,HA!!!F218!VSS(43)!!!!
S!GND!J6T1!151!@baseboard_fab2_lib.baseboard_fab2(sch_1):page44_i139@mstr_sconn.sconn288_h44441003(chips)!SCONN288_H44441003_PIP-SCONN,HA!!!F218!VSS(44)!!!!
S!GND!J6T1!149!@baseboard_fab2_lib.baseboard_fab2(sch_1):page44_i139@mstr_sconn.sconn288_h44441003(chips)!SCONN288_H44441003_PIP-SCONN,HA!!!F218!VSS(45)!!!!
S!GND!J6T1!147!@baseboard_fab2_lib.baseboard_fab2(sch_1):page44_i139@mstr_sconn.sconn288_h44441003(chips)!SCONN288_H44441003_PIP-SCONN,HA!!!F218!VSS(46)!!!!
S!GND!J6T1!138!@baseboard_fab2_lib.baseboard_fab2(sch_1):page44_i139@mstr_sconn.sconn288_h44441003(chips)!SCONN288_H44441003_PIP-SCONN,HA!!!F218!VSS(47)!!!!
S!GND!J6T1!136!@baseboard_fab2_lib.baseboard_fab2(sch_1):page44_i139@mstr_sconn.sconn288_h44441003(chips)!SCONN288_H44441003_PIP-SCONN,HA!!!F218!VSS(48)!!!!
S!GND!J6T1!134!@baseboard_fab2_lib.baseboard_fab2(sch_1):page44_i139@mstr_sconn.sconn288_h44441003(chips)!SCONN288_H44441003_PIP-SCONN,HA!!!F218!VSS(49)!!!!
S!GND!J6T1!274!@baseboard_fab2_lib.baseboard_fab2(sch_1):page44_i139@mstr_sconn.sconn288_h44441003(chips)!SCONN288_H44441003_PIP-SCONN,HA!!!F218!VSS(4)!!!!
S!GND!J6T1!131!@baseboard_fab2_lib.baseboard_fab2(sch_1):page44_i139@mstr_sconn.sconn288_h44441003(chips)!SCONN288_H44441003_PIP-SCONN,HA!!!F218!VSS(50)!!!!
S!GND!J6T1!129!@baseboard_fab2_lib.baseboard_fab2(sch_1):page44_i139@mstr_sconn.sconn288_h44441003(chips)!SCONN288_H44441003_PIP-SCONN,HA!!!F218!VSS(51)!!!!
S!GND!J6T1!127!@baseboard_fab2_lib.baseboard_fab2(sch_1):page44_i139@mstr_sconn.sconn288_h44441003(chips)!SCONN288_H44441003_PIP-SCONN,HA!!!F218!VSS(52)!!!!
S!GND!J6T1!125!@baseboard_fab2_lib.baseboard_fab2(sch_1):page44_i139@mstr_sconn.sconn288_h44441003(chips)!SCONN288_H44441003_PIP-SCONN,HA!!!F218!VSS(53)!!!!
S!GND!J6T1!123!@baseboard_fab2_lib.baseboard_fab2(sch_1):page44_i139@mstr_sconn.sconn288_h44441003(chips)!SCONN288_H44441003_PIP-SCONN,HA!!!F218!VSS(54)!!!!
S!GND!J6T1!120!@baseboard_fab2_lib.baseboard_fab2(sch_1):page44_i139@mstr_sconn.sconn288_h44441003(chips)!SCONN288_H44441003_PIP-SCONN,HA!!!F218!VSS(55)!!!!
S!GND!J6T1!118!@baseboard_fab2_lib.baseboard_fab2(sch_1):page44_i139@mstr_sconn.sconn288_h44441003(chips)!SCONN288_H44441003_PIP-SCONN,HA!!!F218!VSS(56)!!!!
S!GND!J6T1!116!@baseboard_fab2_lib.baseboard_fab2(sch_1):page44_i139@mstr_sconn.sconn288_h44441003(chips)!SCONN288_H44441003_PIP-SCONN,HA!!!F218!VSS(57)!!!!
S!GND!J6T1!114!@baseboard_fab2_lib.baseboard_fab2(sch_1):page44_i139@mstr_sconn.sconn288_h44441003(chips)!SCONN288_H44441003_PIP-SCONN,HA!!!F218!VSS(58)!!!!
S!GND!J6T1!112!@baseboard_fab2_lib.baseboard_fab2(sch_1):page44_i139@mstr_sconn.sconn288_h44441003(chips)!SCONN288_H44441003_PIP-SCONN,HA!!!F218!VSS(59)!!!!
S!GND!J6T1!272!@baseboard_fab2_lib.baseboard_fab2(sch_1):page44_i139@mstr_sconn.sconn288_h44441003(chips)!SCONN288_H44441003_PIP-SCONN,HA!!!F218!VSS(5)!!!!
S!GND!J6T1!109!@baseboard_fab2_lib.baseboard_fab2(sch_1):page44_i139@mstr_sconn.sconn288_h44441003(chips)!SCONN288_H44441003_PIP-SCONN,HA!!!F218!VSS(60)!!!!
S!GND!J6T1!107!@baseboard_fab2_lib.baseboard_fab2(sch_1):page44_i139@mstr_sconn.sconn288_h44441003(chips)!SCONN288_H44441003_PIP-SCONN,HA!!!F218!VSS(61)!!!!
S!GND!J6T1!105!@baseboard_fab2_lib.baseboard_fab2(sch_1):page44_i139@mstr_sconn.sconn288_h44441003(chips)!SCONN288_H44441003_PIP-SCONN,HA!!!F218!VSS(62)!!!!
S!GND!J6T1!103!@baseboard_fab2_lib.baseboard_fab2(sch_1):page44_i139@mstr_sconn.sconn288_h44441003(chips)!SCONN288_H44441003_PIP-SCONN,HA!!!F218!VSS(63)!!!!
S!GND!J6T1!101!@baseboard_fab2_lib.baseboard_fab2(sch_1):page44_i139@mstr_sconn.sconn288_h44441003(chips)!SCONN288_H44441003_PIP-SCONN,HA!!!F218!VSS(64)!!!!
S!GND!J6T1!98!@baseboard_fab2_lib.baseboard_fab2(sch_1):page44_i139@mstr_sconn.sconn288_h44441003(chips)!SCONN288_H44441003_PIP-SCONN,HA!!!F218!VSS(65)!!!!
S!GND!J6T1!96!@baseboard_fab2_lib.baseboard_fab2(sch_1):page44_i139@mstr_sconn.sconn288_h44441003(chips)!SCONN288_H44441003_PIP-SCONN,HA!!!F218!VSS(66)!!!!
S!GND!J6T1!94!@baseboard_fab2_lib.baseboard_fab2(sch_1):page44_i139@mstr_sconn.sconn288_h44441003(chips)!SCONN288_H44441003_PIP-SCONN,HA!!!F218!VSS(67)!!!!
S!GND!J6T1!57!@baseboard_fab2_lib.baseboard_fab2(sch_1):page44_i139@mstr_sconn.sconn288_h44441003(chips)!SCONN288_H44441003_PIP-SCONN,HA!!!F218!VSS(68)!!!!
S!GND!J6T1!55!@baseboard_fab2_lib.baseboard_fab2(sch_1):page44_i139@mstr_sconn.sconn288_h44441003(chips)!SCONN288_H44441003_PIP-SCONN,HA!!!F218!VSS(69)!!!!
S!GND!J6T1!270!@baseboard_fab2_lib.baseboard_fab2(sch_1):page44_i139@mstr_sconn.sconn288_h44441003(chips)!SCONN288_H44441003_PIP-SCONN,HA!!!F218!VSS(6)!!!!
S!GND!J6T1!53!@baseboard_fab2_lib.baseboard_fab2(sch_1):page44_i139@mstr_sconn.sconn288_h44441003(chips)!SCONN288_H44441003_PIP-SCONN,HA!!!F218!VSS(70)!!!!
S!GND!J6T1!50!@baseboard_fab2_lib.baseboard_fab2(sch_1):page44_i139@mstr_sconn.sconn288_h44441003(chips)!SCONN288_H44441003_PIP-SCONN,HA!!!F218!VSS(71)!!!!
S!GND!J6T1!48!@baseboard_fab2_lib.baseboard_fab2(sch_1):page44_i139@mstr_sconn.sconn288_h44441003(chips)!SCONN288_H44441003_PIP-SCONN,HA!!!F218!VSS(72)!!!!
S!GND!J6T1!46!@baseboard_fab2_lib.baseboard_fab2(sch_1):page44_i139@mstr_sconn.sconn288_h44441003(chips)!SCONN288_H44441003_PIP-SCONN,HA!!!F218!VSS(73)!!!!
S!GND!J6T1!44!@baseboard_fab2_lib.baseboard_fab2(sch_1):page44_i139@mstr_sconn.sconn288_h44441003(chips)!SCONN288_H44441003_PIP-SCONN,HA!!!F218!VSS(74)!!!!
S!GND!J6T1!42!@baseboard_fab2_lib.baseboard_fab2(sch_1):page44_i139@mstr_sconn.sconn288_h44441003(chips)!SCONN288_H44441003_PIP-SCONN,HA!!!F218!VSS(75)!!!!
S!GND!J6T1!39!@baseboard_fab2_lib.baseboard_fab2(sch_1):page44_i139@mstr_sconn.sconn288_h44441003(chips)!SCONN288_H44441003_PIP-SCONN,HA!!!F218!VSS(76)!!!!
S!GND!J6T1!37!@baseboard_fab2_lib.baseboard_fab2(sch_1):page44_i139@mstr_sconn.sconn288_h44441003(chips)!SCONN288_H44441003_PIP-SCONN,HA!!!F218!VSS(77)!!!!
S!GND!J6T1!35!@baseboard_fab2_lib.baseboard_fab2(sch_1):page44_i139@mstr_sconn.sconn288_h44441003(chips)!SCONN288_H44441003_PIP-SCONN,HA!!!F218!VSS(78)!!!!
S!GND!J6T1!33!@baseboard_fab2_lib.baseboard_fab2(sch_1):page44_i139@mstr_sconn.sconn288_h44441003(chips)!SCONN288_H44441003_PIP-SCONN,HA!!!F218!VSS(79)!!!!
S!GND!J6T1!268!@baseboard_fab2_lib.baseboard_fab2(sch_1):page44_i139@mstr_sconn.sconn288_h44441003(chips)!SCONN288_H44441003_PIP-SCONN,HA!!!F218!VSS(7)!!!!
S!GND!J6T1!31!@baseboard_fab2_lib.baseboard_fab2(sch_1):page44_i139@mstr_sconn.sconn288_h44441003(chips)!SCONN288_H44441003_PIP-SCONN,HA!!!F218!VSS(80)!!!!
S!GND!J6T1!28!@baseboard_fab2_lib.baseboard_fab2(sch_1):page44_i139@mstr_sconn.sconn288_h44441003(chips)!SCONN288_H44441003_PIP-SCONN,HA!!!F218!VSS(81)!!!!
S!GND!J6T1!26!@baseboard_fab2_lib.baseboard_fab2(sch_1):page44_i139@mstr_sconn.sconn288_h44441003(chips)!SCONN288_H44441003_PIP-SCONN,HA!!!F218!VSS(82)!!!!
S!GND!J6T1!24!@baseboard_fab2_lib.baseboard_fab2(sch_1):page44_i139@mstr_sconn.sconn288_h44441003(chips)!SCONN288_H44441003_PIP-SCONN,HA!!!F218!VSS(83)!!!!
S!GND!J6T1!22!@baseboard_fab2_lib.baseboard_fab2(sch_1):page44_i139@mstr_sconn.sconn288_h44441003(chips)!SCONN288_H44441003_PIP-SCONN,HA!!!F218!VSS(84)!!!!
S!GND!J6T1!20!@baseboard_fab2_lib.baseboard_fab2(sch_1):page44_i139@mstr_sconn.sconn288_h44441003(chips)!SCONN288_H44441003_PIP-SCONN,HA!!!F218!VSS(85)!!!!
S!GND!J6T1!17!@baseboard_fab2_lib.baseboard_fab2(sch_1):page44_i139@mstr_sconn.sconn288_h44441003(chips)!SCONN288_H44441003_PIP-SCONN,HA!!!F218!VSS(86)!!!!
S!GND!J6T1!15!@baseboard_fab2_lib.baseboard_fab2(sch_1):page44_i139@mstr_sconn.sconn288_h44441003(chips)!SCONN288_H44441003_PIP-SCONN,HA!!!F218!VSS(87)!!!!
S!GND!J6T1!13!@baseboard_fab2_lib.baseboard_fab2(sch_1):page44_i139@mstr_sconn.sconn288_h44441003(chips)!SCONN288_H44441003_PIP-SCONN,HA!!!F218!VSS(88)!!!!
S!GND!J6T1!11!@baseboard_fab2_lib.baseboard_fab2(sch_1):page44_i139@mstr_sconn.sconn288_h44441003(chips)!SCONN288_H44441003_PIP-SCONN,HA!!!F218!VSS(89)!!!!
S!GND!J6T1!265!@baseboard_fab2_lib.baseboard_fab2(sch_1):page44_i139@mstr_sconn.sconn288_h44441003(chips)!SCONN288_H44441003_PIP-SCONN,HA!!!F218!VSS(8)!!!!
S!GND!J6T1!9!@baseboard_fab2_lib.baseboard_fab2(sch_1):page44_i139@mstr_sconn.sconn288_h44441003(chips)!SCONN288_H44441003_PIP-SCONN,HA!!!F218!VSS(90)!!!!
S!GND!J6T1!6!@baseboard_fab2_lib.baseboard_fab2(sch_1):page44_i139@mstr_sconn.sconn288_h44441003(chips)!SCONN288_H44441003_PIP-SCONN,HA!!!F218!VSS(91)!!!!
S!GND!J6T1!4!@baseboard_fab2_lib.baseboard_fab2(sch_1):page44_i139@mstr_sconn.sconn288_h44441003(chips)!SCONN288_H44441003_PIP-SCONN,HA!!!F218!VSS(92)!!!!
S!GND!J6T1!2!@baseboard_fab2_lib.baseboard_fab2(sch_1):page44_i139@mstr_sconn.sconn288_h44441003(chips)!SCONN288_H44441003_PIP-SCONN,HA!!!F218!VSS(93)!!!!
S!GND!J6T1!263!@baseboard_fab2_lib.baseboard_fab2(sch_1):page44_i139@mstr_sconn.sconn288_h44441003(chips)!SCONN288_H44441003_PIP-SCONN,HA!!!F218!VSS(9)!!!!
S!P12V_NVDIMM_ABC!J6T1!145!@baseboard_fab2_lib.baseboard_fab2(sch_1):page44_i75@mstr_sconn.sconn288_h44441003(chips)!SCONN288_H44441003_PIP-SCONN,HA!!!F217!\12v\(0)!!!!
S!P12V_NVDIMM_ABC!J6T1!1!@baseboard_fab2_lib.baseboard_fab2(sch_1):page44_i75@mstr_sconn.sconn288_h44441003(chips)!SCONN288_H44441003_PIP-SCONN,HA!!!F217!\12v\(1)!!!!
S!PVDDQ_ABC!J6T1!236!@baseboard_fab2_lib.baseboard_fab2(sch_1):page44_i75@mstr_sconn.sconn288_h44441003(chips)!SCONN288_H44441003_PIP-SCONN,HA!!!F217!VDD(0)!!!!
S!PVDDQ_ABC!J6T1!209!@baseboard_fab2_lib.baseboard_fab2(sch_1):page44_i75@mstr_sconn.sconn288_h44441003(chips)!SCONN288_H44441003_PIP-SCONN,HA!!!F217!VDD(10)!!!!
S!PVDDQ_ABC!J6T1!206!@baseboard_fab2_lib.baseboard_fab2(sch_1):page44_i75@mstr_sconn.sconn288_h44441003(chips)!SCONN288_H44441003_PIP-SCONN,HA!!!F217!VDD(11)!!!!
S!PVDDQ_ABC!J6T1!204!@baseboard_fab2_lib.baseboard_fab2(sch_1):page44_i75@mstr_sconn.sconn288_h44441003(chips)!SCONN288_H44441003_PIP-SCONN,HA!!!F217!VDD(12)!!!!
S!PVDDQ_ABC!J6T1!92!@baseboard_fab2_lib.baseboard_fab2(sch_1):page44_i75@mstr_sconn.sconn288_h44441003(chips)!SCONN288_H44441003_PIP-SCONN,HA!!!F217!VDD(13)!!!!
S!PVDDQ_ABC!J6T1!90!@baseboard_fab2_lib.baseboard_fab2(sch_1):page44_i75@mstr_sconn.sconn288_h44441003(chips)!SCONN288_H44441003_PIP-SCONN,HA!!!F217!VDD(14)!!!!
S!PVDDQ_ABC!J6T1!88!@baseboard_fab2_lib.baseboard_fab2(sch_1):page44_i75@mstr_sconn.sconn288_h44441003(chips)!SCONN288_H44441003_PIP-SCONN,HA!!!F217!VDD(15)!!!!
S!PVDDQ_ABC!J6T1!85!@baseboard_fab2_lib.baseboard_fab2(sch_1):page44_i75@mstr_sconn.sconn288_h44441003(chips)!SCONN288_H44441003_PIP-SCONN,HA!!!F217!VDD(16)!!!!
S!PVDDQ_ABC!J6T1!83!@baseboard_fab2_lib.baseboard_fab2(sch_1):page44_i75@mstr_sconn.sconn288_h44441003(chips)!SCONN288_H44441003_PIP-SCONN,HA!!!F217!VDD(17)!!!!
S!PVDDQ_ABC!J6T1!80!@baseboard_fab2_lib.baseboard_fab2(sch_1):page44_i75@mstr_sconn.sconn288_h44441003(chips)!SCONN288_H44441003_PIP-SCONN,HA!!!F217!VDD(18)!!!!
S!PVDDQ_ABC!J6T1!76!@baseboard_fab2_lib.baseboard_fab2(sch_1):page44_i75@mstr_sconn.sconn288_h44441003(chips)!SCONN288_H44441003_PIP-SCONN,HA!!!F217!VDD(19)!!!!
S!PVDDQ_ABC!J6T1!233!@baseboard_fab2_lib.baseboard_fab2(sch_1):page44_i75@mstr_sconn.sconn288_h44441003(chips)!SCONN288_H44441003_PIP-SCONN,HA!!!F217!VDD(1)!!!!
S!PVDDQ_ABC!J6T1!73!@baseboard_fab2_lib.baseboard_fab2(sch_1):page44_i75@mstr_sconn.sconn288_h44441003(chips)!SCONN288_H44441003_PIP-SCONN,HA!!!F217!VDD(20)!!!!
S!PVDDQ_ABC!J6T1!70!@baseboard_fab2_lib.baseboard_fab2(sch_1):page44_i75@mstr_sconn.sconn288_h44441003(chips)!SCONN288_H44441003_PIP-SCONN,HA!!!F217!VDD(21)!!!!
S!PVDDQ_ABC!J6T1!67!@baseboard_fab2_lib.baseboard_fab2(sch_1):page44_i75@mstr_sconn.sconn288_h44441003(chips)!SCONN288_H44441003_PIP-SCONN,HA!!!F217!VDD(22)!!!!
S!PVDDQ_ABC!J6T1!64!@baseboard_fab2_lib.baseboard_fab2(sch_1):page44_i75@mstr_sconn.sconn288_h44441003(chips)!SCONN288_H44441003_PIP-SCONN,HA!!!F217!VDD(23)!!!!
S!PVDDQ_ABC!J6T1!61!@baseboard_fab2_lib.baseboard_fab2(sch_1):page44_i75@mstr_sconn.sconn288_h44441003(chips)!SCONN288_H44441003_PIP-SCONN,HA!!!F217!VDD(24)!!!!
S!PVDDQ_ABC!J6T1!59!@baseboard_fab2_lib.baseboard_fab2(sch_1):page44_i75@mstr_sconn.sconn288_h44441003(chips)!SCONN288_H44441003_PIP-SCONN,HA!!!F217!VDD(25)!!!!
S!PVDDQ_ABC!J6T1!231!@baseboard_fab2_lib.baseboard_fab2(sch_1):page44_i75@mstr_sconn.sconn288_h44441003(chips)!SCONN288_H44441003_PIP-SCONN,HA!!!F217!VDD(2)!!!!
S!PVDDQ_ABC!J6T1!229!@baseboard_fab2_lib.baseboard_fab2(sch_1):page44_i75@mstr_sconn.sconn288_h44441003(chips)!SCONN288_H44441003_PIP-SCONN,HA!!!F217!VDD(3)!!!!
S!PVDDQ_ABC!J6T1!226!@baseboard_fab2_lib.baseboard_fab2(sch_1):page44_i75@mstr_sconn.sconn288_h44441003(chips)!SCONN288_H44441003_PIP-SCONN,HA!!!F217!VDD(4)!!!!
S!PVDDQ_ABC!J6T1!223!@baseboard_fab2_lib.baseboard_fab2(sch_1):page44_i75@mstr_sconn.sconn288_h44441003(chips)!SCONN288_H44441003_PIP-SCONN,HA!!!F217!VDD(5)!!!!
S!PVDDQ_ABC!J6T1!220!@baseboard_fab2_lib.baseboard_fab2(sch_1):page44_i75@mstr_sconn.sconn288_h44441003(chips)!SCONN288_H44441003_PIP-SCONN,HA!!!F217!VDD(6)!!!!
S!PVDDQ_ABC!J6T1!217!@baseboard_fab2_lib.baseboard_fab2(sch_1):page44_i75@mstr_sconn.sconn288_h44441003(chips)!SCONN288_H44441003_PIP-SCONN,HA!!!F217!VDD(7)!!!!
S!PVDDQ_ABC!J6T1!215!@baseboard_fab2_lib.baseboard_fab2(sch_1):page44_i75@mstr_sconn.sconn288_h44441003(chips)!SCONN288_H44441003_PIP-SCONN,HA!!!F217!VDD(8)!!!!
S!PVDDQ_ABC!J6T1!212!@baseboard_fab2_lib.baseboard_fab2(sch_1):page44_i75@mstr_sconn.sconn288_h44441003(chips)!SCONN288_H44441003_PIP-SCONN,HA!!!F217!VDD(9)!!!!
S!PVPP_ABC!J6T1!287!@baseboard_fab2_lib.baseboard_fab2(sch_1):page44_i75@mstr_sconn.sconn288_h44441003(chips)!SCONN288_H44441003_PIP-SCONN,HA!!!F217!VPP(0)!!!!
S!PVPP_ABC!J6T1!286!@baseboard_fab2_lib.baseboard_fab2(sch_1):page44_i75@mstr_sconn.sconn288_h44441003(chips)!SCONN288_H44441003_PIP-SCONN,HA!!!F217!VPP(1)!!!!
S!PVPP_ABC!J6T1!288!@baseboard_fab2_lib.baseboard_fab2(sch_1):page44_i75@mstr_sconn.sconn288_h44441003(chips)!SCONN288_H44441003_PIP-SCONN,HA!!!F217!VPP(2)!!!!
S!PVPP_ABC!J6T1!143!@baseboard_fab2_lib.baseboard_fab2(sch_1):page44_i75@mstr_sconn.sconn288_h44441003(chips)!SCONN288_H44441003_PIP-SCONN,HA!!!F217!VPP(3)!!!!
S!PVPP_ABC!J6T1!142!@baseboard_fab2_lib.baseboard_fab2(sch_1):page44_i75@mstr_sconn.sconn288_h44441003(chips)!SCONN288_H44441003_PIP-SCONN,HA!!!F217!VPP(4)!!!!
S!PVTT_ABC!J6T1!221!@baseboard_fab2_lib.baseboard_fab2(sch_1):page44_i75@mstr_sconn.sconn288_h44441003(chips)!SCONN288_H44441003_PIP-SCONN,HA!!!F217!VTT(0)!!!!
S!PVTT_ABC!J6T1!77!@baseboard_fab2_lib.baseboard_fab2(sch_1):page44_i75@mstr_sconn.sconn288_h44441003(chips)!SCONN288_H44441003_PIP-SCONN,HA!!!F217!VTT(1)!!!!
S!M_B_MA<0>!J6U1!79!@baseboard_fab2_lib.baseboard_fab2(sch_1):page46_i14@mstr_sconn.sconn288_h44441003(chips)!SCONN288_H44441003_PIP-SCONN,HA!!!F216!A0!!!!
S!M_B_MA<1>!J6U1!72!@baseboard_fab2_lib.baseboard_fab2(sch_1):page46_i14@mstr_sconn.sconn288_h44441003(chips)!SCONN288_H44441003_PIP-SCONN,HA!!!F216!A1!!!!
S!M_B_MA<10>!J6U1!225!@baseboard_fab2_lib.baseboard_fab2(sch_1):page46_i14@mstr_sconn.sconn288_h44441003(chips)!SCONN288_H44441003_PIP-SCONN,HA!!!F216!A10!!!!
S!M_B_MA<11>!J6U1!210!@baseboard_fab2_lib.baseboard_fab2(sch_1):page46_i14@mstr_sconn.sconn288_h44441003(chips)!SCONN288_H44441003_PIP-SCONN,HA!!!F216!A11!!!!
S!M_B_MA<12>!J6U1!65!@baseboard_fab2_lib.baseboard_fab2(sch_1):page46_i14@mstr_sconn.sconn288_h44441003(chips)!SCONN288_H44441003_PIP-SCONN,HA!!!F216!A12!!!!
S!M_B_MA<13>!J6U1!232!@baseboard_fab2_lib.baseboard_fab2(sch_1):page46_i14@mstr_sconn.sconn288_h44441003(chips)!SCONN288_H44441003_PIP-SCONN,HA!!!F216!A13!!!!
S!M_B_MA<14>!J6U1!228!@baseboard_fab2_lib.baseboard_fab2(sch_1):page46_i14@mstr_sconn.sconn288_h44441003(chips)!SCONN288_H44441003_PIP-SCONN,HA!!!F216!A14_WE_N!!!!
S!M_B_MA<15>!J6U1!86!@baseboard_fab2_lib.baseboard_fab2(sch_1):page46_i14@mstr_sconn.sconn288_h44441003(chips)!SCONN288_H44441003_PIP-SCONN,HA!!!F216!A15_CAS_N!!!!
S!M_B_MA<16>!J6U1!82!@baseboard_fab2_lib.baseboard_fab2(sch_1):page46_i14@mstr_sconn.sconn288_h44441003(chips)!SCONN288_H44441003_PIP-SCONN,HA!!!F216!A16_RAS_N!!!!
S!M_B_MA<17>!J6U1!234!@baseboard_fab2_lib.baseboard_fab2(sch_1):page46_i14@mstr_sconn.sconn288_h44441003(chips)!SCONN288_H44441003_PIP-SCONN,HA!!!F216!A17!!!!
S!M_B_MA<2>!J6U1!216!@baseboard_fab2_lib.baseboard_fab2(sch_1):page46_i14@mstr_sconn.sconn288_h44441003(chips)!SCONN288_H44441003_PIP-SCONN,HA!!!F216!A2!!!!
S!M_B_MA<3>!J6U1!71!@baseboard_fab2_lib.baseboard_fab2(sch_1):page46_i14@mstr_sconn.sconn288_h44441003(chips)!SCONN288_H44441003_PIP-SCONN,HA!!!F216!A3!!!!
S!M_B_MA<4>!J6U1!214!@baseboard_fab2_lib.baseboard_fab2(sch_1):page46_i14@mstr_sconn.sconn288_h44441003(chips)!SCONN288_H44441003_PIP-SCONN,HA!!!F216!A4!!!!
S!M_B_MA<5>!J6U1!213!@baseboard_fab2_lib.baseboard_fab2(sch_1):page46_i14@mstr_sconn.sconn288_h44441003(chips)!SCONN288_H44441003_PIP-SCONN,HA!!!F216!A5!!!!
S!M_B_MA<6>!J6U1!69!@baseboard_fab2_lib.baseboard_fab2(sch_1):page46_i14@mstr_sconn.sconn288_h44441003(chips)!SCONN288_H44441003_PIP-SCONN,HA!!!F216!A6!!!!
S!M_B_MA<7>!J6U1!211!@baseboard_fab2_lib.baseboard_fab2(sch_1):page46_i14@mstr_sconn.sconn288_h44441003(chips)!SCONN288_H44441003_PIP-SCONN,HA!!!F216!A7!!!!
S!M_B_MA<8>!J6U1!68!@baseboard_fab2_lib.baseboard_fab2(sch_1):page46_i14@mstr_sconn.sconn288_h44441003(chips)!SCONN288_H44441003_PIP-SCONN,HA!!!F216!A8!!!!
S!M_B_MA<9>!J6U1!66!@baseboard_fab2_lib.baseboard_fab2(sch_1):page46_i14@mstr_sconn.sconn288_h44441003(chips)!SCONN288_H44441003_PIP-SCONN,HA!!!F216!A9!!!!
S!M_B_ACT_N!J6U1!62!@baseboard_fab2_lib.baseboard_fab2(sch_1):page46_i14@mstr_sconn.sconn288_h44441003(chips)!SCONN288_H44441003_PIP-SCONN,HA!!!F216!ACT_N!!!!
S!M_B_ALERT_N!J6U1!208!@baseboard_fab2_lib.baseboard_fab2(sch_1):page46_i14@mstr_sconn.sconn288_h44441003(chips)!SCONN288_H44441003_PIP-SCONN,HA!!!F216!ALERT_N!!!!
S!M_B_BA<0>!J6U1!81!@baseboard_fab2_lib.baseboard_fab2(sch_1):page46_i14@mstr_sconn.sconn288_h44441003(chips)!SCONN288_H44441003_PIP-SCONN,HA!!!F216!BA(0)!!!!
S!M_B_BA<1>!J6U1!224!@baseboard_fab2_lib.baseboard_fab2(sch_1):page46_i14@mstr_sconn.sconn288_h44441003(chips)!SCONN288_H44441003_PIP-SCONN,HA!!!F216!BA(1)!!!!
S!M_B_BG<0>!J6U1!63!@baseboard_fab2_lib.baseboard_fab2(sch_1):page46_i14@mstr_sconn.sconn288_h44441003(chips)!SCONN288_H44441003_PIP-SCONN,HA!!!F216!BG(0)!!!!
S!M_B_BG<1>!J6U1!207!@baseboard_fab2_lib.baseboard_fab2(sch_1):page46_i14@mstr_sconn.sconn288_h44441003(chips)!SCONN288_H44441003_PIP-SCONN,HA!!!F216!BG(1)!!!!
S!M_B_C<2>!J6U1!235!@baseboard_fab2_lib.baseboard_fab2(sch_1):page46_i14@mstr_sconn.sconn288_h44441003(chips)!SCONN288_H44441003_PIP-SCONN,HA!!!F216!C(2)!!!!
S!M_B_ECC<0>!J6U1!49!@baseboard_fab2_lib.baseboard_fab2(sch_1):page46_i14@mstr_sconn.sconn288_h44441003(chips)!SCONN288_H44441003_PIP-SCONN,HA!!!F216!CB(0)!!!!
S!M_B_ECC<1>!J6U1!194!@baseboard_fab2_lib.baseboard_fab2(sch_1):page46_i14@mstr_sconn.sconn288_h44441003(chips)!SCONN288_H44441003_PIP-SCONN,HA!!!F216!CB(1)!!!!
S!M_B_ECC<2>!J6U1!56!@baseboard_fab2_lib.baseboard_fab2(sch_1):page46_i14@mstr_sconn.sconn288_h44441003(chips)!SCONN288_H44441003_PIP-SCONN,HA!!!F216!CB(2)!!!!
S!M_B_ECC<3>!J6U1!201!@baseboard_fab2_lib.baseboard_fab2(sch_1):page46_i14@mstr_sconn.sconn288_h44441003(chips)!SCONN288_H44441003_PIP-SCONN,HA!!!F216!CB(3)!!!!
S!M_B_ECC<4>!J6U1!47!@baseboard_fab2_lib.baseboard_fab2(sch_1):page46_i14@mstr_sconn.sconn288_h44441003(chips)!SCONN288_H44441003_PIP-SCONN,HA!!!F216!CB(4)!!!!
S!M_B_ECC<5>!J6U1!192!@baseboard_fab2_lib.baseboard_fab2(sch_1):page46_i14@mstr_sconn.sconn288_h44441003(chips)!SCONN288_H44441003_PIP-SCONN,HA!!!F216!CB(5)!!!!
S!M_B_ECC<6>!J6U1!54!@baseboard_fab2_lib.baseboard_fab2(sch_1):page46_i14@mstr_sconn.sconn288_h44441003(chips)!SCONN288_H44441003_PIP-SCONN,HA!!!F216!CB(6)!!!!
S!M_B_ECC<7>!J6U1!199!@baseboard_fab2_lib.baseboard_fab2(sch_1):page46_i14@mstr_sconn.sconn288_h44441003(chips)!SCONN288_H44441003_PIP-SCONN,HA!!!F216!CB(7)!!!!
S!M_B_CLK_DN<2>!J6U1!75!@baseboard_fab2_lib.baseboard_fab2(sch_1):page46_i14@mstr_sconn.sconn288_h44441003(chips)!SCONN288_H44441003_PIP-SCONN,HA!!!F216!CK0N!!!!
S!M_B_CLK_DP<2>!J6U1!74!@baseboard_fab2_lib.baseboard_fab2(sch_1):page46_i14@mstr_sconn.sconn288_h44441003(chips)!SCONN288_H44441003_PIP-SCONN,HA!!!F216!CK0P!!!!
S!M_B_CLK_DN<3>!J6U1!219!@baseboard_fab2_lib.baseboard_fab2(sch_1):page46_i14@mstr_sconn.sconn288_h44441003(chips)!SCONN288_H44441003_PIP-SCONN,HA!!!F216!CK1N!!!!
S!M_B_CLK_DP<3>!J6U1!218!@baseboard_fab2_lib.baseboard_fab2(sch_1):page46_i14@mstr_sconn.sconn288_h44441003(chips)!SCONN288_H44441003_PIP-SCONN,HA!!!F216!CK1P!!!!
S!M_B_CKE<2>!J6U1!60!@baseboard_fab2_lib.baseboard_fab2(sch_1):page46_i14@mstr_sconn.sconn288_h44441003(chips)!SCONN288_H44441003_PIP-SCONN,HA!!!F216!CKE(0)!!!!
S!M_B_CKE<3>!J6U1!203!@baseboard_fab2_lib.baseboard_fab2(sch_1):page46_i14@mstr_sconn.sconn288_h44441003(chips)!SCONN288_H44441003_PIP-SCONN,HA!!!F216!CKE(1)!!!!
S!M_B_DQ<0>!J6U1!5!@baseboard_fab2_lib.baseboard_fab2(sch_1):page46_i14@mstr_sconn.sconn288_h44441003(chips)!SCONN288_H44441003_PIP-SCONN,HA!!!F216!DQ(0)!!!!
S!M_B_DQ<10>!J6U1!23!@baseboard_fab2_lib.baseboard_fab2(sch_1):page46_i14@mstr_sconn.sconn288_h44441003(chips)!SCONN288_H44441003_PIP-SCONN,HA!!!F216!DQ(10)!!!!
S!M_B_DQ<11>!J6U1!168!@baseboard_fab2_lib.baseboard_fab2(sch_1):page46_i14@mstr_sconn.sconn288_h44441003(chips)!SCONN288_H44441003_PIP-SCONN,HA!!!F216!DQ(11)!!!!
S!M_B_DQ<12>!J6U1!14!@baseboard_fab2_lib.baseboard_fab2(sch_1):page46_i14@mstr_sconn.sconn288_h44441003(chips)!SCONN288_H44441003_PIP-SCONN,HA!!!F216!DQ(12)!!!!
S!M_B_DQ<13>!J6U1!159!@baseboard_fab2_lib.baseboard_fab2(sch_1):page46_i14@mstr_sconn.sconn288_h44441003(chips)!SCONN288_H44441003_PIP-SCONN,HA!!!F216!DQ(13)!!!!
S!M_B_DQ<14>!J6U1!21!@baseboard_fab2_lib.baseboard_fab2(sch_1):page46_i14@mstr_sconn.sconn288_h44441003(chips)!SCONN288_H44441003_PIP-SCONN,HA!!!F216!DQ(14)!!!!
S!M_B_DQ<15>!J6U1!166!@baseboard_fab2_lib.baseboard_fab2(sch_1):page46_i14@mstr_sconn.sconn288_h44441003(chips)!SCONN288_H44441003_PIP-SCONN,HA!!!F216!DQ(15)!!!!
S!M_B_DQ<16>!J6U1!27!@baseboard_fab2_lib.baseboard_fab2(sch_1):page46_i14@mstr_sconn.sconn288_h44441003(chips)!SCONN288_H44441003_PIP-SCONN,HA!!!F216!DQ(16)!!!!
S!M_B_DQ<17>!J6U1!172!@baseboard_fab2_lib.baseboard_fab2(sch_1):page46_i14@mstr_sconn.sconn288_h44441003(chips)!SCONN288_H44441003_PIP-SCONN,HA!!!F216!DQ(17)!!!!
S!M_B_DQ<18>!J6U1!34!@baseboard_fab2_lib.baseboard_fab2(sch_1):page46_i14@mstr_sconn.sconn288_h44441003(chips)!SCONN288_H44441003_PIP-SCONN,HA!!!F216!DQ(18)!!!!
S!M_B_DQ<19>!J6U1!179!@baseboard_fab2_lib.baseboard_fab2(sch_1):page46_i14@mstr_sconn.sconn288_h44441003(chips)!SCONN288_H44441003_PIP-SCONN,HA!!!F216!DQ(19)!!!!
S!M_B_DQ<1>!J6U1!150!@baseboard_fab2_lib.baseboard_fab2(sch_1):page46_i14@mstr_sconn.sconn288_h44441003(chips)!SCONN288_H44441003_PIP-SCONN,HA!!!F216!DQ(1)!!!!
S!M_B_DQ<20>!J6U1!25!@baseboard_fab2_lib.baseboard_fab2(sch_1):page46_i14@mstr_sconn.sconn288_h44441003(chips)!SCONN288_H44441003_PIP-SCONN,HA!!!F216!DQ(20)!!!!
S!M_B_DQ<21>!J6U1!170!@baseboard_fab2_lib.baseboard_fab2(sch_1):page46_i14@mstr_sconn.sconn288_h44441003(chips)!SCONN288_H44441003_PIP-SCONN,HA!!!F216!DQ(21)!!!!
S!M_B_DQ<22>!J6U1!32!@baseboard_fab2_lib.baseboard_fab2(sch_1):page46_i14@mstr_sconn.sconn288_h44441003(chips)!SCONN288_H44441003_PIP-SCONN,HA!!!F216!DQ(22)!!!!
S!M_B_DQ<23>!J6U1!177!@baseboard_fab2_lib.baseboard_fab2(sch_1):page46_i14@mstr_sconn.sconn288_h44441003(chips)!SCONN288_H44441003_PIP-SCONN,HA!!!F216!DQ(23)!!!!
S!M_B_DQ<24>!J6U1!38!@baseboard_fab2_lib.baseboard_fab2(sch_1):page46_i14@mstr_sconn.sconn288_h44441003(chips)!SCONN288_H44441003_PIP-SCONN,HA!!!F216!DQ(24)!!!!
S!M_B_DQ<25>!J6U1!183!@baseboard_fab2_lib.baseboard_fab2(sch_1):page46_i14@mstr_sconn.sconn288_h44441003(chips)!SCONN288_H44441003_PIP-SCONN,HA!!!F216!DQ(25)!!!!
S!M_B_DQ<26>!J6U1!45!@baseboard_fab2_lib.baseboard_fab2(sch_1):page46_i14@mstr_sconn.sconn288_h44441003(chips)!SCONN288_H44441003_PIP-SCONN,HA!!!F216!DQ(26)!!!!
S!M_B_DQ<27>!J6U1!190!@baseboard_fab2_lib.baseboard_fab2(sch_1):page46_i14@mstr_sconn.sconn288_h44441003(chips)!SCONN288_H44441003_PIP-SCONN,HA!!!F216!DQ(27)!!!!
S!M_B_DQ<28>!J6U1!36!@baseboard_fab2_lib.baseboard_fab2(sch_1):page46_i14@mstr_sconn.sconn288_h44441003(chips)!SCONN288_H44441003_PIP-SCONN,HA!!!F216!DQ(28)!!!!
S!M_B_DQ<29>!J6U1!181!@baseboard_fab2_lib.baseboard_fab2(sch_1):page46_i14@mstr_sconn.sconn288_h44441003(chips)!SCONN288_H44441003_PIP-SCONN,HA!!!F216!DQ(29)!!!!
S!M_B_DQ<2>!J6U1!12!@baseboard_fab2_lib.baseboard_fab2(sch_1):page46_i14@mstr_sconn.sconn288_h44441003(chips)!SCONN288_H44441003_PIP-SCONN,HA!!!F216!DQ(2)!!!!
S!M_B_DQ<30>!J6U1!43!@baseboard_fab2_lib.baseboard_fab2(sch_1):page46_i14@mstr_sconn.sconn288_h44441003(chips)!SCONN288_H44441003_PIP-SCONN,HA!!!F216!DQ(30)!!!!
S!M_B_DQ<31>!J6U1!188!@baseboard_fab2_lib.baseboard_fab2(sch_1):page46_i14@mstr_sconn.sconn288_h44441003(chips)!SCONN288_H44441003_PIP-SCONN,HA!!!F216!DQ(31)!!!!
S!M_B_DQ<32>!J6U1!97!@baseboard_fab2_lib.baseboard_fab2(sch_1):page46_i14@mstr_sconn.sconn288_h44441003(chips)!SCONN288_H44441003_PIP-SCONN,HA!!!F216!DQ(32)!!!!
S!M_B_DQ<33>!J6U1!242!@baseboard_fab2_lib.baseboard_fab2(sch_1):page46_i14@mstr_sconn.sconn288_h44441003(chips)!SCONN288_H44441003_PIP-SCONN,HA!!!F216!DQ(33)!!!!
S!M_B_DQ<34>!J6U1!104!@baseboard_fab2_lib.baseboard_fab2(sch_1):page46_i14@mstr_sconn.sconn288_h44441003(chips)!SCONN288_H44441003_PIP-SCONN,HA!!!F216!DQ(34)!!!!
S!M_B_DQ<35>!J6U1!249!@baseboard_fab2_lib.baseboard_fab2(sch_1):page46_i14@mstr_sconn.sconn288_h44441003(chips)!SCONN288_H44441003_PIP-SCONN,HA!!!F216!DQ(35)!!!!
S!M_B_DQ<36>!J6U1!95!@baseboard_fab2_lib.baseboard_fab2(sch_1):page46_i14@mstr_sconn.sconn288_h44441003(chips)!SCONN288_H44441003_PIP-SCONN,HA!!!F216!DQ(36)!!!!
S!M_B_DQ<37>!J6U1!240!@baseboard_fab2_lib.baseboard_fab2(sch_1):page46_i14@mstr_sconn.sconn288_h44441003(chips)!SCONN288_H44441003_PIP-SCONN,HA!!!F216!DQ(37)!!!!
S!M_B_DQ<38>!J6U1!102!@baseboard_fab2_lib.baseboard_fab2(sch_1):page46_i14@mstr_sconn.sconn288_h44441003(chips)!SCONN288_H44441003_PIP-SCONN,HA!!!F216!DQ(38)!!!!
S!M_B_DQ<39>!J6U1!247!@baseboard_fab2_lib.baseboard_fab2(sch_1):page46_i14@mstr_sconn.sconn288_h44441003(chips)!SCONN288_H44441003_PIP-SCONN,HA!!!F216!DQ(39)!!!!
S!M_B_DQ<3>!J6U1!157!@baseboard_fab2_lib.baseboard_fab2(sch_1):page46_i14@mstr_sconn.sconn288_h44441003(chips)!SCONN288_H44441003_PIP-SCONN,HA!!!F216!DQ(3)!!!!
S!M_B_DQ<40>!J6U1!108!@baseboard_fab2_lib.baseboard_fab2(sch_1):page46_i14@mstr_sconn.sconn288_h44441003(chips)!SCONN288_H44441003_PIP-SCONN,HA!!!F216!DQ(40)!!!!
S!M_B_DQ<41>!J6U1!253!@baseboard_fab2_lib.baseboard_fab2(sch_1):page46_i14@mstr_sconn.sconn288_h44441003(chips)!SCONN288_H44441003_PIP-SCONN,HA!!!F216!DQ(41)!!!!
S!M_B_DQ<42>!J6U1!115!@baseboard_fab2_lib.baseboard_fab2(sch_1):page46_i14@mstr_sconn.sconn288_h44441003(chips)!SCONN288_H44441003_PIP-SCONN,HA!!!F216!DQ(42)!!!!
S!M_B_DQ<43>!J6U1!260!@baseboard_fab2_lib.baseboard_fab2(sch_1):page46_i14@mstr_sconn.sconn288_h44441003(chips)!SCONN288_H44441003_PIP-SCONN,HA!!!F216!DQ(43)!!!!
S!M_B_DQ<44>!J6U1!106!@baseboard_fab2_lib.baseboard_fab2(sch_1):page46_i14@mstr_sconn.sconn288_h44441003(chips)!SCONN288_H44441003_PIP-SCONN,HA!!!F216!DQ(44)!!!!
S!M_B_DQ<45>!J6U1!251!@baseboard_fab2_lib.baseboard_fab2(sch_1):page46_i14@mstr_sconn.sconn288_h44441003(chips)!SCONN288_H44441003_PIP-SCONN,HA!!!F216!DQ(45)!!!!
S!M_B_DQ<46>!J6U1!113!@baseboard_fab2_lib.baseboard_fab2(sch_1):page46_i14@mstr_sconn.sconn288_h44441003(chips)!SCONN288_H44441003_PIP-SCONN,HA!!!F216!DQ(46)!!!!
S!M_B_DQ<47>!J6U1!258!@baseboard_fab2_lib.baseboard_fab2(sch_1):page46_i14@mstr_sconn.sconn288_h44441003(chips)!SCONN288_H44441003_PIP-SCONN,HA!!!F216!DQ(47)!!!!
S!M_B_DQ<48>!J6U1!119!@baseboard_fab2_lib.baseboard_fab2(sch_1):page46_i14@mstr_sconn.sconn288_h44441003(chips)!SCONN288_H44441003_PIP-SCONN,HA!!!F216!DQ(48)!!!!
S!M_B_DQ<49>!J6U1!264!@baseboard_fab2_lib.baseboard_fab2(sch_1):page46_i14@mstr_sconn.sconn288_h44441003(chips)!SCONN288_H44441003_PIP-SCONN,HA!!!F216!DQ(49)!!!!
S!M_B_DQ<4>!J6U1!3!@baseboard_fab2_lib.baseboard_fab2(sch_1):page46_i14@mstr_sconn.sconn288_h44441003(chips)!SCONN288_H44441003_PIP-SCONN,HA!!!F216!DQ(4)!!!!
S!M_B_DQ<50>!J6U1!126!@baseboard_fab2_lib.baseboard_fab2(sch_1):page46_i14@mstr_sconn.sconn288_h44441003(chips)!SCONN288_H44441003_PIP-SCONN,HA!!!F216!DQ(50)!!!!
S!M_B_DQ<51>!J6U1!271!@baseboard_fab2_lib.baseboard_fab2(sch_1):page46_i14@mstr_sconn.sconn288_h44441003(chips)!SCONN288_H44441003_PIP-SCONN,HA!!!F216!DQ(51)!!!!
S!M_B_DQ<52>!J6U1!117!@baseboard_fab2_lib.baseboard_fab2(sch_1):page46_i14@mstr_sconn.sconn288_h44441003(chips)!SCONN288_H44441003_PIP-SCONN,HA!!!F216!DQ(52)!!!!
S!M_B_DQ<53>!J6U1!262!@baseboard_fab2_lib.baseboard_fab2(sch_1):page46_i14@mstr_sconn.sconn288_h44441003(chips)!SCONN288_H44441003_PIP-SCONN,HA!!!F216!DQ(53)!!!!
S!M_B_DQ<54>!J6U1!124!@baseboard_fab2_lib.baseboard_fab2(sch_1):page46_i14@mstr_sconn.sconn288_h44441003(chips)!SCONN288_H44441003_PIP-SCONN,HA!!!F216!DQ(54)!!!!
S!M_B_DQ<55>!J6U1!269!@baseboard_fab2_lib.baseboard_fab2(sch_1):page46_i14@mstr_sconn.sconn288_h44441003(chips)!SCONN288_H44441003_PIP-SCONN,HA!!!F216!DQ(55)!!!!
S!M_B_DQ<56>!J6U1!130!@baseboard_fab2_lib.baseboard_fab2(sch_1):page46_i14@mstr_sconn.sconn288_h44441003(chips)!SCONN288_H44441003_PIP-SCONN,HA!!!F216!DQ(56)!!!!
S!M_B_DQ<57>!J6U1!275!@baseboard_fab2_lib.baseboard_fab2(sch_1):page46_i14@mstr_sconn.sconn288_h44441003(chips)!SCONN288_H44441003_PIP-SCONN,HA!!!F216!DQ(57)!!!!
S!M_B_DQ<58>!J6U1!137!@baseboard_fab2_lib.baseboard_fab2(sch_1):page46_i14@mstr_sconn.sconn288_h44441003(chips)!SCONN288_H44441003_PIP-SCONN,HA!!!F216!DQ(58)!!!!
S!M_B_DQ<59>!J6U1!282!@baseboard_fab2_lib.baseboard_fab2(sch_1):page46_i14@mstr_sconn.sconn288_h44441003(chips)!SCONN288_H44441003_PIP-SCONN,HA!!!F216!DQ(59)!!!!
S!M_B_DQ<5>!J6U1!148!@baseboard_fab2_lib.baseboard_fab2(sch_1):page46_i14@mstr_sconn.sconn288_h44441003(chips)!SCONN288_H44441003_PIP-SCONN,HA!!!F216!DQ(5)!!!!
S!M_B_DQ<60>!J6U1!128!@baseboard_fab2_lib.baseboard_fab2(sch_1):page46_i14@mstr_sconn.sconn288_h44441003(chips)!SCONN288_H44441003_PIP-SCONN,HA!!!F216!DQ(60)!!!!
S!M_B_DQ<61>!J6U1!273!@baseboard_fab2_lib.baseboard_fab2(sch_1):page46_i14@mstr_sconn.sconn288_h44441003(chips)!SCONN288_H44441003_PIP-SCONN,HA!!!F216!DQ(61)!!!!
S!M_B_DQ<62>!J6U1!135!@baseboard_fab2_lib.baseboard_fab2(sch_1):page46_i14@mstr_sconn.sconn288_h44441003(chips)!SCONN288_H44441003_PIP-SCONN,HA!!!F216!DQ(62)!!!!
S!M_B_DQ<63>!J6U1!280!@baseboard_fab2_lib.baseboard_fab2(sch_1):page46_i14@mstr_sconn.sconn288_h44441003(chips)!SCONN288_H44441003_PIP-SCONN,HA!!!F216!DQ(63)!!!!
S!M_B_DQ<6>!J6U1!10!@baseboard_fab2_lib.baseboard_fab2(sch_1):page46_i14@mstr_sconn.sconn288_h44441003(chips)!SCONN288_H44441003_PIP-SCONN,HA!!!F216!DQ(6)!!!!
S!M_B_DQ<7>!J6U1!155!@baseboard_fab2_lib.baseboard_fab2(sch_1):page46_i14@mstr_sconn.sconn288_h44441003(chips)!SCONN288_H44441003_PIP-SCONN,HA!!!F216!DQ(7)!!!!
S!M_B_DQ<8>!J6U1!16!@baseboard_fab2_lib.baseboard_fab2(sch_1):page46_i14@mstr_sconn.sconn288_h44441003(chips)!SCONN288_H44441003_PIP-SCONN,HA!!!F216!DQ(8)!!!!
S!M_B_DQ<9>!J6U1!161!@baseboard_fab2_lib.baseboard_fab2(sch_1):page46_i14@mstr_sconn.sconn288_h44441003(chips)!SCONN288_H44441003_PIP-SCONN,HA!!!F216!DQ(9)!!!!
S!FM_DIMM_EVENT_COD_N!J6U1!78!@baseboard_fab2_lib.baseboard_fab2(sch_1):page46_i14@mstr_sconn.sconn288_h44441003(chips)!SCONN288_H44441003_PIP-SCONN,HA!!!F216!EVENT_N!!!!
S!M_B_ODT<2>!J6U1!87!@baseboard_fab2_lib.baseboard_fab2(sch_1):page46_i14@mstr_sconn.sconn288_h44441003(chips)!SCONN288_H44441003_PIP-SCONN,HA!!!F216!ODT(0)!!!!
S!M_B_ODT<3>!J6U1!91!@baseboard_fab2_lib.baseboard_fab2(sch_1):page46_i14@mstr_sconn.sconn288_h44441003(chips)!SCONN288_H44441003_PIP-SCONN,HA!!!F216!ODT(1)!!!!
S!M_B_PAR!J6U1!222!@baseboard_fab2_lib.baseboard_fab2(sch_1):page46_i14@mstr_sconn.sconn288_h44441003(chips)!SCONN288_H44441003_PIP-SCONN,HA!!!F216!PAR!!!!
S!M_ABC_RST_N!J6U1!58!@baseboard_fab2_lib.baseboard_fab2(sch_1):page46_i14@mstr_sconn.sconn288_h44441003(chips)!SCONN288_H44441003_PIP-SCONN,HA!!!F216!RESET_N!!!!
S!TP_CH_B_DIMM_B1_RFU_0!J6U1!205!@baseboard_fab2_lib.baseboard_fab2(sch_1):page46_i14@mstr_sconn.sconn288_h44441003(chips)!SCONN288_H44441003_PIP-SCONN,HA!!!F216!RFU(0)!!!!
S!TP_CH_B_DIMM_B1_RFU_1!J6U1!227!@baseboard_fab2_lib.baseboard_fab2(sch_1):page46_i14@mstr_sconn.sconn288_h44441003(chips)!SCONN288_H44441003_PIP-SCONN,HA!!!F216!RFU(1)!!!!
S!TP_CH_B_DIMM_B1_RFU_2!J6U1!144!@baseboard_fab2_lib.baseboard_fab2(sch_1):page46_i14@mstr_sconn.sconn288_h44441003(chips)!SCONN288_H44441003_PIP-SCONN,HA!!!F216!RFU(2)!!!!
S!M_B_CS_N<4>!J6U1!84!@baseboard_fab2_lib.baseboard_fab2(sch_1):page46_i14@mstr_sconn.sconn288_h44441003(chips)!SCONN288_H44441003_PIP-SCONN,HA!!!F216!S0_N!!!!
S!M_B_CS_N<5>!J6U1!89!@baseboard_fab2_lib.baseboard_fab2(sch_1):page46_i14@mstr_sconn.sconn288_h44441003(chips)!SCONN288_H44441003_PIP-SCONN,HA!!!F216!S1_N!!!!
S!M_B_CS_N<6>!J6U1!93!@baseboard_fab2_lib.baseboard_fab2(sch_1):page46_i14@mstr_sconn.sconn288_h44441003(chips)!SCONN288_H44441003_PIP-SCONN,HA!!!F216!S2_N_C(0)!!!!
S!M_B_CS_N<7>!J6U1!237!@baseboard_fab2_lib.baseboard_fab2(sch_1):page46_i14@mstr_sconn.sconn288_h44441003(chips)!SCONN288_H44441003_PIP-SCONN,HA!!!F216!S3_N_C(1)!!!!
S!PVPP_ABC!J6U1!139!@baseboard_fab2_lib.baseboard_fab2(sch_1):page46_i14@mstr_sconn.sconn288_h44441003(chips)!SCONN288_H44441003_PIP-SCONN,HA!!!F216!SA(0)!!!!
S!PVPP_ABC!J6U1!140!@baseboard_fab2_lib.baseboard_fab2(sch_1):page46_i14@mstr_sconn.sconn288_h44441003(chips)!SCONN288_H44441003_PIP-SCONN,HA!!!F216!SA(1)!!!!
S!GND!J6U1!238!@baseboard_fab2_lib.baseboard_fab2(sch_1):page46_i14@mstr_sconn.sconn288_h44441003(chips)!SCONN288_H44441003_PIP-SCONN,HA!!!F216!SA(2)!!!!
S!FM_ADR_COMPLETE_ABC_N!J6U1!230!@baseboard_fab2_lib.baseboard_fab2(sch_1):page46_i14@mstr_sconn.sconn288_h44441003(chips)!SCONN288_H44441003_PIP-SCONN,HA!!!F216!SAVE_N_NC!!!!
S!SMB_DDR_ABC_VPP_SCL!J6U1!141!@baseboard_fab2_lib.baseboard_fab2(sch_1):page46_i14@mstr_sconn.sconn288_h44441003(chips)!SCONN288_H44441003_PIP-SCONN,HA!!!F216!SCL!!!!
S!SMB_DDR_ABC_VPP_SDA!J6U1!285!@baseboard_fab2_lib.baseboard_fab2(sch_1):page46_i14@mstr_sconn.sconn288_h44441003(chips)!SCONN288_H44441003_PIP-SCONN,HA!!!F216!SDA!!!!
S!PVPP_ABC!J6U1!284!@baseboard_fab2_lib.baseboard_fab2(sch_1):page46_i14@mstr_sconn.sconn288_h44441003(chips)!SCONN288_H44441003_PIP-SCONN,HA!!!F216!VDDSPD!!!!
S!M_B_VREF!J6U1!146!@baseboard_fab2_lib.baseboard_fab2(sch_1):page46_i14@mstr_sconn.sconn288_h44441003(chips)!SCONN288_H44441003_PIP-SCONN,HA!!!F216!VREFCA!!!!
S!M_B_DQS_DN<0>!J6U1!152!@baseboard_fab2_lib.baseboard_fab2(sch_1):page46_i112@mstr_sconn.sconn288_h44441003(chips)!SCONN288_H44441003_PIP-SCONN,HA!!!F215!DQS0N!!!!
S!M_B_DQS_DP<0>!J6U1!153!@baseboard_fab2_lib.baseboard_fab2(sch_1):page46_i112@mstr_sconn.sconn288_h44441003(chips)!SCONN288_H44441003_PIP-SCONN,HA!!!F215!DQS0P!!!!
S!M_B_DQS_DN<10>!J6U1!19!@baseboard_fab2_lib.baseboard_fab2(sch_1):page46_i112@mstr_sconn.sconn288_h44441003(chips)!SCONN288_H44441003_PIP-SCONN,HA!!!F215!DQS10N!!!!
S!M_B_DQS_DP<10>!J6U1!18!@baseboard_fab2_lib.baseboard_fab2(sch_1):page46_i112@mstr_sconn.sconn288_h44441003(chips)!SCONN288_H44441003_PIP-SCONN,HA!!!F215!DQS10P!!!!
S!M_B_DQS_DN<11>!J6U1!30!@baseboard_fab2_lib.baseboard_fab2(sch_1):page46_i112@mstr_sconn.sconn288_h44441003(chips)!SCONN288_H44441003_PIP-SCONN,HA!!!F215!DQS11N!!!!
S!M_B_DQS_DP<11>!J6U1!29!@baseboard_fab2_lib.baseboard_fab2(sch_1):page46_i112@mstr_sconn.sconn288_h44441003(chips)!SCONN288_H44441003_PIP-SCONN,HA!!!F215!DQS11P!!!!
S!M_B_DQS_DN<12>!J6U1!41!@baseboard_fab2_lib.baseboard_fab2(sch_1):page46_i112@mstr_sconn.sconn288_h44441003(chips)!SCONN288_H44441003_PIP-SCONN,HA!!!F215!DQS12N!!!!
S!M_B_DQS_DP<12>!J6U1!40!@baseboard_fab2_lib.baseboard_fab2(sch_1):page46_i112@mstr_sconn.sconn288_h44441003(chips)!SCONN288_H44441003_PIP-SCONN,HA!!!F215!DQS12P!!!!
S!M_B_DQS_DN<13>!J6U1!100!@baseboard_fab2_lib.baseboard_fab2(sch_1):page46_i112@mstr_sconn.sconn288_h44441003(chips)!SCONN288_H44441003_PIP-SCONN,HA!!!F215!DQS13N!!!!
S!M_B_DQS_DP<13>!J6U1!99!@baseboard_fab2_lib.baseboard_fab2(sch_1):page46_i112@mstr_sconn.sconn288_h44441003(chips)!SCONN288_H44441003_PIP-SCONN,HA!!!F215!DQS13P!!!!
S!M_B_DQS_DN<14>!J6U1!111!@baseboard_fab2_lib.baseboard_fab2(sch_1):page46_i112@mstr_sconn.sconn288_h44441003(chips)!SCONN288_H44441003_PIP-SCONN,HA!!!F215!DQS14N!!!!
S!M_B_DQS_DP<14>!J6U1!110!@baseboard_fab2_lib.baseboard_fab2(sch_1):page46_i112@mstr_sconn.sconn288_h44441003(chips)!SCONN288_H44441003_PIP-SCONN,HA!!!F215!DQS14P!!!!
S!M_B_DQS_DN<15>!J6U1!122!@baseboard_fab2_lib.baseboard_fab2(sch_1):page46_i112@mstr_sconn.sconn288_h44441003(chips)!SCONN288_H44441003_PIP-SCONN,HA!!!F215!DQS15N!!!!
S!M_B_DQS_DP<15>!J6U1!121!@baseboard_fab2_lib.baseboard_fab2(sch_1):page46_i112@mstr_sconn.sconn288_h44441003(chips)!SCONN288_H44441003_PIP-SCONN,HA!!!F215!DQS15P!!!!
S!M_B_DQS_DN<16>!J6U1!133!@baseboard_fab2_lib.baseboard_fab2(sch_1):page46_i112@mstr_sconn.sconn288_h44441003(chips)!SCONN288_H44441003_PIP-SCONN,HA!!!F215!DQS16N!!!!
S!M_B_DQS_DP<16>!J6U1!132!@baseboard_fab2_lib.baseboard_fab2(sch_1):page46_i112@mstr_sconn.sconn288_h44441003(chips)!SCONN288_H44441003_PIP-SCONN,HA!!!F215!DQS16P!!!!
S!M_B_DQS_DN<17>!J6U1!52!@baseboard_fab2_lib.baseboard_fab2(sch_1):page46_i112@mstr_sconn.sconn288_h44441003(chips)!SCONN288_H44441003_PIP-SCONN,HA!!!F215!DQS17N!!!!
S!M_B_DQS_DP<17>!J6U1!51!@baseboard_fab2_lib.baseboard_fab2(sch_1):page46_i112@mstr_sconn.sconn288_h44441003(chips)!SCONN288_H44441003_PIP-SCONN,HA!!!F215!DQS17P!!!!
S!M_B_DQS_DN<1>!J6U1!163!@baseboard_fab2_lib.baseboard_fab2(sch_1):page46_i112@mstr_sconn.sconn288_h44441003(chips)!SCONN288_H44441003_PIP-SCONN,HA!!!F215!DQS1N!!!!
S!M_B_DQS_DP<1>!J6U1!164!@baseboard_fab2_lib.baseboard_fab2(sch_1):page46_i112@mstr_sconn.sconn288_h44441003(chips)!SCONN288_H44441003_PIP-SCONN,HA!!!F215!DQS1P!!!!
S!M_B_DQS_DN<2>!J6U1!174!@baseboard_fab2_lib.baseboard_fab2(sch_1):page46_i112@mstr_sconn.sconn288_h44441003(chips)!SCONN288_H44441003_PIP-SCONN,HA!!!F215!DQS2N!!!!
S!M_B_DQS_DP<2>!J6U1!175!@baseboard_fab2_lib.baseboard_fab2(sch_1):page46_i112@mstr_sconn.sconn288_h44441003(chips)!SCONN288_H44441003_PIP-SCONN,HA!!!F215!DQS2P!!!!
S!M_B_DQS_DN<3>!J6U1!185!@baseboard_fab2_lib.baseboard_fab2(sch_1):page46_i112@mstr_sconn.sconn288_h44441003(chips)!SCONN288_H44441003_PIP-SCONN,HA!!!F215!DQS3N!!!!
S!M_B_DQS_DP<3>!J6U1!186!@baseboard_fab2_lib.baseboard_fab2(sch_1):page46_i112@mstr_sconn.sconn288_h44441003(chips)!SCONN288_H44441003_PIP-SCONN,HA!!!F215!DQS3P!!!!
S!M_B_DQS_DN<4>!J6U1!244!@baseboard_fab2_lib.baseboard_fab2(sch_1):page46_i112@mstr_sconn.sconn288_h44441003(chips)!SCONN288_H44441003_PIP-SCONN,HA!!!F215!DQS4N!!!!
S!M_B_DQS_DP<4>!J6U1!245!@baseboard_fab2_lib.baseboard_fab2(sch_1):page46_i112@mstr_sconn.sconn288_h44441003(chips)!SCONN288_H44441003_PIP-SCONN,HA!!!F215!DQS4P!!!!
S!M_B_DQS_DN<5>!J6U1!255!@baseboard_fab2_lib.baseboard_fab2(sch_1):page46_i112@mstr_sconn.sconn288_h44441003(chips)!SCONN288_H44441003_PIP-SCONN,HA!!!F215!DQS5N!!!!
S!M_B_DQS_DP<5>!J6U1!256!@baseboard_fab2_lib.baseboard_fab2(sch_1):page46_i112@mstr_sconn.sconn288_h44441003(chips)!SCONN288_H44441003_PIP-SCONN,HA!!!F215!DQS5P!!!!
S!M_B_DQS_DN<6>!J6U1!266!@baseboard_fab2_lib.baseboard_fab2(sch_1):page46_i112@mstr_sconn.sconn288_h44441003(chips)!SCONN288_H44441003_PIP-SCONN,HA!!!F215!DQS6N!!!!
S!M_B_DQS_DP<6>!J6U1!267!@baseboard_fab2_lib.baseboard_fab2(sch_1):page46_i112@mstr_sconn.sconn288_h44441003(chips)!SCONN288_H44441003_PIP-SCONN,HA!!!F215!DQS6P!!!!
S!M_B_DQS_DN<7>!J6U1!277!@baseboard_fab2_lib.baseboard_fab2(sch_1):page46_i112@mstr_sconn.sconn288_h44441003(chips)!SCONN288_H44441003_PIP-SCONN,HA!!!F215!DQS7N!!!!
S!M_B_DQS_DP<7>!J6U1!278!@baseboard_fab2_lib.baseboard_fab2(sch_1):page46_i112@mstr_sconn.sconn288_h44441003(chips)!SCONN288_H44441003_PIP-SCONN,HA!!!F215!DQS7P!!!!
S!M_B_DQS_DN<8>!J6U1!196!@baseboard_fab2_lib.baseboard_fab2(sch_1):page46_i112@mstr_sconn.sconn288_h44441003(chips)!SCONN288_H44441003_PIP-SCONN,HA!!!F215!DQS8N!!!!
S!M_B_DQS_DP<8>!J6U1!197!@baseboard_fab2_lib.baseboard_fab2(sch_1):page46_i112@mstr_sconn.sconn288_h44441003(chips)!SCONN288_H44441003_PIP-SCONN,HA!!!F215!DQS8P!!!!
S!M_B_DQS_DN<9>!J6U1!8!@baseboard_fab2_lib.baseboard_fab2(sch_1):page46_i112@mstr_sconn.sconn288_h44441003(chips)!SCONN288_H44441003_PIP-SCONN,HA!!!F215!DQS9N!!!!
S!M_B_DQS_DP<9>!J6U1!7!@baseboard_fab2_lib.baseboard_fab2(sch_1):page46_i112@mstr_sconn.sconn288_h44441003(chips)!SCONN288_H44441003_PIP-SCONN,HA!!!F215!DQS9P!!!!
S!GND!J6U1!283!@baseboard_fab2_lib.baseboard_fab2(sch_1):page46_i138@mstr_sconn.sconn288_h44441003(chips)!SCONN288_H44441003_PIP-SCONN,HA!!!F214!VSS(0)!!!!
S!GND!J6U1!261!@baseboard_fab2_lib.baseboard_fab2(sch_1):page46_i138@mstr_sconn.sconn288_h44441003(chips)!SCONN288_H44441003_PIP-SCONN,HA!!!F214!VSS(10)!!!!
S!GND!J6U1!259!@baseboard_fab2_lib.baseboard_fab2(sch_1):page46_i138@mstr_sconn.sconn288_h44441003(chips)!SCONN288_H44441003_PIP-SCONN,HA!!!F214!VSS(11)!!!!
S!GND!J6U1!257!@baseboard_fab2_lib.baseboard_fab2(sch_1):page46_i138@mstr_sconn.sconn288_h44441003(chips)!SCONN288_H44441003_PIP-SCONN,HA!!!F214!VSS(12)!!!!
S!GND!J6U1!254!@baseboard_fab2_lib.baseboard_fab2(sch_1):page46_i138@mstr_sconn.sconn288_h44441003(chips)!SCONN288_H44441003_PIP-SCONN,HA!!!F214!VSS(13)!!!!
S!GND!J6U1!252!@baseboard_fab2_lib.baseboard_fab2(sch_1):page46_i138@mstr_sconn.sconn288_h44441003(chips)!SCONN288_H44441003_PIP-SCONN,HA!!!F214!VSS(14)!!!!
S!GND!J6U1!250!@baseboard_fab2_lib.baseboard_fab2(sch_1):page46_i138@mstr_sconn.sconn288_h44441003(chips)!SCONN288_H44441003_PIP-SCONN,HA!!!F214!VSS(15)!!!!
S!GND!J6U1!248!@baseboard_fab2_lib.baseboard_fab2(sch_1):page46_i138@mstr_sconn.sconn288_h44441003(chips)!SCONN288_H44441003_PIP-SCONN,HA!!!F214!VSS(16)!!!!
S!GND!J6U1!246!@baseboard_fab2_lib.baseboard_fab2(sch_1):page46_i138@mstr_sconn.sconn288_h44441003(chips)!SCONN288_H44441003_PIP-SCONN,HA!!!F214!VSS(17)!!!!
S!GND!J6U1!243!@baseboard_fab2_lib.baseboard_fab2(sch_1):page46_i138@mstr_sconn.sconn288_h44441003(chips)!SCONN288_H44441003_PIP-SCONN,HA!!!F214!VSS(18)!!!!
S!GND!J6U1!241!@baseboard_fab2_lib.baseboard_fab2(sch_1):page46_i138@mstr_sconn.sconn288_h44441003(chips)!SCONN288_H44441003_PIP-SCONN,HA!!!F214!VSS(19)!!!!
S!GND!J6U1!281!@baseboard_fab2_lib.baseboard_fab2(sch_1):page46_i138@mstr_sconn.sconn288_h44441003(chips)!SCONN288_H44441003_PIP-SCONN,HA!!!F214!VSS(1)!!!!
S!GND!J6U1!239!@baseboard_fab2_lib.baseboard_fab2(sch_1):page46_i138@mstr_sconn.sconn288_h44441003(chips)!SCONN288_H44441003_PIP-SCONN,HA!!!F214!VSS(20)!!!!
S!GND!J6U1!202!@baseboard_fab2_lib.baseboard_fab2(sch_1):page46_i138@mstr_sconn.sconn288_h44441003(chips)!SCONN288_H44441003_PIP-SCONN,HA!!!F214!VSS(21)!!!!
S!GND!J6U1!200!@baseboard_fab2_lib.baseboard_fab2(sch_1):page46_i138@mstr_sconn.sconn288_h44441003(chips)!SCONN288_H44441003_PIP-SCONN,HA!!!F214!VSS(22)!!!!
S!GND!J6U1!198!@baseboard_fab2_lib.baseboard_fab2(sch_1):page46_i138@mstr_sconn.sconn288_h44441003(chips)!SCONN288_H44441003_PIP-SCONN,HA!!!F214!VSS(23)!!!!
S!GND!J6U1!195!@baseboard_fab2_lib.baseboard_fab2(sch_1):page46_i138@mstr_sconn.sconn288_h44441003(chips)!SCONN288_H44441003_PIP-SCONN,HA!!!F214!VSS(24)!!!!
S!GND!J6U1!193!@baseboard_fab2_lib.baseboard_fab2(sch_1):page46_i138@mstr_sconn.sconn288_h44441003(chips)!SCONN288_H44441003_PIP-SCONN,HA!!!F214!VSS(25)!!!!
S!GND!J6U1!191!@baseboard_fab2_lib.baseboard_fab2(sch_1):page46_i138@mstr_sconn.sconn288_h44441003(chips)!SCONN288_H44441003_PIP-SCONN,HA!!!F214!VSS(26)!!!!
S!GND!J6U1!189!@baseboard_fab2_lib.baseboard_fab2(sch_1):page46_i138@mstr_sconn.sconn288_h44441003(chips)!SCONN288_H44441003_PIP-SCONN,HA!!!F214!VSS(27)!!!!
S!GND!J6U1!187!@baseboard_fab2_lib.baseboard_fab2(sch_1):page46_i138@mstr_sconn.sconn288_h44441003(chips)!SCONN288_H44441003_PIP-SCONN,HA!!!F214!VSS(28)!!!!
S!GND!J6U1!184!@baseboard_fab2_lib.baseboard_fab2(sch_1):page46_i138@mstr_sconn.sconn288_h44441003(chips)!SCONN288_H44441003_PIP-SCONN,HA!!!F214!VSS(29)!!!!
S!GND!J6U1!279!@baseboard_fab2_lib.baseboard_fab2(sch_1):page46_i138@mstr_sconn.sconn288_h44441003(chips)!SCONN288_H44441003_PIP-SCONN,HA!!!F214!VSS(2)!!!!
S!GND!J6U1!182!@baseboard_fab2_lib.baseboard_fab2(sch_1):page46_i138@mstr_sconn.sconn288_h44441003(chips)!SCONN288_H44441003_PIP-SCONN,HA!!!F214!VSS(30)!!!!
S!GND!J6U1!180!@baseboard_fab2_lib.baseboard_fab2(sch_1):page46_i138@mstr_sconn.sconn288_h44441003(chips)!SCONN288_H44441003_PIP-SCONN,HA!!!F214!VSS(31)!!!!
S!GND!J6U1!178!@baseboard_fab2_lib.baseboard_fab2(sch_1):page46_i138@mstr_sconn.sconn288_h44441003(chips)!SCONN288_H44441003_PIP-SCONN,HA!!!F214!VSS(32)!!!!
S!GND!J6U1!176!@baseboard_fab2_lib.baseboard_fab2(sch_1):page46_i138@mstr_sconn.sconn288_h44441003(chips)!SCONN288_H44441003_PIP-SCONN,HA!!!F214!VSS(33)!!!!
S!GND!J6U1!173!@baseboard_fab2_lib.baseboard_fab2(sch_1):page46_i138@mstr_sconn.sconn288_h44441003(chips)!SCONN288_H44441003_PIP-SCONN,HA!!!F214!VSS(34)!!!!
S!GND!J6U1!171!@baseboard_fab2_lib.baseboard_fab2(sch_1):page46_i138@mstr_sconn.sconn288_h44441003(chips)!SCONN288_H44441003_PIP-SCONN,HA!!!F214!VSS(35)!!!!
S!GND!J6U1!169!@baseboard_fab2_lib.baseboard_fab2(sch_1):page46_i138@mstr_sconn.sconn288_h44441003(chips)!SCONN288_H44441003_PIP-SCONN,HA!!!F214!VSS(36)!!!!
S!GND!J6U1!167!@baseboard_fab2_lib.baseboard_fab2(sch_1):page46_i138@mstr_sconn.sconn288_h44441003(chips)!SCONN288_H44441003_PIP-SCONN,HA!!!F214!VSS(37)!!!!
S!GND!J6U1!165!@baseboard_fab2_lib.baseboard_fab2(sch_1):page46_i138@mstr_sconn.sconn288_h44441003(chips)!SCONN288_H44441003_PIP-SCONN,HA!!!F214!VSS(38)!!!!
S!GND!J6U1!162!@baseboard_fab2_lib.baseboard_fab2(sch_1):page46_i138@mstr_sconn.sconn288_h44441003(chips)!SCONN288_H44441003_PIP-SCONN,HA!!!F214!VSS(39)!!!!
S!GND!J6U1!276!@baseboard_fab2_lib.baseboard_fab2(sch_1):page46_i138@mstr_sconn.sconn288_h44441003(chips)!SCONN288_H44441003_PIP-SCONN,HA!!!F214!VSS(3)!!!!
S!GND!J6U1!160!@baseboard_fab2_lib.baseboard_fab2(sch_1):page46_i138@mstr_sconn.sconn288_h44441003(chips)!SCONN288_H44441003_PIP-SCONN,HA!!!F214!VSS(40)!!!!
S!GND!J6U1!158!@baseboard_fab2_lib.baseboard_fab2(sch_1):page46_i138@mstr_sconn.sconn288_h44441003(chips)!SCONN288_H44441003_PIP-SCONN,HA!!!F214!VSS(41)!!!!
S!GND!J6U1!156!@baseboard_fab2_lib.baseboard_fab2(sch_1):page46_i138@mstr_sconn.sconn288_h44441003(chips)!SCONN288_H44441003_PIP-SCONN,HA!!!F214!VSS(42)!!!!
S!GND!J6U1!154!@baseboard_fab2_lib.baseboard_fab2(sch_1):page46_i138@mstr_sconn.sconn288_h44441003(chips)!SCONN288_H44441003_PIP-SCONN,HA!!!F214!VSS(43)!!!!
S!GND!J6U1!151!@baseboard_fab2_lib.baseboard_fab2(sch_1):page46_i138@mstr_sconn.sconn288_h44441003(chips)!SCONN288_H44441003_PIP-SCONN,HA!!!F214!VSS(44)!!!!
S!GND!J6U1!149!@baseboard_fab2_lib.baseboard_fab2(sch_1):page46_i138@mstr_sconn.sconn288_h44441003(chips)!SCONN288_H44441003_PIP-SCONN,HA!!!F214!VSS(45)!!!!
S!GND!J6U1!147!@baseboard_fab2_lib.baseboard_fab2(sch_1):page46_i138@mstr_sconn.sconn288_h44441003(chips)!SCONN288_H44441003_PIP-SCONN,HA!!!F214!VSS(46)!!!!
S!GND!J6U1!138!@baseboard_fab2_lib.baseboard_fab2(sch_1):page46_i138@mstr_sconn.sconn288_h44441003(chips)!SCONN288_H44441003_PIP-SCONN,HA!!!F214!VSS(47)!!!!
S!GND!J6U1!136!@baseboard_fab2_lib.baseboard_fab2(sch_1):page46_i138@mstr_sconn.sconn288_h44441003(chips)!SCONN288_H44441003_PIP-SCONN,HA!!!F214!VSS(48)!!!!
S!GND!J6U1!134!@baseboard_fab2_lib.baseboard_fab2(sch_1):page46_i138@mstr_sconn.sconn288_h44441003(chips)!SCONN288_H44441003_PIP-SCONN,HA!!!F214!VSS(49)!!!!
S!GND!J6U1!274!@baseboard_fab2_lib.baseboard_fab2(sch_1):page46_i138@mstr_sconn.sconn288_h44441003(chips)!SCONN288_H44441003_PIP-SCONN,HA!!!F214!VSS(4)!!!!
S!GND!J6U1!131!@baseboard_fab2_lib.baseboard_fab2(sch_1):page46_i138@mstr_sconn.sconn288_h44441003(chips)!SCONN288_H44441003_PIP-SCONN,HA!!!F214!VSS(50)!!!!
S!GND!J6U1!129!@baseboard_fab2_lib.baseboard_fab2(sch_1):page46_i138@mstr_sconn.sconn288_h44441003(chips)!SCONN288_H44441003_PIP-SCONN,HA!!!F214!VSS(51)!!!!
S!GND!J6U1!127!@baseboard_fab2_lib.baseboard_fab2(sch_1):page46_i138@mstr_sconn.sconn288_h44441003(chips)!SCONN288_H44441003_PIP-SCONN,HA!!!F214!VSS(52)!!!!
S!GND!J6U1!125!@baseboard_fab2_lib.baseboard_fab2(sch_1):page46_i138@mstr_sconn.sconn288_h44441003(chips)!SCONN288_H44441003_PIP-SCONN,HA!!!F214!VSS(53)!!!!
S!GND!J6U1!123!@baseboard_fab2_lib.baseboard_fab2(sch_1):page46_i138@mstr_sconn.sconn288_h44441003(chips)!SCONN288_H44441003_PIP-SCONN,HA!!!F214!VSS(54)!!!!
S!GND!J6U1!120!@baseboard_fab2_lib.baseboard_fab2(sch_1):page46_i138@mstr_sconn.sconn288_h44441003(chips)!SCONN288_H44441003_PIP-SCONN,HA!!!F214!VSS(55)!!!!
S!GND!J6U1!118!@baseboard_fab2_lib.baseboard_fab2(sch_1):page46_i138@mstr_sconn.sconn288_h44441003(chips)!SCONN288_H44441003_PIP-SCONN,HA!!!F214!VSS(56)!!!!
S!GND!J6U1!116!@baseboard_fab2_lib.baseboard_fab2(sch_1):page46_i138@mstr_sconn.sconn288_h44441003(chips)!SCONN288_H44441003_PIP-SCONN,HA!!!F214!VSS(57)!!!!
S!GND!J6U1!114!@baseboard_fab2_lib.baseboard_fab2(sch_1):page46_i138@mstr_sconn.sconn288_h44441003(chips)!SCONN288_H44441003_PIP-SCONN,HA!!!F214!VSS(58)!!!!
S!GND!J6U1!112!@baseboard_fab2_lib.baseboard_fab2(sch_1):page46_i138@mstr_sconn.sconn288_h44441003(chips)!SCONN288_H44441003_PIP-SCONN,HA!!!F214!VSS(59)!!!!
S!GND!J6U1!272!@baseboard_fab2_lib.baseboard_fab2(sch_1):page46_i138@mstr_sconn.sconn288_h44441003(chips)!SCONN288_H44441003_PIP-SCONN,HA!!!F214!VSS(5)!!!!
S!GND!J6U1!109!@baseboard_fab2_lib.baseboard_fab2(sch_1):page46_i138@mstr_sconn.sconn288_h44441003(chips)!SCONN288_H44441003_PIP-SCONN,HA!!!F214!VSS(60)!!!!
S!GND!J6U1!107!@baseboard_fab2_lib.baseboard_fab2(sch_1):page46_i138@mstr_sconn.sconn288_h44441003(chips)!SCONN288_H44441003_PIP-SCONN,HA!!!F214!VSS(61)!!!!
S!GND!J6U1!105!@baseboard_fab2_lib.baseboard_fab2(sch_1):page46_i138@mstr_sconn.sconn288_h44441003(chips)!SCONN288_H44441003_PIP-SCONN,HA!!!F214!VSS(62)!!!!
S!GND!J6U1!103!@baseboard_fab2_lib.baseboard_fab2(sch_1):page46_i138@mstr_sconn.sconn288_h44441003(chips)!SCONN288_H44441003_PIP-SCONN,HA!!!F214!VSS(63)!!!!
S!GND!J6U1!101!@baseboard_fab2_lib.baseboard_fab2(sch_1):page46_i138@mstr_sconn.sconn288_h44441003(chips)!SCONN288_H44441003_PIP-SCONN,HA!!!F214!VSS(64)!!!!
S!GND!J6U1!98!@baseboard_fab2_lib.baseboard_fab2(sch_1):page46_i138@mstr_sconn.sconn288_h44441003(chips)!SCONN288_H44441003_PIP-SCONN,HA!!!F214!VSS(65)!!!!
S!GND!J6U1!96!@baseboard_fab2_lib.baseboard_fab2(sch_1):page46_i138@mstr_sconn.sconn288_h44441003(chips)!SCONN288_H44441003_PIP-SCONN,HA!!!F214!VSS(66)!!!!
S!GND!J6U1!94!@baseboard_fab2_lib.baseboard_fab2(sch_1):page46_i138@mstr_sconn.sconn288_h44441003(chips)!SCONN288_H44441003_PIP-SCONN,HA!!!F214!VSS(67)!!!!
S!GND!J6U1!57!@baseboard_fab2_lib.baseboard_fab2(sch_1):page46_i138@mstr_sconn.sconn288_h44441003(chips)!SCONN288_H44441003_PIP-SCONN,HA!!!F214!VSS(68)!!!!
S!GND!J6U1!55!@baseboard_fab2_lib.baseboard_fab2(sch_1):page46_i138@mstr_sconn.sconn288_h44441003(chips)!SCONN288_H44441003_PIP-SCONN,HA!!!F214!VSS(69)!!!!
S!GND!J6U1!270!@baseboard_fab2_lib.baseboard_fab2(sch_1):page46_i138@mstr_sconn.sconn288_h44441003(chips)!SCONN288_H44441003_PIP-SCONN,HA!!!F214!VSS(6)!!!!
S!GND!J6U1!53!@baseboard_fab2_lib.baseboard_fab2(sch_1):page46_i138@mstr_sconn.sconn288_h44441003(chips)!SCONN288_H44441003_PIP-SCONN,HA!!!F214!VSS(70)!!!!
S!GND!J6U1!50!@baseboard_fab2_lib.baseboard_fab2(sch_1):page46_i138@mstr_sconn.sconn288_h44441003(chips)!SCONN288_H44441003_PIP-SCONN,HA!!!F214!VSS(71)!!!!
S!GND!J6U1!48!@baseboard_fab2_lib.baseboard_fab2(sch_1):page46_i138@mstr_sconn.sconn288_h44441003(chips)!SCONN288_H44441003_PIP-SCONN,HA!!!F214!VSS(72)!!!!
S!GND!J6U1!46!@baseboard_fab2_lib.baseboard_fab2(sch_1):page46_i138@mstr_sconn.sconn288_h44441003(chips)!SCONN288_H44441003_PIP-SCONN,HA!!!F214!VSS(73)!!!!
S!GND!J6U1!44!@baseboard_fab2_lib.baseboard_fab2(sch_1):page46_i138@mstr_sconn.sconn288_h44441003(chips)!SCONN288_H44441003_PIP-SCONN,HA!!!F214!VSS(74)!!!!
S!GND!J6U1!42!@baseboard_fab2_lib.baseboard_fab2(sch_1):page46_i138@mstr_sconn.sconn288_h44441003(chips)!SCONN288_H44441003_PIP-SCONN,HA!!!F214!VSS(75)!!!!
S!GND!J6U1!39!@baseboard_fab2_lib.baseboard_fab2(sch_1):page46_i138@mstr_sconn.sconn288_h44441003(chips)!SCONN288_H44441003_PIP-SCONN,HA!!!F214!VSS(76)!!!!
S!GND!J6U1!37!@baseboard_fab2_lib.baseboard_fab2(sch_1):page46_i138@mstr_sconn.sconn288_h44441003(chips)!SCONN288_H44441003_PIP-SCONN,HA!!!F214!VSS(77)!!!!
S!GND!J6U1!35!@baseboard_fab2_lib.baseboard_fab2(sch_1):page46_i138@mstr_sconn.sconn288_h44441003(chips)!SCONN288_H44441003_PIP-SCONN,HA!!!F214!VSS(78)!!!!
S!GND!J6U1!33!@baseboard_fab2_lib.baseboard_fab2(sch_1):page46_i138@mstr_sconn.sconn288_h44441003(chips)!SCONN288_H44441003_PIP-SCONN,HA!!!F214!VSS(79)!!!!
S!GND!J6U1!268!@baseboard_fab2_lib.baseboard_fab2(sch_1):page46_i138@mstr_sconn.sconn288_h44441003(chips)!SCONN288_H44441003_PIP-SCONN,HA!!!F214!VSS(7)!!!!
S!GND!J6U1!31!@baseboard_fab2_lib.baseboard_fab2(sch_1):page46_i138@mstr_sconn.sconn288_h44441003(chips)!SCONN288_H44441003_PIP-SCONN,HA!!!F214!VSS(80)!!!!
S!GND!J6U1!28!@baseboard_fab2_lib.baseboard_fab2(sch_1):page46_i138@mstr_sconn.sconn288_h44441003(chips)!SCONN288_H44441003_PIP-SCONN,HA!!!F214!VSS(81)!!!!
S!GND!J6U1!26!@baseboard_fab2_lib.baseboard_fab2(sch_1):page46_i138@mstr_sconn.sconn288_h44441003(chips)!SCONN288_H44441003_PIP-SCONN,HA!!!F214!VSS(82)!!!!
S!GND!J6U1!24!@baseboard_fab2_lib.baseboard_fab2(sch_1):page46_i138@mstr_sconn.sconn288_h44441003(chips)!SCONN288_H44441003_PIP-SCONN,HA!!!F214!VSS(83)!!!!
S!GND!J6U1!22!@baseboard_fab2_lib.baseboard_fab2(sch_1):page46_i138@mstr_sconn.sconn288_h44441003(chips)!SCONN288_H44441003_PIP-SCONN,HA!!!F214!VSS(84)!!!!
S!GND!J6U1!20!@baseboard_fab2_lib.baseboard_fab2(sch_1):page46_i138@mstr_sconn.sconn288_h44441003(chips)!SCONN288_H44441003_PIP-SCONN,HA!!!F214!VSS(85)!!!!
S!GND!J6U1!17!@baseboard_fab2_lib.baseboard_fab2(sch_1):page46_i138@mstr_sconn.sconn288_h44441003(chips)!SCONN288_H44441003_PIP-SCONN,HA!!!F214!VSS(86)!!!!
S!GND!J6U1!15!@baseboard_fab2_lib.baseboard_fab2(sch_1):page46_i138@mstr_sconn.sconn288_h44441003(chips)!SCONN288_H44441003_PIP-SCONN,HA!!!F214!VSS(87)!!!!
S!GND!J6U1!13!@baseboard_fab2_lib.baseboard_fab2(sch_1):page46_i138@mstr_sconn.sconn288_h44441003(chips)!SCONN288_H44441003_PIP-SCONN,HA!!!F214!VSS(88)!!!!
S!GND!J6U1!11!@baseboard_fab2_lib.baseboard_fab2(sch_1):page46_i138@mstr_sconn.sconn288_h44441003(chips)!SCONN288_H44441003_PIP-SCONN,HA!!!F214!VSS(89)!!!!
S!GND!J6U1!265!@baseboard_fab2_lib.baseboard_fab2(sch_1):page46_i138@mstr_sconn.sconn288_h44441003(chips)!SCONN288_H44441003_PIP-SCONN,HA!!!F214!VSS(8)!!!!
S!GND!J6U1!9!@baseboard_fab2_lib.baseboard_fab2(sch_1):page46_i138@mstr_sconn.sconn288_h44441003(chips)!SCONN288_H44441003_PIP-SCONN,HA!!!F214!VSS(90)!!!!
S!GND!J6U1!6!@baseboard_fab2_lib.baseboard_fab2(sch_1):page46_i138@mstr_sconn.sconn288_h44441003(chips)!SCONN288_H44441003_PIP-SCONN,HA!!!F214!VSS(91)!!!!
S!GND!J6U1!4!@baseboard_fab2_lib.baseboard_fab2(sch_1):page46_i138@mstr_sconn.sconn288_h44441003(chips)!SCONN288_H44441003_PIP-SCONN,HA!!!F214!VSS(92)!!!!
S!GND!J6U1!2!@baseboard_fab2_lib.baseboard_fab2(sch_1):page46_i138@mstr_sconn.sconn288_h44441003(chips)!SCONN288_H44441003_PIP-SCONN,HA!!!F214!VSS(93)!!!!
S!GND!J6U1!263!@baseboard_fab2_lib.baseboard_fab2(sch_1):page46_i138@mstr_sconn.sconn288_h44441003(chips)!SCONN288_H44441003_PIP-SCONN,HA!!!F214!VSS(9)!!!!
S!P12V_NVDIMM_ABC!J6U1!145!@baseboard_fab2_lib.baseboard_fab2(sch_1):page46_i67@mstr_sconn.sconn288_h44441003(chips)!SCONN288_H44441003_PIP-SCONN,HA!!!F213!\12v\(0)!!!!
S!P12V_NVDIMM_ABC!J6U1!1!@baseboard_fab2_lib.baseboard_fab2(sch_1):page46_i67@mstr_sconn.sconn288_h44441003(chips)!SCONN288_H44441003_PIP-SCONN,HA!!!F213!\12v\(1)!!!!
S!PVDDQ_ABC!J6U1!236!@baseboard_fab2_lib.baseboard_fab2(sch_1):page46_i67@mstr_sconn.sconn288_h44441003(chips)!SCONN288_H44441003_PIP-SCONN,HA!!!F213!VDD(0)!!!!
S!PVDDQ_ABC!J6U1!209!@baseboard_fab2_lib.baseboard_fab2(sch_1):page46_i67@mstr_sconn.sconn288_h44441003(chips)!SCONN288_H44441003_PIP-SCONN,HA!!!F213!VDD(10)!!!!
S!PVDDQ_ABC!J6U1!206!@baseboard_fab2_lib.baseboard_fab2(sch_1):page46_i67@mstr_sconn.sconn288_h44441003(chips)!SCONN288_H44441003_PIP-SCONN,HA!!!F213!VDD(11)!!!!
S!PVDDQ_ABC!J6U1!204!@baseboard_fab2_lib.baseboard_fab2(sch_1):page46_i67@mstr_sconn.sconn288_h44441003(chips)!SCONN288_H44441003_PIP-SCONN,HA!!!F213!VDD(12)!!!!
S!PVDDQ_ABC!J6U1!92!@baseboard_fab2_lib.baseboard_fab2(sch_1):page46_i67@mstr_sconn.sconn288_h44441003(chips)!SCONN288_H44441003_PIP-SCONN,HA!!!F213!VDD(13)!!!!
S!PVDDQ_ABC!J6U1!90!@baseboard_fab2_lib.baseboard_fab2(sch_1):page46_i67@mstr_sconn.sconn288_h44441003(chips)!SCONN288_H44441003_PIP-SCONN,HA!!!F213!VDD(14)!!!!
S!PVDDQ_ABC!J6U1!88!@baseboard_fab2_lib.baseboard_fab2(sch_1):page46_i67@mstr_sconn.sconn288_h44441003(chips)!SCONN288_H44441003_PIP-SCONN,HA!!!F213!VDD(15)!!!!
S!PVDDQ_ABC!J6U1!85!@baseboard_fab2_lib.baseboard_fab2(sch_1):page46_i67@mstr_sconn.sconn288_h44441003(chips)!SCONN288_H44441003_PIP-SCONN,HA!!!F213!VDD(16)!!!!
S!PVDDQ_ABC!J6U1!83!@baseboard_fab2_lib.baseboard_fab2(sch_1):page46_i67@mstr_sconn.sconn288_h44441003(chips)!SCONN288_H44441003_PIP-SCONN,HA!!!F213!VDD(17)!!!!
S!PVDDQ_ABC!J6U1!80!@baseboard_fab2_lib.baseboard_fab2(sch_1):page46_i67@mstr_sconn.sconn288_h44441003(chips)!SCONN288_H44441003_PIP-SCONN,HA!!!F213!VDD(18)!!!!
S!PVDDQ_ABC!J6U1!76!@baseboard_fab2_lib.baseboard_fab2(sch_1):page46_i67@mstr_sconn.sconn288_h44441003(chips)!SCONN288_H44441003_PIP-SCONN,HA!!!F213!VDD(19)!!!!
S!PVDDQ_ABC!J6U1!233!@baseboard_fab2_lib.baseboard_fab2(sch_1):page46_i67@mstr_sconn.sconn288_h44441003(chips)!SCONN288_H44441003_PIP-SCONN,HA!!!F213!VDD(1)!!!!
S!PVDDQ_ABC!J6U1!73!@baseboard_fab2_lib.baseboard_fab2(sch_1):page46_i67@mstr_sconn.sconn288_h44441003(chips)!SCONN288_H44441003_PIP-SCONN,HA!!!F213!VDD(20)!!!!
S!PVDDQ_ABC!J6U1!70!@baseboard_fab2_lib.baseboard_fab2(sch_1):page46_i67@mstr_sconn.sconn288_h44441003(chips)!SCONN288_H44441003_PIP-SCONN,HA!!!F213!VDD(21)!!!!
S!PVDDQ_ABC!J6U1!67!@baseboard_fab2_lib.baseboard_fab2(sch_1):page46_i67@mstr_sconn.sconn288_h44441003(chips)!SCONN288_H44441003_PIP-SCONN,HA!!!F213!VDD(22)!!!!
S!PVDDQ_ABC!J6U1!64!@baseboard_fab2_lib.baseboard_fab2(sch_1):page46_i67@mstr_sconn.sconn288_h44441003(chips)!SCONN288_H44441003_PIP-SCONN,HA!!!F213!VDD(23)!!!!
S!PVDDQ_ABC!J6U1!61!@baseboard_fab2_lib.baseboard_fab2(sch_1):page46_i67@mstr_sconn.sconn288_h44441003(chips)!SCONN288_H44441003_PIP-SCONN,HA!!!F213!VDD(24)!!!!
S!PVDDQ_ABC!J6U1!59!@baseboard_fab2_lib.baseboard_fab2(sch_1):page46_i67@mstr_sconn.sconn288_h44441003(chips)!SCONN288_H44441003_PIP-SCONN,HA!!!F213!VDD(25)!!!!
S!PVDDQ_ABC!J6U1!231!@baseboard_fab2_lib.baseboard_fab2(sch_1):page46_i67@mstr_sconn.sconn288_h44441003(chips)!SCONN288_H44441003_PIP-SCONN,HA!!!F213!VDD(2)!!!!
S!PVDDQ_ABC!J6U1!229!@baseboard_fab2_lib.baseboard_fab2(sch_1):page46_i67@mstr_sconn.sconn288_h44441003(chips)!SCONN288_H44441003_PIP-SCONN,HA!!!F213!VDD(3)!!!!
S!PVDDQ_ABC!J6U1!226!@baseboard_fab2_lib.baseboard_fab2(sch_1):page46_i67@mstr_sconn.sconn288_h44441003(chips)!SCONN288_H44441003_PIP-SCONN,HA!!!F213!VDD(4)!!!!
S!PVDDQ_ABC!J6U1!223!@baseboard_fab2_lib.baseboard_fab2(sch_1):page46_i67@mstr_sconn.sconn288_h44441003(chips)!SCONN288_H44441003_PIP-SCONN,HA!!!F213!VDD(5)!!!!
S!PVDDQ_ABC!J6U1!220!@baseboard_fab2_lib.baseboard_fab2(sch_1):page46_i67@mstr_sconn.sconn288_h44441003(chips)!SCONN288_H44441003_PIP-SCONN,HA!!!F213!VDD(6)!!!!
S!PVDDQ_ABC!J6U1!217!@baseboard_fab2_lib.baseboard_fab2(sch_1):page46_i67@mstr_sconn.sconn288_h44441003(chips)!SCONN288_H44441003_PIP-SCONN,HA!!!F213!VDD(7)!!!!
S!PVDDQ_ABC!J6U1!215!@baseboard_fab2_lib.baseboard_fab2(sch_1):page46_i67@mstr_sconn.sconn288_h44441003(chips)!SCONN288_H44441003_PIP-SCONN,HA!!!F213!VDD(8)!!!!
S!PVDDQ_ABC!J6U1!212!@baseboard_fab2_lib.baseboard_fab2(sch_1):page46_i67@mstr_sconn.sconn288_h44441003(chips)!SCONN288_H44441003_PIP-SCONN,HA!!!F213!VDD(9)!!!!
S!PVPP_ABC!J6U1!287!@baseboard_fab2_lib.baseboard_fab2(sch_1):page46_i67@mstr_sconn.sconn288_h44441003(chips)!SCONN288_H44441003_PIP-SCONN,HA!!!F213!VPP(0)!!!!
S!PVPP_ABC!J6U1!286!@baseboard_fab2_lib.baseboard_fab2(sch_1):page46_i67@mstr_sconn.sconn288_h44441003(chips)!SCONN288_H44441003_PIP-SCONN,HA!!!F213!VPP(1)!!!!
S!PVPP_ABC!J6U1!288!@baseboard_fab2_lib.baseboard_fab2(sch_1):page46_i67@mstr_sconn.sconn288_h44441003(chips)!SCONN288_H44441003_PIP-SCONN,HA!!!F213!VPP(2)!!!!
S!PVPP_ABC!J6U1!143!@baseboard_fab2_lib.baseboard_fab2(sch_1):page46_i67@mstr_sconn.sconn288_h44441003(chips)!SCONN288_H44441003_PIP-SCONN,HA!!!F213!VPP(3)!!!!
S!PVPP_ABC!J6U1!142!@baseboard_fab2_lib.baseboard_fab2(sch_1):page46_i67@mstr_sconn.sconn288_h44441003(chips)!SCONN288_H44441003_PIP-SCONN,HA!!!F213!VPP(4)!!!!
S!PVTT_ABC!J6U1!221!@baseboard_fab2_lib.baseboard_fab2(sch_1):page46_i67@mstr_sconn.sconn288_h44441003(chips)!SCONN288_H44441003_PIP-SCONN,HA!!!F213!VTT(0)!!!!
S!PVTT_ABC!J6U1!77!@baseboard_fab2_lib.baseboard_fab2(sch_1):page46_i67@mstr_sconn.sconn288_h44441003(chips)!SCONN288_H44441003_PIP-SCONN,HA!!!F213!VTT(1)!!!!
S!M_C_MA<0>!J6U2!79!@baseboard_fab2_lib.baseboard_fab2(sch_1):page48_i111@mstr_sconn.sconn288_h44441003(chips)!SCONN288_H44441003_PIP-SCONN,HA!!!F212!A0!!!!
S!M_C_MA<1>!J6U2!72!@baseboard_fab2_lib.baseboard_fab2(sch_1):page48_i111@mstr_sconn.sconn288_h44441003(chips)!SCONN288_H44441003_PIP-SCONN,HA!!!F212!A1!!!!
S!M_C_MA<10>!J6U2!225!@baseboard_fab2_lib.baseboard_fab2(sch_1):page48_i111@mstr_sconn.sconn288_h44441003(chips)!SCONN288_H44441003_PIP-SCONN,HA!!!F212!A10!!!!
S!M_C_MA<11>!J6U2!210!@baseboard_fab2_lib.baseboard_fab2(sch_1):page48_i111@mstr_sconn.sconn288_h44441003(chips)!SCONN288_H44441003_PIP-SCONN,HA!!!F212!A11!!!!
S!M_C_MA<12>!J6U2!65!@baseboard_fab2_lib.baseboard_fab2(sch_1):page48_i111@mstr_sconn.sconn288_h44441003(chips)!SCONN288_H44441003_PIP-SCONN,HA!!!F212!A12!!!!
S!M_C_MA<13>!J6U2!232!@baseboard_fab2_lib.baseboard_fab2(sch_1):page48_i111@mstr_sconn.sconn288_h44441003(chips)!SCONN288_H44441003_PIP-SCONN,HA!!!F212!A13!!!!
S!M_C_MA<14>!J6U2!228!@baseboard_fab2_lib.baseboard_fab2(sch_1):page48_i111@mstr_sconn.sconn288_h44441003(chips)!SCONN288_H44441003_PIP-SCONN,HA!!!F212!A14_WE_N!!!!
S!M_C_MA<15>!J6U2!86!@baseboard_fab2_lib.baseboard_fab2(sch_1):page48_i111@mstr_sconn.sconn288_h44441003(chips)!SCONN288_H44441003_PIP-SCONN,HA!!!F212!A15_CAS_N!!!!
S!M_C_MA<16>!J6U2!82!@baseboard_fab2_lib.baseboard_fab2(sch_1):page48_i111@mstr_sconn.sconn288_h44441003(chips)!SCONN288_H44441003_PIP-SCONN,HA!!!F212!A16_RAS_N!!!!
S!M_C_MA<17>!J6U2!234!@baseboard_fab2_lib.baseboard_fab2(sch_1):page48_i111@mstr_sconn.sconn288_h44441003(chips)!SCONN288_H44441003_PIP-SCONN,HA!!!F212!A17!!!!
S!M_C_MA<2>!J6U2!216!@baseboard_fab2_lib.baseboard_fab2(sch_1):page48_i111@mstr_sconn.sconn288_h44441003(chips)!SCONN288_H44441003_PIP-SCONN,HA!!!F212!A2!!!!
S!M_C_MA<3>!J6U2!71!@baseboard_fab2_lib.baseboard_fab2(sch_1):page48_i111@mstr_sconn.sconn288_h44441003(chips)!SCONN288_H44441003_PIP-SCONN,HA!!!F212!A3!!!!
S!M_C_MA<4>!J6U2!214!@baseboard_fab2_lib.baseboard_fab2(sch_1):page48_i111@mstr_sconn.sconn288_h44441003(chips)!SCONN288_H44441003_PIP-SCONN,HA!!!F212!A4!!!!
S!M_C_MA<5>!J6U2!213!@baseboard_fab2_lib.baseboard_fab2(sch_1):page48_i111@mstr_sconn.sconn288_h44441003(chips)!SCONN288_H44441003_PIP-SCONN,HA!!!F212!A5!!!!
S!M_C_MA<6>!J6U2!69!@baseboard_fab2_lib.baseboard_fab2(sch_1):page48_i111@mstr_sconn.sconn288_h44441003(chips)!SCONN288_H44441003_PIP-SCONN,HA!!!F212!A6!!!!
S!M_C_MA<7>!J6U2!211!@baseboard_fab2_lib.baseboard_fab2(sch_1):page48_i111@mstr_sconn.sconn288_h44441003(chips)!SCONN288_H44441003_PIP-SCONN,HA!!!F212!A7!!!!
S!M_C_MA<8>!J6U2!68!@baseboard_fab2_lib.baseboard_fab2(sch_1):page48_i111@mstr_sconn.sconn288_h44441003(chips)!SCONN288_H44441003_PIP-SCONN,HA!!!F212!A8!!!!
S!M_C_MA<9>!J6U2!66!@baseboard_fab2_lib.baseboard_fab2(sch_1):page48_i111@mstr_sconn.sconn288_h44441003(chips)!SCONN288_H44441003_PIP-SCONN,HA!!!F212!A9!!!!
S!M_C_ACT_N!J6U2!62!@baseboard_fab2_lib.baseboard_fab2(sch_1):page48_i111@mstr_sconn.sconn288_h44441003(chips)!SCONN288_H44441003_PIP-SCONN,HA!!!F212!ACT_N!!!!
S!M_C_ALERT_N!J6U2!208!@baseboard_fab2_lib.baseboard_fab2(sch_1):page48_i111@mstr_sconn.sconn288_h44441003(chips)!SCONN288_H44441003_PIP-SCONN,HA!!!F212!ALERT_N!!!!
S!M_C_BA<0>!J6U2!81!@baseboard_fab2_lib.baseboard_fab2(sch_1):page48_i111@mstr_sconn.sconn288_h44441003(chips)!SCONN288_H44441003_PIP-SCONN,HA!!!F212!BA(0)!!!!
S!M_C_BA<1>!J6U2!224!@baseboard_fab2_lib.baseboard_fab2(sch_1):page48_i111@mstr_sconn.sconn288_h44441003(chips)!SCONN288_H44441003_PIP-SCONN,HA!!!F212!BA(1)!!!!
S!M_C_BG<0>!J6U2!63!@baseboard_fab2_lib.baseboard_fab2(sch_1):page48_i111@mstr_sconn.sconn288_h44441003(chips)!SCONN288_H44441003_PIP-SCONN,HA!!!F212!BG(0)!!!!
S!M_C_BG<1>!J6U2!207!@baseboard_fab2_lib.baseboard_fab2(sch_1):page48_i111@mstr_sconn.sconn288_h44441003(chips)!SCONN288_H44441003_PIP-SCONN,HA!!!F212!BG(1)!!!!
S!M_C_C<2>!J6U2!235!@baseboard_fab2_lib.baseboard_fab2(sch_1):page48_i111@mstr_sconn.sconn288_h44441003(chips)!SCONN288_H44441003_PIP-SCONN,HA!!!F212!C(2)!!!!
S!M_C_ECC<0>!J6U2!49!@baseboard_fab2_lib.baseboard_fab2(sch_1):page48_i111@mstr_sconn.sconn288_h44441003(chips)!SCONN288_H44441003_PIP-SCONN,HA!!!F212!CB(0)!!!!
S!M_C_ECC<1>!J6U2!194!@baseboard_fab2_lib.baseboard_fab2(sch_1):page48_i111@mstr_sconn.sconn288_h44441003(chips)!SCONN288_H44441003_PIP-SCONN,HA!!!F212!CB(1)!!!!
S!M_C_ECC<2>!J6U2!56!@baseboard_fab2_lib.baseboard_fab2(sch_1):page48_i111@mstr_sconn.sconn288_h44441003(chips)!SCONN288_H44441003_PIP-SCONN,HA!!!F212!CB(2)!!!!
S!M_C_ECC<3>!J6U2!201!@baseboard_fab2_lib.baseboard_fab2(sch_1):page48_i111@mstr_sconn.sconn288_h44441003(chips)!SCONN288_H44441003_PIP-SCONN,HA!!!F212!CB(3)!!!!
S!M_C_ECC<4>!J6U2!47!@baseboard_fab2_lib.baseboard_fab2(sch_1):page48_i111@mstr_sconn.sconn288_h44441003(chips)!SCONN288_H44441003_PIP-SCONN,HA!!!F212!CB(4)!!!!
S!M_C_ECC<5>!J6U2!192!@baseboard_fab2_lib.baseboard_fab2(sch_1):page48_i111@mstr_sconn.sconn288_h44441003(chips)!SCONN288_H44441003_PIP-SCONN,HA!!!F212!CB(5)!!!!
S!M_C_ECC<6>!J6U2!54!@baseboard_fab2_lib.baseboard_fab2(sch_1):page48_i111@mstr_sconn.sconn288_h44441003(chips)!SCONN288_H44441003_PIP-SCONN,HA!!!F212!CB(6)!!!!
S!M_C_ECC<7>!J6U2!199!@baseboard_fab2_lib.baseboard_fab2(sch_1):page48_i111@mstr_sconn.sconn288_h44441003(chips)!SCONN288_H44441003_PIP-SCONN,HA!!!F212!CB(7)!!!!
S!M_C_CLK_DN<2>!J6U2!75!@baseboard_fab2_lib.baseboard_fab2(sch_1):page48_i111@mstr_sconn.sconn288_h44441003(chips)!SCONN288_H44441003_PIP-SCONN,HA!!!F212!CK0N!!!!
S!M_C_CLK_DP<2>!J6U2!74!@baseboard_fab2_lib.baseboard_fab2(sch_1):page48_i111@mstr_sconn.sconn288_h44441003(chips)!SCONN288_H44441003_PIP-SCONN,HA!!!F212!CK0P!!!!
S!M_C_CLK_DN<3>!J6U2!219!@baseboard_fab2_lib.baseboard_fab2(sch_1):page48_i111@mstr_sconn.sconn288_h44441003(chips)!SCONN288_H44441003_PIP-SCONN,HA!!!F212!CK1N!!!!
S!M_C_CLK_DP<3>!J6U2!218!@baseboard_fab2_lib.baseboard_fab2(sch_1):page48_i111@mstr_sconn.sconn288_h44441003(chips)!SCONN288_H44441003_PIP-SCONN,HA!!!F212!CK1P!!!!
S!M_C_CKE<2>!J6U2!60!@baseboard_fab2_lib.baseboard_fab2(sch_1):page48_i111@mstr_sconn.sconn288_h44441003(chips)!SCONN288_H44441003_PIP-SCONN,HA!!!F212!CKE(0)!!!!
S!M_C_CKE<3>!J6U2!203!@baseboard_fab2_lib.baseboard_fab2(sch_1):page48_i111@mstr_sconn.sconn288_h44441003(chips)!SCONN288_H44441003_PIP-SCONN,HA!!!F212!CKE(1)!!!!
S!M_C_DQ<0>!J6U2!5!@baseboard_fab2_lib.baseboard_fab2(sch_1):page48_i111@mstr_sconn.sconn288_h44441003(chips)!SCONN288_H44441003_PIP-SCONN,HA!!!F212!DQ(0)!!!!
S!M_C_DQ<10>!J6U2!23!@baseboard_fab2_lib.baseboard_fab2(sch_1):page48_i111@mstr_sconn.sconn288_h44441003(chips)!SCONN288_H44441003_PIP-SCONN,HA!!!F212!DQ(10)!!!!
S!M_C_DQ<11>!J6U2!168!@baseboard_fab2_lib.baseboard_fab2(sch_1):page48_i111@mstr_sconn.sconn288_h44441003(chips)!SCONN288_H44441003_PIP-SCONN,HA!!!F212!DQ(11)!!!!
S!M_C_DQ<12>!J6U2!14!@baseboard_fab2_lib.baseboard_fab2(sch_1):page48_i111@mstr_sconn.sconn288_h44441003(chips)!SCONN288_H44441003_PIP-SCONN,HA!!!F212!DQ(12)!!!!
S!M_C_DQ<13>!J6U2!159!@baseboard_fab2_lib.baseboard_fab2(sch_1):page48_i111@mstr_sconn.sconn288_h44441003(chips)!SCONN288_H44441003_PIP-SCONN,HA!!!F212!DQ(13)!!!!
S!M_C_DQ<14>!J6U2!21!@baseboard_fab2_lib.baseboard_fab2(sch_1):page48_i111@mstr_sconn.sconn288_h44441003(chips)!SCONN288_H44441003_PIP-SCONN,HA!!!F212!DQ(14)!!!!
S!M_C_DQ<15>!J6U2!166!@baseboard_fab2_lib.baseboard_fab2(sch_1):page48_i111@mstr_sconn.sconn288_h44441003(chips)!SCONN288_H44441003_PIP-SCONN,HA!!!F212!DQ(15)!!!!
S!M_C_DQ<16>!J6U2!27!@baseboard_fab2_lib.baseboard_fab2(sch_1):page48_i111@mstr_sconn.sconn288_h44441003(chips)!SCONN288_H44441003_PIP-SCONN,HA!!!F212!DQ(16)!!!!
S!M_C_DQ<17>!J6U2!172!@baseboard_fab2_lib.baseboard_fab2(sch_1):page48_i111@mstr_sconn.sconn288_h44441003(chips)!SCONN288_H44441003_PIP-SCONN,HA!!!F212!DQ(17)!!!!
S!M_C_DQ<18>!J6U2!34!@baseboard_fab2_lib.baseboard_fab2(sch_1):page48_i111@mstr_sconn.sconn288_h44441003(chips)!SCONN288_H44441003_PIP-SCONN,HA!!!F212!DQ(18)!!!!
S!M_C_DQ<19>!J6U2!179!@baseboard_fab2_lib.baseboard_fab2(sch_1):page48_i111@mstr_sconn.sconn288_h44441003(chips)!SCONN288_H44441003_PIP-SCONN,HA!!!F212!DQ(19)!!!!
S!M_C_DQ<1>!J6U2!150!@baseboard_fab2_lib.baseboard_fab2(sch_1):page48_i111@mstr_sconn.sconn288_h44441003(chips)!SCONN288_H44441003_PIP-SCONN,HA!!!F212!DQ(1)!!!!
S!M_C_DQ<20>!J6U2!25!@baseboard_fab2_lib.baseboard_fab2(sch_1):page48_i111@mstr_sconn.sconn288_h44441003(chips)!SCONN288_H44441003_PIP-SCONN,HA!!!F212!DQ(20)!!!!
S!M_C_DQ<21>!J6U2!170!@baseboard_fab2_lib.baseboard_fab2(sch_1):page48_i111@mstr_sconn.sconn288_h44441003(chips)!SCONN288_H44441003_PIP-SCONN,HA!!!F212!DQ(21)!!!!
S!M_C_DQ<22>!J6U2!32!@baseboard_fab2_lib.baseboard_fab2(sch_1):page48_i111@mstr_sconn.sconn288_h44441003(chips)!SCONN288_H44441003_PIP-SCONN,HA!!!F212!DQ(22)!!!!
S!M_C_DQ<23>!J6U2!177!@baseboard_fab2_lib.baseboard_fab2(sch_1):page48_i111@mstr_sconn.sconn288_h44441003(chips)!SCONN288_H44441003_PIP-SCONN,HA!!!F212!DQ(23)!!!!
S!M_C_DQ<24>!J6U2!38!@baseboard_fab2_lib.baseboard_fab2(sch_1):page48_i111@mstr_sconn.sconn288_h44441003(chips)!SCONN288_H44441003_PIP-SCONN,HA!!!F212!DQ(24)!!!!
S!M_C_DQ<25>!J6U2!183!@baseboard_fab2_lib.baseboard_fab2(sch_1):page48_i111@mstr_sconn.sconn288_h44441003(chips)!SCONN288_H44441003_PIP-SCONN,HA!!!F212!DQ(25)!!!!
S!M_C_DQ<26>!J6U2!45!@baseboard_fab2_lib.baseboard_fab2(sch_1):page48_i111@mstr_sconn.sconn288_h44441003(chips)!SCONN288_H44441003_PIP-SCONN,HA!!!F212!DQ(26)!!!!
S!M_C_DQ<27>!J6U2!190!@baseboard_fab2_lib.baseboard_fab2(sch_1):page48_i111@mstr_sconn.sconn288_h44441003(chips)!SCONN288_H44441003_PIP-SCONN,HA!!!F212!DQ(27)!!!!
S!M_C_DQ<28>!J6U2!36!@baseboard_fab2_lib.baseboard_fab2(sch_1):page48_i111@mstr_sconn.sconn288_h44441003(chips)!SCONN288_H44441003_PIP-SCONN,HA!!!F212!DQ(28)!!!!
S!M_C_DQ<29>!J6U2!181!@baseboard_fab2_lib.baseboard_fab2(sch_1):page48_i111@mstr_sconn.sconn288_h44441003(chips)!SCONN288_H44441003_PIP-SCONN,HA!!!F212!DQ(29)!!!!
S!M_C_DQ<2>!J6U2!12!@baseboard_fab2_lib.baseboard_fab2(sch_1):page48_i111@mstr_sconn.sconn288_h44441003(chips)!SCONN288_H44441003_PIP-SCONN,HA!!!F212!DQ(2)!!!!
S!M_C_DQ<30>!J6U2!43!@baseboard_fab2_lib.baseboard_fab2(sch_1):page48_i111@mstr_sconn.sconn288_h44441003(chips)!SCONN288_H44441003_PIP-SCONN,HA!!!F212!DQ(30)!!!!
S!M_C_DQ<31>!J6U2!188!@baseboard_fab2_lib.baseboard_fab2(sch_1):page48_i111@mstr_sconn.sconn288_h44441003(chips)!SCONN288_H44441003_PIP-SCONN,HA!!!F212!DQ(31)!!!!
S!M_C_DQ<32>!J6U2!97!@baseboard_fab2_lib.baseboard_fab2(sch_1):page48_i111@mstr_sconn.sconn288_h44441003(chips)!SCONN288_H44441003_PIP-SCONN,HA!!!F212!DQ(32)!!!!
S!M_C_DQ<33>!J6U2!242!@baseboard_fab2_lib.baseboard_fab2(sch_1):page48_i111@mstr_sconn.sconn288_h44441003(chips)!SCONN288_H44441003_PIP-SCONN,HA!!!F212!DQ(33)!!!!
S!M_C_DQ<34>!J6U2!104!@baseboard_fab2_lib.baseboard_fab2(sch_1):page48_i111@mstr_sconn.sconn288_h44441003(chips)!SCONN288_H44441003_PIP-SCONN,HA!!!F212!DQ(34)!!!!
S!M_C_DQ<35>!J6U2!249!@baseboard_fab2_lib.baseboard_fab2(sch_1):page48_i111@mstr_sconn.sconn288_h44441003(chips)!SCONN288_H44441003_PIP-SCONN,HA!!!F212!DQ(35)!!!!
S!M_C_DQ<36>!J6U2!95!@baseboard_fab2_lib.baseboard_fab2(sch_1):page48_i111@mstr_sconn.sconn288_h44441003(chips)!SCONN288_H44441003_PIP-SCONN,HA!!!F212!DQ(36)!!!!
S!M_C_DQ<37>!J6U2!240!@baseboard_fab2_lib.baseboard_fab2(sch_1):page48_i111@mstr_sconn.sconn288_h44441003(chips)!SCONN288_H44441003_PIP-SCONN,HA!!!F212!DQ(37)!!!!
S!M_C_DQ<38>!J6U2!102!@baseboard_fab2_lib.baseboard_fab2(sch_1):page48_i111@mstr_sconn.sconn288_h44441003(chips)!SCONN288_H44441003_PIP-SCONN,HA!!!F212!DQ(38)!!!!
S!M_C_DQ<39>!J6U2!247!@baseboard_fab2_lib.baseboard_fab2(sch_1):page48_i111@mstr_sconn.sconn288_h44441003(chips)!SCONN288_H44441003_PIP-SCONN,HA!!!F212!DQ(39)!!!!
S!M_C_DQ<3>!J6U2!157!@baseboard_fab2_lib.baseboard_fab2(sch_1):page48_i111@mstr_sconn.sconn288_h44441003(chips)!SCONN288_H44441003_PIP-SCONN,HA!!!F212!DQ(3)!!!!
S!M_C_DQ<40>!J6U2!108!@baseboard_fab2_lib.baseboard_fab2(sch_1):page48_i111@mstr_sconn.sconn288_h44441003(chips)!SCONN288_H44441003_PIP-SCONN,HA!!!F212!DQ(40)!!!!
S!M_C_DQ<41>!J6U2!253!@baseboard_fab2_lib.baseboard_fab2(sch_1):page48_i111@mstr_sconn.sconn288_h44441003(chips)!SCONN288_H44441003_PIP-SCONN,HA!!!F212!DQ(41)!!!!
S!M_C_DQ<42>!J6U2!115!@baseboard_fab2_lib.baseboard_fab2(sch_1):page48_i111@mstr_sconn.sconn288_h44441003(chips)!SCONN288_H44441003_PIP-SCONN,HA!!!F212!DQ(42)!!!!
S!M_C_DQ<43>!J6U2!260!@baseboard_fab2_lib.baseboard_fab2(sch_1):page48_i111@mstr_sconn.sconn288_h44441003(chips)!SCONN288_H44441003_PIP-SCONN,HA!!!F212!DQ(43)!!!!
S!M_C_DQ<44>!J6U2!106!@baseboard_fab2_lib.baseboard_fab2(sch_1):page48_i111@mstr_sconn.sconn288_h44441003(chips)!SCONN288_H44441003_PIP-SCONN,HA!!!F212!DQ(44)!!!!
S!M_C_DQ<45>!J6U2!251!@baseboard_fab2_lib.baseboard_fab2(sch_1):page48_i111@mstr_sconn.sconn288_h44441003(chips)!SCONN288_H44441003_PIP-SCONN,HA!!!F212!DQ(45)!!!!
S!M_C_DQ<46>!J6U2!113!@baseboard_fab2_lib.baseboard_fab2(sch_1):page48_i111@mstr_sconn.sconn288_h44441003(chips)!SCONN288_H44441003_PIP-SCONN,HA!!!F212!DQ(46)!!!!
S!M_C_DQ<47>!J6U2!258!@baseboard_fab2_lib.baseboard_fab2(sch_1):page48_i111@mstr_sconn.sconn288_h44441003(chips)!SCONN288_H44441003_PIP-SCONN,HA!!!F212!DQ(47)!!!!
S!M_C_DQ<48>!J6U2!119!@baseboard_fab2_lib.baseboard_fab2(sch_1):page48_i111@mstr_sconn.sconn288_h44441003(chips)!SCONN288_H44441003_PIP-SCONN,HA!!!F212!DQ(48)!!!!
S!M_C_DQ<49>!J6U2!264!@baseboard_fab2_lib.baseboard_fab2(sch_1):page48_i111@mstr_sconn.sconn288_h44441003(chips)!SCONN288_H44441003_PIP-SCONN,HA!!!F212!DQ(49)!!!!
S!M_C_DQ<4>!J6U2!3!@baseboard_fab2_lib.baseboard_fab2(sch_1):page48_i111@mstr_sconn.sconn288_h44441003(chips)!SCONN288_H44441003_PIP-SCONN,HA!!!F212!DQ(4)!!!!
S!M_C_DQ<50>!J6U2!126!@baseboard_fab2_lib.baseboard_fab2(sch_1):page48_i111@mstr_sconn.sconn288_h44441003(chips)!SCONN288_H44441003_PIP-SCONN,HA!!!F212!DQ(50)!!!!
S!M_C_DQ<51>!J6U2!271!@baseboard_fab2_lib.baseboard_fab2(sch_1):page48_i111@mstr_sconn.sconn288_h44441003(chips)!SCONN288_H44441003_PIP-SCONN,HA!!!F212!DQ(51)!!!!
S!M_C_DQ<52>!J6U2!117!@baseboard_fab2_lib.baseboard_fab2(sch_1):page48_i111@mstr_sconn.sconn288_h44441003(chips)!SCONN288_H44441003_PIP-SCONN,HA!!!F212!DQ(52)!!!!
S!M_C_DQ<53>!J6U2!262!@baseboard_fab2_lib.baseboard_fab2(sch_1):page48_i111@mstr_sconn.sconn288_h44441003(chips)!SCONN288_H44441003_PIP-SCONN,HA!!!F212!DQ(53)!!!!
S!M_C_DQ<54>!J6U2!124!@baseboard_fab2_lib.baseboard_fab2(sch_1):page48_i111@mstr_sconn.sconn288_h44441003(chips)!SCONN288_H44441003_PIP-SCONN,HA!!!F212!DQ(54)!!!!
S!M_C_DQ<55>!J6U2!269!@baseboard_fab2_lib.baseboard_fab2(sch_1):page48_i111@mstr_sconn.sconn288_h44441003(chips)!SCONN288_H44441003_PIP-SCONN,HA!!!F212!DQ(55)!!!!
S!M_C_DQ<56>!J6U2!130!@baseboard_fab2_lib.baseboard_fab2(sch_1):page48_i111@mstr_sconn.sconn288_h44441003(chips)!SCONN288_H44441003_PIP-SCONN,HA!!!F212!DQ(56)!!!!
S!M_C_DQ<57>!J6U2!275!@baseboard_fab2_lib.baseboard_fab2(sch_1):page48_i111@mstr_sconn.sconn288_h44441003(chips)!SCONN288_H44441003_PIP-SCONN,HA!!!F212!DQ(57)!!!!
S!M_C_DQ<58>!J6U2!137!@baseboard_fab2_lib.baseboard_fab2(sch_1):page48_i111@mstr_sconn.sconn288_h44441003(chips)!SCONN288_H44441003_PIP-SCONN,HA!!!F212!DQ(58)!!!!
S!M_C_DQ<59>!J6U2!282!@baseboard_fab2_lib.baseboard_fab2(sch_1):page48_i111@mstr_sconn.sconn288_h44441003(chips)!SCONN288_H44441003_PIP-SCONN,HA!!!F212!DQ(59)!!!!
S!M_C_DQ<5>!J6U2!148!@baseboard_fab2_lib.baseboard_fab2(sch_1):page48_i111@mstr_sconn.sconn288_h44441003(chips)!SCONN288_H44441003_PIP-SCONN,HA!!!F212!DQ(5)!!!!
S!M_C_DQ<60>!J6U2!128!@baseboard_fab2_lib.baseboard_fab2(sch_1):page48_i111@mstr_sconn.sconn288_h44441003(chips)!SCONN288_H44441003_PIP-SCONN,HA!!!F212!DQ(60)!!!!
S!M_C_DQ<61>!J6U2!273!@baseboard_fab2_lib.baseboard_fab2(sch_1):page48_i111@mstr_sconn.sconn288_h44441003(chips)!SCONN288_H44441003_PIP-SCONN,HA!!!F212!DQ(61)!!!!
S!M_C_DQ<62>!J6U2!135!@baseboard_fab2_lib.baseboard_fab2(sch_1):page48_i111@mstr_sconn.sconn288_h44441003(chips)!SCONN288_H44441003_PIP-SCONN,HA!!!F212!DQ(62)!!!!
S!M_C_DQ<63>!J6U2!280!@baseboard_fab2_lib.baseboard_fab2(sch_1):page48_i111@mstr_sconn.sconn288_h44441003(chips)!SCONN288_H44441003_PIP-SCONN,HA!!!F212!DQ(63)!!!!
S!M_C_DQ<6>!J6U2!10!@baseboard_fab2_lib.baseboard_fab2(sch_1):page48_i111@mstr_sconn.sconn288_h44441003(chips)!SCONN288_H44441003_PIP-SCONN,HA!!!F212!DQ(6)!!!!
S!M_C_DQ<7>!J6U2!155!@baseboard_fab2_lib.baseboard_fab2(sch_1):page48_i111@mstr_sconn.sconn288_h44441003(chips)!SCONN288_H44441003_PIP-SCONN,HA!!!F212!DQ(7)!!!!
S!M_C_DQ<8>!J6U2!16!@baseboard_fab2_lib.baseboard_fab2(sch_1):page48_i111@mstr_sconn.sconn288_h44441003(chips)!SCONN288_H44441003_PIP-SCONN,HA!!!F212!DQ(8)!!!!
S!M_C_DQ<9>!J6U2!161!@baseboard_fab2_lib.baseboard_fab2(sch_1):page48_i111@mstr_sconn.sconn288_h44441003(chips)!SCONN288_H44441003_PIP-SCONN,HA!!!F212!DQ(9)!!!!
S!FM_DIMM_EVENT_COD_N!J6U2!78!@baseboard_fab2_lib.baseboard_fab2(sch_1):page48_i111@mstr_sconn.sconn288_h44441003(chips)!SCONN288_H44441003_PIP-SCONN,HA!!!F212!EVENT_N!!!!
S!M_C_ODT<2>!J6U2!87!@baseboard_fab2_lib.baseboard_fab2(sch_1):page48_i111@mstr_sconn.sconn288_h44441003(chips)!SCONN288_H44441003_PIP-SCONN,HA!!!F212!ODT(0)!!!!
S!M_C_ODT<3>!J6U2!91!@baseboard_fab2_lib.baseboard_fab2(sch_1):page48_i111@mstr_sconn.sconn288_h44441003(chips)!SCONN288_H44441003_PIP-SCONN,HA!!!F212!ODT(1)!!!!
S!M_C_PAR!J6U2!222!@baseboard_fab2_lib.baseboard_fab2(sch_1):page48_i111@mstr_sconn.sconn288_h44441003(chips)!SCONN288_H44441003_PIP-SCONN,HA!!!F212!PAR!!!!
S!M_ABC_RST_N!J6U2!58!@baseboard_fab2_lib.baseboard_fab2(sch_1):page48_i111@mstr_sconn.sconn288_h44441003(chips)!SCONN288_H44441003_PIP-SCONN,HA!!!F212!RESET_N!!!!
S!TP_CH_C_DIMM_C1_RFU_0!J6U2!205!@baseboard_fab2_lib.baseboard_fab2(sch_1):page48_i111@mstr_sconn.sconn288_h44441003(chips)!SCONN288_H44441003_PIP-SCONN,HA!!!F212!RFU(0)!!!!
S!TP_CH_C_DIMM_C1_RFU_1!J6U2!227!@baseboard_fab2_lib.baseboard_fab2(sch_1):page48_i111@mstr_sconn.sconn288_h44441003(chips)!SCONN288_H44441003_PIP-SCONN,HA!!!F212!RFU(1)!!!!
S!TP_CH_C_DIMM_C1_RFU_2!J6U2!144!@baseboard_fab2_lib.baseboard_fab2(sch_1):page48_i111@mstr_sconn.sconn288_h44441003(chips)!SCONN288_H44441003_PIP-SCONN,HA!!!F212!RFU(2)!!!!
S!M_C_CS_N<4>!J6U2!84!@baseboard_fab2_lib.baseboard_fab2(sch_1):page48_i111@mstr_sconn.sconn288_h44441003(chips)!SCONN288_H44441003_PIP-SCONN,HA!!!F212!S0_N!!!!
S!M_C_CS_N<5>!J6U2!89!@baseboard_fab2_lib.baseboard_fab2(sch_1):page48_i111@mstr_sconn.sconn288_h44441003(chips)!SCONN288_H44441003_PIP-SCONN,HA!!!F212!S1_N!!!!
S!M_C_CS_N<6>!J6U2!93!@baseboard_fab2_lib.baseboard_fab2(sch_1):page48_i111@mstr_sconn.sconn288_h44441003(chips)!SCONN288_H44441003_PIP-SCONN,HA!!!F212!S2_N_C(0)!!!!
S!M_C_CS_N<7>!J6U2!237!@baseboard_fab2_lib.baseboard_fab2(sch_1):page48_i111@mstr_sconn.sconn288_h44441003(chips)!SCONN288_H44441003_PIP-SCONN,HA!!!F212!S3_N_C(1)!!!!
S!PVPP_ABC!J6U2!139!@baseboard_fab2_lib.baseboard_fab2(sch_1):page48_i111@mstr_sconn.sconn288_h44441003(chips)!SCONN288_H44441003_PIP-SCONN,HA!!!F212!SA(0)!!!!
S!GND!J6U2!140!@baseboard_fab2_lib.baseboard_fab2(sch_1):page48_i111@mstr_sconn.sconn288_h44441003(chips)!SCONN288_H44441003_PIP-SCONN,HA!!!F212!SA(1)!!!!
S!PVPP_ABC!J6U2!238!@baseboard_fab2_lib.baseboard_fab2(sch_1):page48_i111@mstr_sconn.sconn288_h44441003(chips)!SCONN288_H44441003_PIP-SCONN,HA!!!F212!SA(2)!!!!
S!FM_ADR_COMPLETE_ABC_N!J6U2!230!@baseboard_fab2_lib.baseboard_fab2(sch_1):page48_i111@mstr_sconn.sconn288_h44441003(chips)!SCONN288_H44441003_PIP-SCONN,HA!!!F212!SAVE_N_NC!!!!
S!SMB_DDR_ABC_VPP_SCL!J6U2!141!@baseboard_fab2_lib.baseboard_fab2(sch_1):page48_i111@mstr_sconn.sconn288_h44441003(chips)!SCONN288_H44441003_PIP-SCONN,HA!!!F212!SCL!!!!
S!SMB_DDR_ABC_VPP_SDA!J6U2!285!@baseboard_fab2_lib.baseboard_fab2(sch_1):page48_i111@mstr_sconn.sconn288_h44441003(chips)!SCONN288_H44441003_PIP-SCONN,HA!!!F212!SDA!!!!
S!PVPP_ABC!J6U2!284!@baseboard_fab2_lib.baseboard_fab2(sch_1):page48_i111@mstr_sconn.sconn288_h44441003(chips)!SCONN288_H44441003_PIP-SCONN,HA!!!F212!VDDSPD!!!!
S!M_C_VREF!J6U2!146!@baseboard_fab2_lib.baseboard_fab2(sch_1):page48_i111@mstr_sconn.sconn288_h44441003(chips)!SCONN288_H44441003_PIP-SCONN,HA!!!F212!VREFCA!!!!
S!M_C_DQS_DN<0>!J6U2!152!@baseboard_fab2_lib.baseboard_fab2(sch_1):page48_i61@mstr_sconn.sconn288_h44441003(chips)!SCONN288_H44441003_PIP-SCONN,HA!!!F211!DQS0N!!!!
S!M_C_DQS_DP<0>!J6U2!153!@baseboard_fab2_lib.baseboard_fab2(sch_1):page48_i61@mstr_sconn.sconn288_h44441003(chips)!SCONN288_H44441003_PIP-SCONN,HA!!!F211!DQS0P!!!!
S!M_C_DQS_DN<10>!J6U2!19!@baseboard_fab2_lib.baseboard_fab2(sch_1):page48_i61@mstr_sconn.sconn288_h44441003(chips)!SCONN288_H44441003_PIP-SCONN,HA!!!F211!DQS10N!!!!
S!M_C_DQS_DP<10>!J6U2!18!@baseboard_fab2_lib.baseboard_fab2(sch_1):page48_i61@mstr_sconn.sconn288_h44441003(chips)!SCONN288_H44441003_PIP-SCONN,HA!!!F211!DQS10P!!!!
S!M_C_DQS_DN<11>!J6U2!30!@baseboard_fab2_lib.baseboard_fab2(sch_1):page48_i61@mstr_sconn.sconn288_h44441003(chips)!SCONN288_H44441003_PIP-SCONN,HA!!!F211!DQS11N!!!!
S!M_C_DQS_DP<11>!J6U2!29!@baseboard_fab2_lib.baseboard_fab2(sch_1):page48_i61@mstr_sconn.sconn288_h44441003(chips)!SCONN288_H44441003_PIP-SCONN,HA!!!F211!DQS11P!!!!
S!M_C_DQS_DN<12>!J6U2!41!@baseboard_fab2_lib.baseboard_fab2(sch_1):page48_i61@mstr_sconn.sconn288_h44441003(chips)!SCONN288_H44441003_PIP-SCONN,HA!!!F211!DQS12N!!!!
S!M_C_DQS_DP<12>!J6U2!40!@baseboard_fab2_lib.baseboard_fab2(sch_1):page48_i61@mstr_sconn.sconn288_h44441003(chips)!SCONN288_H44441003_PIP-SCONN,HA!!!F211!DQS12P!!!!
S!M_C_DQS_DN<13>!J6U2!100!@baseboard_fab2_lib.baseboard_fab2(sch_1):page48_i61@mstr_sconn.sconn288_h44441003(chips)!SCONN288_H44441003_PIP-SCONN,HA!!!F211!DQS13N!!!!
S!M_C_DQS_DP<13>!J6U2!99!@baseboard_fab2_lib.baseboard_fab2(sch_1):page48_i61@mstr_sconn.sconn288_h44441003(chips)!SCONN288_H44441003_PIP-SCONN,HA!!!F211!DQS13P!!!!
S!M_C_DQS_DN<14>!J6U2!111!@baseboard_fab2_lib.baseboard_fab2(sch_1):page48_i61@mstr_sconn.sconn288_h44441003(chips)!SCONN288_H44441003_PIP-SCONN,HA!!!F211!DQS14N!!!!
S!M_C_DQS_DP<14>!J6U2!110!@baseboard_fab2_lib.baseboard_fab2(sch_1):page48_i61@mstr_sconn.sconn288_h44441003(chips)!SCONN288_H44441003_PIP-SCONN,HA!!!F211!DQS14P!!!!
S!M_C_DQS_DN<15>!J6U2!122!@baseboard_fab2_lib.baseboard_fab2(sch_1):page48_i61@mstr_sconn.sconn288_h44441003(chips)!SCONN288_H44441003_PIP-SCONN,HA!!!F211!DQS15N!!!!
S!M_C_DQS_DP<15>!J6U2!121!@baseboard_fab2_lib.baseboard_fab2(sch_1):page48_i61@mstr_sconn.sconn288_h44441003(chips)!SCONN288_H44441003_PIP-SCONN,HA!!!F211!DQS15P!!!!
S!M_C_DQS_DN<16>!J6U2!133!@baseboard_fab2_lib.baseboard_fab2(sch_1):page48_i61@mstr_sconn.sconn288_h44441003(chips)!SCONN288_H44441003_PIP-SCONN,HA!!!F211!DQS16N!!!!
S!M_C_DQS_DP<16>!J6U2!132!@baseboard_fab2_lib.baseboard_fab2(sch_1):page48_i61@mstr_sconn.sconn288_h44441003(chips)!SCONN288_H44441003_PIP-SCONN,HA!!!F211!DQS16P!!!!
S!M_C_DQS_DN<17>!J6U2!52!@baseboard_fab2_lib.baseboard_fab2(sch_1):page48_i61@mstr_sconn.sconn288_h44441003(chips)!SCONN288_H44441003_PIP-SCONN,HA!!!F211!DQS17N!!!!
S!M_C_DQS_DP<17>!J6U2!51!@baseboard_fab2_lib.baseboard_fab2(sch_1):page48_i61@mstr_sconn.sconn288_h44441003(chips)!SCONN288_H44441003_PIP-SCONN,HA!!!F211!DQS17P!!!!
S!M_C_DQS_DN<1>!J6U2!163!@baseboard_fab2_lib.baseboard_fab2(sch_1):page48_i61@mstr_sconn.sconn288_h44441003(chips)!SCONN288_H44441003_PIP-SCONN,HA!!!F211!DQS1N!!!!
S!M_C_DQS_DP<1>!J6U2!164!@baseboard_fab2_lib.baseboard_fab2(sch_1):page48_i61@mstr_sconn.sconn288_h44441003(chips)!SCONN288_H44441003_PIP-SCONN,HA!!!F211!DQS1P!!!!
S!M_C_DQS_DN<2>!J6U2!174!@baseboard_fab2_lib.baseboard_fab2(sch_1):page48_i61@mstr_sconn.sconn288_h44441003(chips)!SCONN288_H44441003_PIP-SCONN,HA!!!F211!DQS2N!!!!
S!M_C_DQS_DP<2>!J6U2!175!@baseboard_fab2_lib.baseboard_fab2(sch_1):page48_i61@mstr_sconn.sconn288_h44441003(chips)!SCONN288_H44441003_PIP-SCONN,HA!!!F211!DQS2P!!!!
S!M_C_DQS_DN<3>!J6U2!185!@baseboard_fab2_lib.baseboard_fab2(sch_1):page48_i61@mstr_sconn.sconn288_h44441003(chips)!SCONN288_H44441003_PIP-SCONN,HA!!!F211!DQS3N!!!!
S!M_C_DQS_DP<3>!J6U2!186!@baseboard_fab2_lib.baseboard_fab2(sch_1):page48_i61@mstr_sconn.sconn288_h44441003(chips)!SCONN288_H44441003_PIP-SCONN,HA!!!F211!DQS3P!!!!
S!M_C_DQS_DN<4>!J6U2!244!@baseboard_fab2_lib.baseboard_fab2(sch_1):page48_i61@mstr_sconn.sconn288_h44441003(chips)!SCONN288_H44441003_PIP-SCONN,HA!!!F211!DQS4N!!!!
S!M_C_DQS_DP<4>!J6U2!245!@baseboard_fab2_lib.baseboard_fab2(sch_1):page48_i61@mstr_sconn.sconn288_h44441003(chips)!SCONN288_H44441003_PIP-SCONN,HA!!!F211!DQS4P!!!!
S!M_C_DQS_DN<5>!J6U2!255!@baseboard_fab2_lib.baseboard_fab2(sch_1):page48_i61@mstr_sconn.sconn288_h44441003(chips)!SCONN288_H44441003_PIP-SCONN,HA!!!F211!DQS5N!!!!
S!M_C_DQS_DP<5>!J6U2!256!@baseboard_fab2_lib.baseboard_fab2(sch_1):page48_i61@mstr_sconn.sconn288_h44441003(chips)!SCONN288_H44441003_PIP-SCONN,HA!!!F211!DQS5P!!!!
S!M_C_DQS_DN<6>!J6U2!266!@baseboard_fab2_lib.baseboard_fab2(sch_1):page48_i61@mstr_sconn.sconn288_h44441003(chips)!SCONN288_H44441003_PIP-SCONN,HA!!!F211!DQS6N!!!!
S!M_C_DQS_DP<6>!J6U2!267!@baseboard_fab2_lib.baseboard_fab2(sch_1):page48_i61@mstr_sconn.sconn288_h44441003(chips)!SCONN288_H44441003_PIP-SCONN,HA!!!F211!DQS6P!!!!
S!M_C_DQS_DN<7>!J6U2!277!@baseboard_fab2_lib.baseboard_fab2(sch_1):page48_i61@mstr_sconn.sconn288_h44441003(chips)!SCONN288_H44441003_PIP-SCONN,HA!!!F211!DQS7N!!!!
S!M_C_DQS_DP<7>!J6U2!278!@baseboard_fab2_lib.baseboard_fab2(sch_1):page48_i61@mstr_sconn.sconn288_h44441003(chips)!SCONN288_H44441003_PIP-SCONN,HA!!!F211!DQS7P!!!!
S!M_C_DQS_DN<8>!J6U2!196!@baseboard_fab2_lib.baseboard_fab2(sch_1):page48_i61@mstr_sconn.sconn288_h44441003(chips)!SCONN288_H44441003_PIP-SCONN,HA!!!F211!DQS8N!!!!
S!M_C_DQS_DP<8>!J6U2!197!@baseboard_fab2_lib.baseboard_fab2(sch_1):page48_i61@mstr_sconn.sconn288_h44441003(chips)!SCONN288_H44441003_PIP-SCONN,HA!!!F211!DQS8P!!!!
S!M_C_DQS_DN<9>!J6U2!8!@baseboard_fab2_lib.baseboard_fab2(sch_1):page48_i61@mstr_sconn.sconn288_h44441003(chips)!SCONN288_H44441003_PIP-SCONN,HA!!!F211!DQS9N!!!!
S!M_C_DQS_DP<9>!J6U2!7!@baseboard_fab2_lib.baseboard_fab2(sch_1):page48_i61@mstr_sconn.sconn288_h44441003(chips)!SCONN288_H44441003_PIP-SCONN,HA!!!F211!DQS9P!!!!
S!GND!J6U2!283!@baseboard_fab2_lib.baseboard_fab2(sch_1):page48_i43@mstr_sconn.sconn288_h44441003(chips)!SCONN288_H44441003_PIP-SCONN,HA!!!F210!VSS(0)!!!!
S!GND!J6U2!261!@baseboard_fab2_lib.baseboard_fab2(sch_1):page48_i43@mstr_sconn.sconn288_h44441003(chips)!SCONN288_H44441003_PIP-SCONN,HA!!!F210!VSS(10)!!!!
S!GND!J6U2!259!@baseboard_fab2_lib.baseboard_fab2(sch_1):page48_i43@mstr_sconn.sconn288_h44441003(chips)!SCONN288_H44441003_PIP-SCONN,HA!!!F210!VSS(11)!!!!
S!GND!J6U2!257!@baseboard_fab2_lib.baseboard_fab2(sch_1):page48_i43@mstr_sconn.sconn288_h44441003(chips)!SCONN288_H44441003_PIP-SCONN,HA!!!F210!VSS(12)!!!!
S!GND!J6U2!254!@baseboard_fab2_lib.baseboard_fab2(sch_1):page48_i43@mstr_sconn.sconn288_h44441003(chips)!SCONN288_H44441003_PIP-SCONN,HA!!!F210!VSS(13)!!!!
S!GND!J6U2!252!@baseboard_fab2_lib.baseboard_fab2(sch_1):page48_i43@mstr_sconn.sconn288_h44441003(chips)!SCONN288_H44441003_PIP-SCONN,HA!!!F210!VSS(14)!!!!
S!GND!J6U2!250!@baseboard_fab2_lib.baseboard_fab2(sch_1):page48_i43@mstr_sconn.sconn288_h44441003(chips)!SCONN288_H44441003_PIP-SCONN,HA!!!F210!VSS(15)!!!!
S!GND!J6U2!248!@baseboard_fab2_lib.baseboard_fab2(sch_1):page48_i43@mstr_sconn.sconn288_h44441003(chips)!SCONN288_H44441003_PIP-SCONN,HA!!!F210!VSS(16)!!!!
S!GND!J6U2!246!@baseboard_fab2_lib.baseboard_fab2(sch_1):page48_i43@mstr_sconn.sconn288_h44441003(chips)!SCONN288_H44441003_PIP-SCONN,HA!!!F210!VSS(17)!!!!
S!GND!J6U2!243!@baseboard_fab2_lib.baseboard_fab2(sch_1):page48_i43@mstr_sconn.sconn288_h44441003(chips)!SCONN288_H44441003_PIP-SCONN,HA!!!F210!VSS(18)!!!!
S!GND!J6U2!241!@baseboard_fab2_lib.baseboard_fab2(sch_1):page48_i43@mstr_sconn.sconn288_h44441003(chips)!SCONN288_H44441003_PIP-SCONN,HA!!!F210!VSS(19)!!!!
S!GND!J6U2!281!@baseboard_fab2_lib.baseboard_fab2(sch_1):page48_i43@mstr_sconn.sconn288_h44441003(chips)!SCONN288_H44441003_PIP-SCONN,HA!!!F210!VSS(1)!!!!
S!GND!J6U2!239!@baseboard_fab2_lib.baseboard_fab2(sch_1):page48_i43@mstr_sconn.sconn288_h44441003(chips)!SCONN288_H44441003_PIP-SCONN,HA!!!F210!VSS(20)!!!!
S!GND!J6U2!202!@baseboard_fab2_lib.baseboard_fab2(sch_1):page48_i43@mstr_sconn.sconn288_h44441003(chips)!SCONN288_H44441003_PIP-SCONN,HA!!!F210!VSS(21)!!!!
S!GND!J6U2!200!@baseboard_fab2_lib.baseboard_fab2(sch_1):page48_i43@mstr_sconn.sconn288_h44441003(chips)!SCONN288_H44441003_PIP-SCONN,HA!!!F210!VSS(22)!!!!
S!GND!J6U2!198!@baseboard_fab2_lib.baseboard_fab2(sch_1):page48_i43@mstr_sconn.sconn288_h44441003(chips)!SCONN288_H44441003_PIP-SCONN,HA!!!F210!VSS(23)!!!!
S!GND!J6U2!195!@baseboard_fab2_lib.baseboard_fab2(sch_1):page48_i43@mstr_sconn.sconn288_h44441003(chips)!SCONN288_H44441003_PIP-SCONN,HA!!!F210!VSS(24)!!!!
S!GND!J6U2!193!@baseboard_fab2_lib.baseboard_fab2(sch_1):page48_i43@mstr_sconn.sconn288_h44441003(chips)!SCONN288_H44441003_PIP-SCONN,HA!!!F210!VSS(25)!!!!
S!GND!J6U2!191!@baseboard_fab2_lib.baseboard_fab2(sch_1):page48_i43@mstr_sconn.sconn288_h44441003(chips)!SCONN288_H44441003_PIP-SCONN,HA!!!F210!VSS(26)!!!!
S!GND!J6U2!189!@baseboard_fab2_lib.baseboard_fab2(sch_1):page48_i43@mstr_sconn.sconn288_h44441003(chips)!SCONN288_H44441003_PIP-SCONN,HA!!!F210!VSS(27)!!!!
S!GND!J6U2!187!@baseboard_fab2_lib.baseboard_fab2(sch_1):page48_i43@mstr_sconn.sconn288_h44441003(chips)!SCONN288_H44441003_PIP-SCONN,HA!!!F210!VSS(28)!!!!
S!GND!J6U2!184!@baseboard_fab2_lib.baseboard_fab2(sch_1):page48_i43@mstr_sconn.sconn288_h44441003(chips)!SCONN288_H44441003_PIP-SCONN,HA!!!F210!VSS(29)!!!!
S!GND!J6U2!279!@baseboard_fab2_lib.baseboard_fab2(sch_1):page48_i43@mstr_sconn.sconn288_h44441003(chips)!SCONN288_H44441003_PIP-SCONN,HA!!!F210!VSS(2)!!!!
S!GND!J6U2!182!@baseboard_fab2_lib.baseboard_fab2(sch_1):page48_i43@mstr_sconn.sconn288_h44441003(chips)!SCONN288_H44441003_PIP-SCONN,HA!!!F210!VSS(30)!!!!
S!GND!J6U2!180!@baseboard_fab2_lib.baseboard_fab2(sch_1):page48_i43@mstr_sconn.sconn288_h44441003(chips)!SCONN288_H44441003_PIP-SCONN,HA!!!F210!VSS(31)!!!!
S!GND!J6U2!178!@baseboard_fab2_lib.baseboard_fab2(sch_1):page48_i43@mstr_sconn.sconn288_h44441003(chips)!SCONN288_H44441003_PIP-SCONN,HA!!!F210!VSS(32)!!!!
S!GND!J6U2!176!@baseboard_fab2_lib.baseboard_fab2(sch_1):page48_i43@mstr_sconn.sconn288_h44441003(chips)!SCONN288_H44441003_PIP-SCONN,HA!!!F210!VSS(33)!!!!
S!GND!J6U2!173!@baseboard_fab2_lib.baseboard_fab2(sch_1):page48_i43@mstr_sconn.sconn288_h44441003(chips)!SCONN288_H44441003_PIP-SCONN,HA!!!F210!VSS(34)!!!!
S!GND!J6U2!171!@baseboard_fab2_lib.baseboard_fab2(sch_1):page48_i43@mstr_sconn.sconn288_h44441003(chips)!SCONN288_H44441003_PIP-SCONN,HA!!!F210!VSS(35)!!!!
S!GND!J6U2!169!@baseboard_fab2_lib.baseboard_fab2(sch_1):page48_i43@mstr_sconn.sconn288_h44441003(chips)!SCONN288_H44441003_PIP-SCONN,HA!!!F210!VSS(36)!!!!
S!GND!J6U2!167!@baseboard_fab2_lib.baseboard_fab2(sch_1):page48_i43@mstr_sconn.sconn288_h44441003(chips)!SCONN288_H44441003_PIP-SCONN,HA!!!F210!VSS(37)!!!!
S!GND!J6U2!165!@baseboard_fab2_lib.baseboard_fab2(sch_1):page48_i43@mstr_sconn.sconn288_h44441003(chips)!SCONN288_H44441003_PIP-SCONN,HA!!!F210!VSS(38)!!!!
S!GND!J6U2!162!@baseboard_fab2_lib.baseboard_fab2(sch_1):page48_i43@mstr_sconn.sconn288_h44441003(chips)!SCONN288_H44441003_PIP-SCONN,HA!!!F210!VSS(39)!!!!
S!GND!J6U2!276!@baseboard_fab2_lib.baseboard_fab2(sch_1):page48_i43@mstr_sconn.sconn288_h44441003(chips)!SCONN288_H44441003_PIP-SCONN,HA!!!F210!VSS(3)!!!!
S!GND!J6U2!160!@baseboard_fab2_lib.baseboard_fab2(sch_1):page48_i43@mstr_sconn.sconn288_h44441003(chips)!SCONN288_H44441003_PIP-SCONN,HA!!!F210!VSS(40)!!!!
S!GND!J6U2!158!@baseboard_fab2_lib.baseboard_fab2(sch_1):page48_i43@mstr_sconn.sconn288_h44441003(chips)!SCONN288_H44441003_PIP-SCONN,HA!!!F210!VSS(41)!!!!
S!GND!J6U2!156!@baseboard_fab2_lib.baseboard_fab2(sch_1):page48_i43@mstr_sconn.sconn288_h44441003(chips)!SCONN288_H44441003_PIP-SCONN,HA!!!F210!VSS(42)!!!!
S!GND!J6U2!154!@baseboard_fab2_lib.baseboard_fab2(sch_1):page48_i43@mstr_sconn.sconn288_h44441003(chips)!SCONN288_H44441003_PIP-SCONN,HA!!!F210!VSS(43)!!!!
S!GND!J6U2!151!@baseboard_fab2_lib.baseboard_fab2(sch_1):page48_i43@mstr_sconn.sconn288_h44441003(chips)!SCONN288_H44441003_PIP-SCONN,HA!!!F210!VSS(44)!!!!
S!GND!J6U2!149!@baseboard_fab2_lib.baseboard_fab2(sch_1):page48_i43@mstr_sconn.sconn288_h44441003(chips)!SCONN288_H44441003_PIP-SCONN,HA!!!F210!VSS(45)!!!!
S!GND!J6U2!147!@baseboard_fab2_lib.baseboard_fab2(sch_1):page48_i43@mstr_sconn.sconn288_h44441003(chips)!SCONN288_H44441003_PIP-SCONN,HA!!!F210!VSS(46)!!!!
S!GND!J6U2!138!@baseboard_fab2_lib.baseboard_fab2(sch_1):page48_i43@mstr_sconn.sconn288_h44441003(chips)!SCONN288_H44441003_PIP-SCONN,HA!!!F210!VSS(47)!!!!
S!GND!J6U2!136!@baseboard_fab2_lib.baseboard_fab2(sch_1):page48_i43@mstr_sconn.sconn288_h44441003(chips)!SCONN288_H44441003_PIP-SCONN,HA!!!F210!VSS(48)!!!!
S!GND!J6U2!134!@baseboard_fab2_lib.baseboard_fab2(sch_1):page48_i43@mstr_sconn.sconn288_h44441003(chips)!SCONN288_H44441003_PIP-SCONN,HA!!!F210!VSS(49)!!!!
S!GND!J6U2!274!@baseboard_fab2_lib.baseboard_fab2(sch_1):page48_i43@mstr_sconn.sconn288_h44441003(chips)!SCONN288_H44441003_PIP-SCONN,HA!!!F210!VSS(4)!!!!
S!GND!J6U2!131!@baseboard_fab2_lib.baseboard_fab2(sch_1):page48_i43@mstr_sconn.sconn288_h44441003(chips)!SCONN288_H44441003_PIP-SCONN,HA!!!F210!VSS(50)!!!!
S!GND!J6U2!129!@baseboard_fab2_lib.baseboard_fab2(sch_1):page48_i43@mstr_sconn.sconn288_h44441003(chips)!SCONN288_H44441003_PIP-SCONN,HA!!!F210!VSS(51)!!!!
S!GND!J6U2!127!@baseboard_fab2_lib.baseboard_fab2(sch_1):page48_i43@mstr_sconn.sconn288_h44441003(chips)!SCONN288_H44441003_PIP-SCONN,HA!!!F210!VSS(52)!!!!
S!GND!J6U2!125!@baseboard_fab2_lib.baseboard_fab2(sch_1):page48_i43@mstr_sconn.sconn288_h44441003(chips)!SCONN288_H44441003_PIP-SCONN,HA!!!F210!VSS(53)!!!!
S!GND!J6U2!123!@baseboard_fab2_lib.baseboard_fab2(sch_1):page48_i43@mstr_sconn.sconn288_h44441003(chips)!SCONN288_H44441003_PIP-SCONN,HA!!!F210!VSS(54)!!!!
S!GND!J6U2!120!@baseboard_fab2_lib.baseboard_fab2(sch_1):page48_i43@mstr_sconn.sconn288_h44441003(chips)!SCONN288_H44441003_PIP-SCONN,HA!!!F210!VSS(55)!!!!
S!GND!J6U2!118!@baseboard_fab2_lib.baseboard_fab2(sch_1):page48_i43@mstr_sconn.sconn288_h44441003(chips)!SCONN288_H44441003_PIP-SCONN,HA!!!F210!VSS(56)!!!!
S!GND!J6U2!116!@baseboard_fab2_lib.baseboard_fab2(sch_1):page48_i43@mstr_sconn.sconn288_h44441003(chips)!SCONN288_H44441003_PIP-SCONN,HA!!!F210!VSS(57)!!!!
S!GND!J6U2!114!@baseboard_fab2_lib.baseboard_fab2(sch_1):page48_i43@mstr_sconn.sconn288_h44441003(chips)!SCONN288_H44441003_PIP-SCONN,HA!!!F210!VSS(58)!!!!
S!GND!J6U2!112!@baseboard_fab2_lib.baseboard_fab2(sch_1):page48_i43@mstr_sconn.sconn288_h44441003(chips)!SCONN288_H44441003_PIP-SCONN,HA!!!F210!VSS(59)!!!!
S!GND!J6U2!272!@baseboard_fab2_lib.baseboard_fab2(sch_1):page48_i43@mstr_sconn.sconn288_h44441003(chips)!SCONN288_H44441003_PIP-SCONN,HA!!!F210!VSS(5)!!!!
S!GND!J6U2!109!@baseboard_fab2_lib.baseboard_fab2(sch_1):page48_i43@mstr_sconn.sconn288_h44441003(chips)!SCONN288_H44441003_PIP-SCONN,HA!!!F210!VSS(60)!!!!
S!GND!J6U2!107!@baseboard_fab2_lib.baseboard_fab2(sch_1):page48_i43@mstr_sconn.sconn288_h44441003(chips)!SCONN288_H44441003_PIP-SCONN,HA!!!F210!VSS(61)!!!!
S!GND!J6U2!105!@baseboard_fab2_lib.baseboard_fab2(sch_1):page48_i43@mstr_sconn.sconn288_h44441003(chips)!SCONN288_H44441003_PIP-SCONN,HA!!!F210!VSS(62)!!!!
S!GND!J6U2!103!@baseboard_fab2_lib.baseboard_fab2(sch_1):page48_i43@mstr_sconn.sconn288_h44441003(chips)!SCONN288_H44441003_PIP-SCONN,HA!!!F210!VSS(63)!!!!
S!GND!J6U2!101!@baseboard_fab2_lib.baseboard_fab2(sch_1):page48_i43@mstr_sconn.sconn288_h44441003(chips)!SCONN288_H44441003_PIP-SCONN,HA!!!F210!VSS(64)!!!!
S!GND!J6U2!98!@baseboard_fab2_lib.baseboard_fab2(sch_1):page48_i43@mstr_sconn.sconn288_h44441003(chips)!SCONN288_H44441003_PIP-SCONN,HA!!!F210!VSS(65)!!!!
S!GND!J6U2!96!@baseboard_fab2_lib.baseboard_fab2(sch_1):page48_i43@mstr_sconn.sconn288_h44441003(chips)!SCONN288_H44441003_PIP-SCONN,HA!!!F210!VSS(66)!!!!
S!GND!J6U2!94!@baseboard_fab2_lib.baseboard_fab2(sch_1):page48_i43@mstr_sconn.sconn288_h44441003(chips)!SCONN288_H44441003_PIP-SCONN,HA!!!F210!VSS(67)!!!!
S!GND!J6U2!57!@baseboard_fab2_lib.baseboard_fab2(sch_1):page48_i43@mstr_sconn.sconn288_h44441003(chips)!SCONN288_H44441003_PIP-SCONN,HA!!!F210!VSS(68)!!!!
S!GND!J6U2!55!@baseboard_fab2_lib.baseboard_fab2(sch_1):page48_i43@mstr_sconn.sconn288_h44441003(chips)!SCONN288_H44441003_PIP-SCONN,HA!!!F210!VSS(69)!!!!
S!GND!J6U2!270!@baseboard_fab2_lib.baseboard_fab2(sch_1):page48_i43@mstr_sconn.sconn288_h44441003(chips)!SCONN288_H44441003_PIP-SCONN,HA!!!F210!VSS(6)!!!!
S!GND!J6U2!53!@baseboard_fab2_lib.baseboard_fab2(sch_1):page48_i43@mstr_sconn.sconn288_h44441003(chips)!SCONN288_H44441003_PIP-SCONN,HA!!!F210!VSS(70)!!!!
S!GND!J6U2!50!@baseboard_fab2_lib.baseboard_fab2(sch_1):page48_i43@mstr_sconn.sconn288_h44441003(chips)!SCONN288_H44441003_PIP-SCONN,HA!!!F210!VSS(71)!!!!
S!GND!J6U2!48!@baseboard_fab2_lib.baseboard_fab2(sch_1):page48_i43@mstr_sconn.sconn288_h44441003(chips)!SCONN288_H44441003_PIP-SCONN,HA!!!F210!VSS(72)!!!!
S!GND!J6U2!46!@baseboard_fab2_lib.baseboard_fab2(sch_1):page48_i43@mstr_sconn.sconn288_h44441003(chips)!SCONN288_H44441003_PIP-SCONN,HA!!!F210!VSS(73)!!!!
S!GND!J6U2!44!@baseboard_fab2_lib.baseboard_fab2(sch_1):page48_i43@mstr_sconn.sconn288_h44441003(chips)!SCONN288_H44441003_PIP-SCONN,HA!!!F210!VSS(74)!!!!
S!GND!J6U2!42!@baseboard_fab2_lib.baseboard_fab2(sch_1):page48_i43@mstr_sconn.sconn288_h44441003(chips)!SCONN288_H44441003_PIP-SCONN,HA!!!F210!VSS(75)!!!!
S!GND!J6U2!39!@baseboard_fab2_lib.baseboard_fab2(sch_1):page48_i43@mstr_sconn.sconn288_h44441003(chips)!SCONN288_H44441003_PIP-SCONN,HA!!!F210!VSS(76)!!!!
S!GND!J6U2!37!@baseboard_fab2_lib.baseboard_fab2(sch_1):page48_i43@mstr_sconn.sconn288_h44441003(chips)!SCONN288_H44441003_PIP-SCONN,HA!!!F210!VSS(77)!!!!
S!GND!J6U2!35!@baseboard_fab2_lib.baseboard_fab2(sch_1):page48_i43@mstr_sconn.sconn288_h44441003(chips)!SCONN288_H44441003_PIP-SCONN,HA!!!F210!VSS(78)!!!!
S!GND!J6U2!33!@baseboard_fab2_lib.baseboard_fab2(sch_1):page48_i43@mstr_sconn.sconn288_h44441003(chips)!SCONN288_H44441003_PIP-SCONN,HA!!!F210!VSS(79)!!!!
S!GND!J6U2!268!@baseboard_fab2_lib.baseboard_fab2(sch_1):page48_i43@mstr_sconn.sconn288_h44441003(chips)!SCONN288_H44441003_PIP-SCONN,HA!!!F210!VSS(7)!!!!
S!GND!J6U2!31!@baseboard_fab2_lib.baseboard_fab2(sch_1):page48_i43@mstr_sconn.sconn288_h44441003(chips)!SCONN288_H44441003_PIP-SCONN,HA!!!F210!VSS(80)!!!!
S!GND!J6U2!28!@baseboard_fab2_lib.baseboard_fab2(sch_1):page48_i43@mstr_sconn.sconn288_h44441003(chips)!SCONN288_H44441003_PIP-SCONN,HA!!!F210!VSS(81)!!!!
S!GND!J6U2!26!@baseboard_fab2_lib.baseboard_fab2(sch_1):page48_i43@mstr_sconn.sconn288_h44441003(chips)!SCONN288_H44441003_PIP-SCONN,HA!!!F210!VSS(82)!!!!
S!GND!J6U2!24!@baseboard_fab2_lib.baseboard_fab2(sch_1):page48_i43@mstr_sconn.sconn288_h44441003(chips)!SCONN288_H44441003_PIP-SCONN,HA!!!F210!VSS(83)!!!!
S!GND!J6U2!22!@baseboard_fab2_lib.baseboard_fab2(sch_1):page48_i43@mstr_sconn.sconn288_h44441003(chips)!SCONN288_H44441003_PIP-SCONN,HA!!!F210!VSS(84)!!!!
S!GND!J6U2!20!@baseboard_fab2_lib.baseboard_fab2(sch_1):page48_i43@mstr_sconn.sconn288_h44441003(chips)!SCONN288_H44441003_PIP-SCONN,HA!!!F210!VSS(85)!!!!
S!GND!J6U2!17!@baseboard_fab2_lib.baseboard_fab2(sch_1):page48_i43@mstr_sconn.sconn288_h44441003(chips)!SCONN288_H44441003_PIP-SCONN,HA!!!F210!VSS(86)!!!!
S!GND!J6U2!15!@baseboard_fab2_lib.baseboard_fab2(sch_1):page48_i43@mstr_sconn.sconn288_h44441003(chips)!SCONN288_H44441003_PIP-SCONN,HA!!!F210!VSS(87)!!!!
S!GND!J6U2!13!@baseboard_fab2_lib.baseboard_fab2(sch_1):page48_i43@mstr_sconn.sconn288_h44441003(chips)!SCONN288_H44441003_PIP-SCONN,HA!!!F210!VSS(88)!!!!
S!GND!J6U2!11!@baseboard_fab2_lib.baseboard_fab2(sch_1):page48_i43@mstr_sconn.sconn288_h44441003(chips)!SCONN288_H44441003_PIP-SCONN,HA!!!F210!VSS(89)!!!!
S!GND!J6U2!265!@baseboard_fab2_lib.baseboard_fab2(sch_1):page48_i43@mstr_sconn.sconn288_h44441003(chips)!SCONN288_H44441003_PIP-SCONN,HA!!!F210!VSS(8)!!!!
S!GND!J6U2!9!@baseboard_fab2_lib.baseboard_fab2(sch_1):page48_i43@mstr_sconn.sconn288_h44441003(chips)!SCONN288_H44441003_PIP-SCONN,HA!!!F210!VSS(90)!!!!
S!GND!J6U2!6!@baseboard_fab2_lib.baseboard_fab2(sch_1):page48_i43@mstr_sconn.sconn288_h44441003(chips)!SCONN288_H44441003_PIP-SCONN,HA!!!F210!VSS(91)!!!!
S!GND!J6U2!4!@baseboard_fab2_lib.baseboard_fab2(sch_1):page48_i43@mstr_sconn.sconn288_h44441003(chips)!SCONN288_H44441003_PIP-SCONN,HA!!!F210!VSS(92)!!!!
S!GND!J6U2!2!@baseboard_fab2_lib.baseboard_fab2(sch_1):page48_i43@mstr_sconn.sconn288_h44441003(chips)!SCONN288_H44441003_PIP-SCONN,HA!!!F210!VSS(93)!!!!
S!GND!J6U2!263!@baseboard_fab2_lib.baseboard_fab2(sch_1):page48_i43@mstr_sconn.sconn288_h44441003(chips)!SCONN288_H44441003_PIP-SCONN,HA!!!F210!VSS(9)!!!!
S!P12V_NVDIMM_ABC!J6U2!145!@baseboard_fab2_lib.baseboard_fab2(sch_1):page48_i171@mstr_sconn.sconn288_h44441003(chips)!SCONN288_H44441003_PIP-SCONN,HA!!!F209!\12v\(0)!!!!
S!P12V_NVDIMM_ABC!J6U2!1!@baseboard_fab2_lib.baseboard_fab2(sch_1):page48_i171@mstr_sconn.sconn288_h44441003(chips)!SCONN288_H44441003_PIP-SCONN,HA!!!F209!\12v\(1)!!!!
S!PVDDQ_ABC!J6U2!236!@baseboard_fab2_lib.baseboard_fab2(sch_1):page48_i171@mstr_sconn.sconn288_h44441003(chips)!SCONN288_H44441003_PIP-SCONN,HA!!!F209!VDD(0)!!!!
S!PVDDQ_ABC!J6U2!209!@baseboard_fab2_lib.baseboard_fab2(sch_1):page48_i171@mstr_sconn.sconn288_h44441003(chips)!SCONN288_H44441003_PIP-SCONN,HA!!!F209!VDD(10)!!!!
S!PVDDQ_ABC!J6U2!206!@baseboard_fab2_lib.baseboard_fab2(sch_1):page48_i171@mstr_sconn.sconn288_h44441003(chips)!SCONN288_H44441003_PIP-SCONN,HA!!!F209!VDD(11)!!!!
S!PVDDQ_ABC!J6U2!204!@baseboard_fab2_lib.baseboard_fab2(sch_1):page48_i171@mstr_sconn.sconn288_h44441003(chips)!SCONN288_H44441003_PIP-SCONN,HA!!!F209!VDD(12)!!!!
S!PVDDQ_ABC!J6U2!92!@baseboard_fab2_lib.baseboard_fab2(sch_1):page48_i171@mstr_sconn.sconn288_h44441003(chips)!SCONN288_H44441003_PIP-SCONN,HA!!!F209!VDD(13)!!!!
S!PVDDQ_ABC!J6U2!90!@baseboard_fab2_lib.baseboard_fab2(sch_1):page48_i171@mstr_sconn.sconn288_h44441003(chips)!SCONN288_H44441003_PIP-SCONN,HA!!!F209!VDD(14)!!!!
S!PVDDQ_ABC!J6U2!88!@baseboard_fab2_lib.baseboard_fab2(sch_1):page48_i171@mstr_sconn.sconn288_h44441003(chips)!SCONN288_H44441003_PIP-SCONN,HA!!!F209!VDD(15)!!!!
S!PVDDQ_ABC!J6U2!85!@baseboard_fab2_lib.baseboard_fab2(sch_1):page48_i171@mstr_sconn.sconn288_h44441003(chips)!SCONN288_H44441003_PIP-SCONN,HA!!!F209!VDD(16)!!!!
S!PVDDQ_ABC!J6U2!83!@baseboard_fab2_lib.baseboard_fab2(sch_1):page48_i171@mstr_sconn.sconn288_h44441003(chips)!SCONN288_H44441003_PIP-SCONN,HA!!!F209!VDD(17)!!!!
S!PVDDQ_ABC!J6U2!80!@baseboard_fab2_lib.baseboard_fab2(sch_1):page48_i171@mstr_sconn.sconn288_h44441003(chips)!SCONN288_H44441003_PIP-SCONN,HA!!!F209!VDD(18)!!!!
S!PVDDQ_ABC!J6U2!76!@baseboard_fab2_lib.baseboard_fab2(sch_1):page48_i171@mstr_sconn.sconn288_h44441003(chips)!SCONN288_H44441003_PIP-SCONN,HA!!!F209!VDD(19)!!!!
S!PVDDQ_ABC!J6U2!233!@baseboard_fab2_lib.baseboard_fab2(sch_1):page48_i171@mstr_sconn.sconn288_h44441003(chips)!SCONN288_H44441003_PIP-SCONN,HA!!!F209!VDD(1)!!!!
S!PVDDQ_ABC!J6U2!73!@baseboard_fab2_lib.baseboard_fab2(sch_1):page48_i171@mstr_sconn.sconn288_h44441003(chips)!SCONN288_H44441003_PIP-SCONN,HA!!!F209!VDD(20)!!!!
S!PVDDQ_ABC!J6U2!70!@baseboard_fab2_lib.baseboard_fab2(sch_1):page48_i171@mstr_sconn.sconn288_h44441003(chips)!SCONN288_H44441003_PIP-SCONN,HA!!!F209!VDD(21)!!!!
S!PVDDQ_ABC!J6U2!67!@baseboard_fab2_lib.baseboard_fab2(sch_1):page48_i171@mstr_sconn.sconn288_h44441003(chips)!SCONN288_H44441003_PIP-SCONN,HA!!!F209!VDD(22)!!!!
S!PVDDQ_ABC!J6U2!64!@baseboard_fab2_lib.baseboard_fab2(sch_1):page48_i171@mstr_sconn.sconn288_h44441003(chips)!SCONN288_H44441003_PIP-SCONN,HA!!!F209!VDD(23)!!!!
S!PVDDQ_ABC!J6U2!61!@baseboard_fab2_lib.baseboard_fab2(sch_1):page48_i171@mstr_sconn.sconn288_h44441003(chips)!SCONN288_H44441003_PIP-SCONN,HA!!!F209!VDD(24)!!!!
S!PVDDQ_ABC!J6U2!59!@baseboard_fab2_lib.baseboard_fab2(sch_1):page48_i171@mstr_sconn.sconn288_h44441003(chips)!SCONN288_H44441003_PIP-SCONN,HA!!!F209!VDD(25)!!!!
S!PVDDQ_ABC!J6U2!231!@baseboard_fab2_lib.baseboard_fab2(sch_1):page48_i171@mstr_sconn.sconn288_h44441003(chips)!SCONN288_H44441003_PIP-SCONN,HA!!!F209!VDD(2)!!!!
S!PVDDQ_ABC!J6U2!229!@baseboard_fab2_lib.baseboard_fab2(sch_1):page48_i171@mstr_sconn.sconn288_h44441003(chips)!SCONN288_H44441003_PIP-SCONN,HA!!!F209!VDD(3)!!!!
S!PVDDQ_ABC!J6U2!226!@baseboard_fab2_lib.baseboard_fab2(sch_1):page48_i171@mstr_sconn.sconn288_h44441003(chips)!SCONN288_H44441003_PIP-SCONN,HA!!!F209!VDD(4)!!!!
S!PVDDQ_ABC!J6U2!223!@baseboard_fab2_lib.baseboard_fab2(sch_1):page48_i171@mstr_sconn.sconn288_h44441003(chips)!SCONN288_H44441003_PIP-SCONN,HA!!!F209!VDD(5)!!!!
S!PVDDQ_ABC!J6U2!220!@baseboard_fab2_lib.baseboard_fab2(sch_1):page48_i171@mstr_sconn.sconn288_h44441003(chips)!SCONN288_H44441003_PIP-SCONN,HA!!!F209!VDD(6)!!!!
S!PVDDQ_ABC!J6U2!217!@baseboard_fab2_lib.baseboard_fab2(sch_1):page48_i171@mstr_sconn.sconn288_h44441003(chips)!SCONN288_H44441003_PIP-SCONN,HA!!!F209!VDD(7)!!!!
S!PVDDQ_ABC!J6U2!215!@baseboard_fab2_lib.baseboard_fab2(sch_1):page48_i171@mstr_sconn.sconn288_h44441003(chips)!SCONN288_H44441003_PIP-SCONN,HA!!!F209!VDD(8)!!!!
S!PVDDQ_ABC!J6U2!212!@baseboard_fab2_lib.baseboard_fab2(sch_1):page48_i171@mstr_sconn.sconn288_h44441003(chips)!SCONN288_H44441003_PIP-SCONN,HA!!!F209!VDD(9)!!!!
S!PVPP_ABC!J6U2!287!@baseboard_fab2_lib.baseboard_fab2(sch_1):page48_i171@mstr_sconn.sconn288_h44441003(chips)!SCONN288_H44441003_PIP-SCONN,HA!!!F209!VPP(0)!!!!
S!PVPP_ABC!J6U2!286!@baseboard_fab2_lib.baseboard_fab2(sch_1):page48_i171@mstr_sconn.sconn288_h44441003(chips)!SCONN288_H44441003_PIP-SCONN,HA!!!F209!VPP(1)!!!!
S!PVPP_ABC!J6U2!288!@baseboard_fab2_lib.baseboard_fab2(sch_1):page48_i171@mstr_sconn.sconn288_h44441003(chips)!SCONN288_H44441003_PIP-SCONN,HA!!!F209!VPP(2)!!!!
S!PVPP_ABC!J6U2!143!@baseboard_fab2_lib.baseboard_fab2(sch_1):page48_i171@mstr_sconn.sconn288_h44441003(chips)!SCONN288_H44441003_PIP-SCONN,HA!!!F209!VPP(3)!!!!
S!PVPP_ABC!J6U2!142!@baseboard_fab2_lib.baseboard_fab2(sch_1):page48_i171@mstr_sconn.sconn288_h44441003(chips)!SCONN288_H44441003_PIP-SCONN,HA!!!F209!VPP(4)!!!!
S!PVTT_ABC!J6U2!221!@baseboard_fab2_lib.baseboard_fab2(sch_1):page48_i171@mstr_sconn.sconn288_h44441003(chips)!SCONN288_H44441003_PIP-SCONN,HA!!!F209!VTT(0)!!!!
S!PVTT_ABC!J6U2!77!@baseboard_fab2_lib.baseboard_fab2(sch_1):page48_i171@mstr_sconn.sconn288_h44441003(chips)!SCONN288_H44441003_PIP-SCONN,HA!!!F209!VTT(1)!!!!
S!M_D_MA<0>!J6M1!79!@baseboard_fab2_lib.baseboard_fab2(sch_1):page50_i158@mstr_sconn.sconn288_h44441003(chips)!SCONN288_H44441003_PIP-SCONN,HA!!!F224!A0!!!!
S!M_D_MA<1>!J6M1!72!@baseboard_fab2_lib.baseboard_fab2(sch_1):page50_i158@mstr_sconn.sconn288_h44441003(chips)!SCONN288_H44441003_PIP-SCONN,HA!!!F224!A1!!!!
S!M_D_MA<10>!J6M1!225!@baseboard_fab2_lib.baseboard_fab2(sch_1):page50_i158@mstr_sconn.sconn288_h44441003(chips)!SCONN288_H44441003_PIP-SCONN,HA!!!F224!A10!!!!
S!M_D_MA<11>!J6M1!210!@baseboard_fab2_lib.baseboard_fab2(sch_1):page50_i158@mstr_sconn.sconn288_h44441003(chips)!SCONN288_H44441003_PIP-SCONN,HA!!!F224!A11!!!!
S!M_D_MA<12>!J6M1!65!@baseboard_fab2_lib.baseboard_fab2(sch_1):page50_i158@mstr_sconn.sconn288_h44441003(chips)!SCONN288_H44441003_PIP-SCONN,HA!!!F224!A12!!!!
S!M_D_MA<13>!J6M1!232!@baseboard_fab2_lib.baseboard_fab2(sch_1):page50_i158@mstr_sconn.sconn288_h44441003(chips)!SCONN288_H44441003_PIP-SCONN,HA!!!F224!A13!!!!
S!M_D_MA<14>!J6M1!228!@baseboard_fab2_lib.baseboard_fab2(sch_1):page50_i158@mstr_sconn.sconn288_h44441003(chips)!SCONN288_H44441003_PIP-SCONN,HA!!!F224!A14_WE_N!!!!
S!M_D_MA<15>!J6M1!86!@baseboard_fab2_lib.baseboard_fab2(sch_1):page50_i158@mstr_sconn.sconn288_h44441003(chips)!SCONN288_H44441003_PIP-SCONN,HA!!!F224!A15_CAS_N!!!!
S!M_D_MA<16>!J6M1!82!@baseboard_fab2_lib.baseboard_fab2(sch_1):page50_i158@mstr_sconn.sconn288_h44441003(chips)!SCONN288_H44441003_PIP-SCONN,HA!!!F224!A16_RAS_N!!!!
S!M_D_MA<17>!J6M1!234!@baseboard_fab2_lib.baseboard_fab2(sch_1):page50_i158@mstr_sconn.sconn288_h44441003(chips)!SCONN288_H44441003_PIP-SCONN,HA!!!F224!A17!!!!
S!M_D_MA<2>!J6M1!216!@baseboard_fab2_lib.baseboard_fab2(sch_1):page50_i158@mstr_sconn.sconn288_h44441003(chips)!SCONN288_H44441003_PIP-SCONN,HA!!!F224!A2!!!!
S!M_D_MA<3>!J6M1!71!@baseboard_fab2_lib.baseboard_fab2(sch_1):page50_i158@mstr_sconn.sconn288_h44441003(chips)!SCONN288_H44441003_PIP-SCONN,HA!!!F224!A3!!!!
S!M_D_MA<4>!J6M1!214!@baseboard_fab2_lib.baseboard_fab2(sch_1):page50_i158@mstr_sconn.sconn288_h44441003(chips)!SCONN288_H44441003_PIP-SCONN,HA!!!F224!A4!!!!
S!M_D_MA<5>!J6M1!213!@baseboard_fab2_lib.baseboard_fab2(sch_1):page50_i158@mstr_sconn.sconn288_h44441003(chips)!SCONN288_H44441003_PIP-SCONN,HA!!!F224!A5!!!!
S!M_D_MA<6>!J6M1!69!@baseboard_fab2_lib.baseboard_fab2(sch_1):page50_i158@mstr_sconn.sconn288_h44441003(chips)!SCONN288_H44441003_PIP-SCONN,HA!!!F224!A6!!!!
S!M_D_MA<7>!J6M1!211!@baseboard_fab2_lib.baseboard_fab2(sch_1):page50_i158@mstr_sconn.sconn288_h44441003(chips)!SCONN288_H44441003_PIP-SCONN,HA!!!F224!A7!!!!
S!M_D_MA<8>!J6M1!68!@baseboard_fab2_lib.baseboard_fab2(sch_1):page50_i158@mstr_sconn.sconn288_h44441003(chips)!SCONN288_H44441003_PIP-SCONN,HA!!!F224!A8!!!!
S!M_D_MA<9>!J6M1!66!@baseboard_fab2_lib.baseboard_fab2(sch_1):page50_i158@mstr_sconn.sconn288_h44441003(chips)!SCONN288_H44441003_PIP-SCONN,HA!!!F224!A9!!!!
S!M_D_ACT_N!J6M1!62!@baseboard_fab2_lib.baseboard_fab2(sch_1):page50_i158@mstr_sconn.sconn288_h44441003(chips)!SCONN288_H44441003_PIP-SCONN,HA!!!F224!ACT_N!!!!
S!M_D_ALERT_N!J6M1!208!@baseboard_fab2_lib.baseboard_fab2(sch_1):page50_i158@mstr_sconn.sconn288_h44441003(chips)!SCONN288_H44441003_PIP-SCONN,HA!!!F224!ALERT_N!!!!
S!M_D_BA<0>!J6M1!81!@baseboard_fab2_lib.baseboard_fab2(sch_1):page50_i158@mstr_sconn.sconn288_h44441003(chips)!SCONN288_H44441003_PIP-SCONN,HA!!!F224!BA(0)!!!!
S!M_D_BA<1>!J6M1!224!@baseboard_fab2_lib.baseboard_fab2(sch_1):page50_i158@mstr_sconn.sconn288_h44441003(chips)!SCONN288_H44441003_PIP-SCONN,HA!!!F224!BA(1)!!!!
S!M_D_BG<0>!J6M1!63!@baseboard_fab2_lib.baseboard_fab2(sch_1):page50_i158@mstr_sconn.sconn288_h44441003(chips)!SCONN288_H44441003_PIP-SCONN,HA!!!F224!BG(0)!!!!
S!M_D_BG<1>!J6M1!207!@baseboard_fab2_lib.baseboard_fab2(sch_1):page50_i158@mstr_sconn.sconn288_h44441003(chips)!SCONN288_H44441003_PIP-SCONN,HA!!!F224!BG(1)!!!!
S!M_D_C<2>!J6M1!235!@baseboard_fab2_lib.baseboard_fab2(sch_1):page50_i158@mstr_sconn.sconn288_h44441003(chips)!SCONN288_H44441003_PIP-SCONN,HA!!!F224!C(2)!!!!
S!M_D_ECC<0>!J6M1!49!@baseboard_fab2_lib.baseboard_fab2(sch_1):page50_i158@mstr_sconn.sconn288_h44441003(chips)!SCONN288_H44441003_PIP-SCONN,HA!!!F224!CB(0)!!!!
S!M_D_ECC<1>!J6M1!194!@baseboard_fab2_lib.baseboard_fab2(sch_1):page50_i158@mstr_sconn.sconn288_h44441003(chips)!SCONN288_H44441003_PIP-SCONN,HA!!!F224!CB(1)!!!!
S!M_D_ECC<2>!J6M1!56!@baseboard_fab2_lib.baseboard_fab2(sch_1):page50_i158@mstr_sconn.sconn288_h44441003(chips)!SCONN288_H44441003_PIP-SCONN,HA!!!F224!CB(2)!!!!
S!M_D_ECC<3>!J6M1!201!@baseboard_fab2_lib.baseboard_fab2(sch_1):page50_i158@mstr_sconn.sconn288_h44441003(chips)!SCONN288_H44441003_PIP-SCONN,HA!!!F224!CB(3)!!!!
S!M_D_ECC<4>!J6M1!47!@baseboard_fab2_lib.baseboard_fab2(sch_1):page50_i158@mstr_sconn.sconn288_h44441003(chips)!SCONN288_H44441003_PIP-SCONN,HA!!!F224!CB(4)!!!!
S!M_D_ECC<5>!J6M1!192!@baseboard_fab2_lib.baseboard_fab2(sch_1):page50_i158@mstr_sconn.sconn288_h44441003(chips)!SCONN288_H44441003_PIP-SCONN,HA!!!F224!CB(5)!!!!
S!M_D_ECC<6>!J6M1!54!@baseboard_fab2_lib.baseboard_fab2(sch_1):page50_i158@mstr_sconn.sconn288_h44441003(chips)!SCONN288_H44441003_PIP-SCONN,HA!!!F224!CB(6)!!!!
S!M_D_ECC<7>!J6M1!199!@baseboard_fab2_lib.baseboard_fab2(sch_1):page50_i158@mstr_sconn.sconn288_h44441003(chips)!SCONN288_H44441003_PIP-SCONN,HA!!!F224!CB(7)!!!!
S!M_D_CLK_DN<2>!J6M1!75!@baseboard_fab2_lib.baseboard_fab2(sch_1):page50_i158@mstr_sconn.sconn288_h44441003(chips)!SCONN288_H44441003_PIP-SCONN,HA!!!F224!CK0N!!!!
S!M_D_CLK_DP<2>!J6M1!74!@baseboard_fab2_lib.baseboard_fab2(sch_1):page50_i158@mstr_sconn.sconn288_h44441003(chips)!SCONN288_H44441003_PIP-SCONN,HA!!!F224!CK0P!!!!
S!M_D_CLK_DN<3>!J6M1!219!@baseboard_fab2_lib.baseboard_fab2(sch_1):page50_i158@mstr_sconn.sconn288_h44441003(chips)!SCONN288_H44441003_PIP-SCONN,HA!!!F224!CK1N!!!!
S!M_D_CLK_DP<3>!J6M1!218!@baseboard_fab2_lib.baseboard_fab2(sch_1):page50_i158@mstr_sconn.sconn288_h44441003(chips)!SCONN288_H44441003_PIP-SCONN,HA!!!F224!CK1P!!!!
S!M_D_CKE<2>!J6M1!60!@baseboard_fab2_lib.baseboard_fab2(sch_1):page50_i158@mstr_sconn.sconn288_h44441003(chips)!SCONN288_H44441003_PIP-SCONN,HA!!!F224!CKE(0)!!!!
S!M_D_CKE<3>!J6M1!203!@baseboard_fab2_lib.baseboard_fab2(sch_1):page50_i158@mstr_sconn.sconn288_h44441003(chips)!SCONN288_H44441003_PIP-SCONN,HA!!!F224!CKE(1)!!!!
S!M_D_DQ<0>!J6M1!5!@baseboard_fab2_lib.baseboard_fab2(sch_1):page50_i158@mstr_sconn.sconn288_h44441003(chips)!SCONN288_H44441003_PIP-SCONN,HA!!!F224!DQ(0)!!!!
S!M_D_DQ<10>!J6M1!23!@baseboard_fab2_lib.baseboard_fab2(sch_1):page50_i158@mstr_sconn.sconn288_h44441003(chips)!SCONN288_H44441003_PIP-SCONN,HA!!!F224!DQ(10)!!!!
S!M_D_DQ<11>!J6M1!168!@baseboard_fab2_lib.baseboard_fab2(sch_1):page50_i158@mstr_sconn.sconn288_h44441003(chips)!SCONN288_H44441003_PIP-SCONN,HA!!!F224!DQ(11)!!!!
S!M_D_DQ<12>!J6M1!14!@baseboard_fab2_lib.baseboard_fab2(sch_1):page50_i158@mstr_sconn.sconn288_h44441003(chips)!SCONN288_H44441003_PIP-SCONN,HA!!!F224!DQ(12)!!!!
S!M_D_DQ<13>!J6M1!159!@baseboard_fab2_lib.baseboard_fab2(sch_1):page50_i158@mstr_sconn.sconn288_h44441003(chips)!SCONN288_H44441003_PIP-SCONN,HA!!!F224!DQ(13)!!!!
S!M_D_DQ<14>!J6M1!21!@baseboard_fab2_lib.baseboard_fab2(sch_1):page50_i158@mstr_sconn.sconn288_h44441003(chips)!SCONN288_H44441003_PIP-SCONN,HA!!!F224!DQ(14)!!!!
S!M_D_DQ<15>!J6M1!166!@baseboard_fab2_lib.baseboard_fab2(sch_1):page50_i158@mstr_sconn.sconn288_h44441003(chips)!SCONN288_H44441003_PIP-SCONN,HA!!!F224!DQ(15)!!!!
S!M_D_DQ<16>!J6M1!27!@baseboard_fab2_lib.baseboard_fab2(sch_1):page50_i158@mstr_sconn.sconn288_h44441003(chips)!SCONN288_H44441003_PIP-SCONN,HA!!!F224!DQ(16)!!!!
S!M_D_DQ<17>!J6M1!172!@baseboard_fab2_lib.baseboard_fab2(sch_1):page50_i158@mstr_sconn.sconn288_h44441003(chips)!SCONN288_H44441003_PIP-SCONN,HA!!!F224!DQ(17)!!!!
S!M_D_DQ<18>!J6M1!34!@baseboard_fab2_lib.baseboard_fab2(sch_1):page50_i158@mstr_sconn.sconn288_h44441003(chips)!SCONN288_H44441003_PIP-SCONN,HA!!!F224!DQ(18)!!!!
S!M_D_DQ<19>!J6M1!179!@baseboard_fab2_lib.baseboard_fab2(sch_1):page50_i158@mstr_sconn.sconn288_h44441003(chips)!SCONN288_H44441003_PIP-SCONN,HA!!!F224!DQ(19)!!!!
S!M_D_DQ<1>!J6M1!150!@baseboard_fab2_lib.baseboard_fab2(sch_1):page50_i158@mstr_sconn.sconn288_h44441003(chips)!SCONN288_H44441003_PIP-SCONN,HA!!!F224!DQ(1)!!!!
S!M_D_DQ<20>!J6M1!25!@baseboard_fab2_lib.baseboard_fab2(sch_1):page50_i158@mstr_sconn.sconn288_h44441003(chips)!SCONN288_H44441003_PIP-SCONN,HA!!!F224!DQ(20)!!!!
S!M_D_DQ<21>!J6M1!170!@baseboard_fab2_lib.baseboard_fab2(sch_1):page50_i158@mstr_sconn.sconn288_h44441003(chips)!SCONN288_H44441003_PIP-SCONN,HA!!!F224!DQ(21)!!!!
S!M_D_DQ<22>!J6M1!32!@baseboard_fab2_lib.baseboard_fab2(sch_1):page50_i158@mstr_sconn.sconn288_h44441003(chips)!SCONN288_H44441003_PIP-SCONN,HA!!!F224!DQ(22)!!!!
S!M_D_DQ<23>!J6M1!177!@baseboard_fab2_lib.baseboard_fab2(sch_1):page50_i158@mstr_sconn.sconn288_h44441003(chips)!SCONN288_H44441003_PIP-SCONN,HA!!!F224!DQ(23)!!!!
S!M_D_DQ<24>!J6M1!38!@baseboard_fab2_lib.baseboard_fab2(sch_1):page50_i158@mstr_sconn.sconn288_h44441003(chips)!SCONN288_H44441003_PIP-SCONN,HA!!!F224!DQ(24)!!!!
S!M_D_DQ<25>!J6M1!183!@baseboard_fab2_lib.baseboard_fab2(sch_1):page50_i158@mstr_sconn.sconn288_h44441003(chips)!SCONN288_H44441003_PIP-SCONN,HA!!!F224!DQ(25)!!!!
S!M_D_DQ<26>!J6M1!45!@baseboard_fab2_lib.baseboard_fab2(sch_1):page50_i158@mstr_sconn.sconn288_h44441003(chips)!SCONN288_H44441003_PIP-SCONN,HA!!!F224!DQ(26)!!!!
S!M_D_DQ<27>!J6M1!190!@baseboard_fab2_lib.baseboard_fab2(sch_1):page50_i158@mstr_sconn.sconn288_h44441003(chips)!SCONN288_H44441003_PIP-SCONN,HA!!!F224!DQ(27)!!!!
S!M_D_DQ<28>!J6M1!36!@baseboard_fab2_lib.baseboard_fab2(sch_1):page50_i158@mstr_sconn.sconn288_h44441003(chips)!SCONN288_H44441003_PIP-SCONN,HA!!!F224!DQ(28)!!!!
S!M_D_DQ<29>!J6M1!181!@baseboard_fab2_lib.baseboard_fab2(sch_1):page50_i158@mstr_sconn.sconn288_h44441003(chips)!SCONN288_H44441003_PIP-SCONN,HA!!!F224!DQ(29)!!!!
S!M_D_DQ<2>!J6M1!12!@baseboard_fab2_lib.baseboard_fab2(sch_1):page50_i158@mstr_sconn.sconn288_h44441003(chips)!SCONN288_H44441003_PIP-SCONN,HA!!!F224!DQ(2)!!!!
S!M_D_DQ<30>!J6M1!43!@baseboard_fab2_lib.baseboard_fab2(sch_1):page50_i158@mstr_sconn.sconn288_h44441003(chips)!SCONN288_H44441003_PIP-SCONN,HA!!!F224!DQ(30)!!!!
S!M_D_DQ<31>!J6M1!188!@baseboard_fab2_lib.baseboard_fab2(sch_1):page50_i158@mstr_sconn.sconn288_h44441003(chips)!SCONN288_H44441003_PIP-SCONN,HA!!!F224!DQ(31)!!!!
S!M_D_DQ<32>!J6M1!97!@baseboard_fab2_lib.baseboard_fab2(sch_1):page50_i158@mstr_sconn.sconn288_h44441003(chips)!SCONN288_H44441003_PIP-SCONN,HA!!!F224!DQ(32)!!!!
S!M_D_DQ<33>!J6M1!242!@baseboard_fab2_lib.baseboard_fab2(sch_1):page50_i158@mstr_sconn.sconn288_h44441003(chips)!SCONN288_H44441003_PIP-SCONN,HA!!!F224!DQ(33)!!!!
S!M_D_DQ<34>!J6M1!104!@baseboard_fab2_lib.baseboard_fab2(sch_1):page50_i158@mstr_sconn.sconn288_h44441003(chips)!SCONN288_H44441003_PIP-SCONN,HA!!!F224!DQ(34)!!!!
S!M_D_DQ<35>!J6M1!249!@baseboard_fab2_lib.baseboard_fab2(sch_1):page50_i158@mstr_sconn.sconn288_h44441003(chips)!SCONN288_H44441003_PIP-SCONN,HA!!!F224!DQ(35)!!!!
S!M_D_DQ<36>!J6M1!95!@baseboard_fab2_lib.baseboard_fab2(sch_1):page50_i158@mstr_sconn.sconn288_h44441003(chips)!SCONN288_H44441003_PIP-SCONN,HA!!!F224!DQ(36)!!!!
S!M_D_DQ<37>!J6M1!240!@baseboard_fab2_lib.baseboard_fab2(sch_1):page50_i158@mstr_sconn.sconn288_h44441003(chips)!SCONN288_H44441003_PIP-SCONN,HA!!!F224!DQ(37)!!!!
S!M_D_DQ<38>!J6M1!102!@baseboard_fab2_lib.baseboard_fab2(sch_1):page50_i158@mstr_sconn.sconn288_h44441003(chips)!SCONN288_H44441003_PIP-SCONN,HA!!!F224!DQ(38)!!!!
S!M_D_DQ<39>!J6M1!247!@baseboard_fab2_lib.baseboard_fab2(sch_1):page50_i158@mstr_sconn.sconn288_h44441003(chips)!SCONN288_H44441003_PIP-SCONN,HA!!!F224!DQ(39)!!!!
S!M_D_DQ<3>!J6M1!157!@baseboard_fab2_lib.baseboard_fab2(sch_1):page50_i158@mstr_sconn.sconn288_h44441003(chips)!SCONN288_H44441003_PIP-SCONN,HA!!!F224!DQ(3)!!!!
S!M_D_DQ<40>!J6M1!108!@baseboard_fab2_lib.baseboard_fab2(sch_1):page50_i158@mstr_sconn.sconn288_h44441003(chips)!SCONN288_H44441003_PIP-SCONN,HA!!!F224!DQ(40)!!!!
S!M_D_DQ<41>!J6M1!253!@baseboard_fab2_lib.baseboard_fab2(sch_1):page50_i158@mstr_sconn.sconn288_h44441003(chips)!SCONN288_H44441003_PIP-SCONN,HA!!!F224!DQ(41)!!!!
S!M_D_DQ<42>!J6M1!115!@baseboard_fab2_lib.baseboard_fab2(sch_1):page50_i158@mstr_sconn.sconn288_h44441003(chips)!SCONN288_H44441003_PIP-SCONN,HA!!!F224!DQ(42)!!!!
S!M_D_DQ<43>!J6M1!260!@baseboard_fab2_lib.baseboard_fab2(sch_1):page50_i158@mstr_sconn.sconn288_h44441003(chips)!SCONN288_H44441003_PIP-SCONN,HA!!!F224!DQ(43)!!!!
S!M_D_DQ<44>!J6M1!106!@baseboard_fab2_lib.baseboard_fab2(sch_1):page50_i158@mstr_sconn.sconn288_h44441003(chips)!SCONN288_H44441003_PIP-SCONN,HA!!!F224!DQ(44)!!!!
S!M_D_DQ<45>!J6M1!251!@baseboard_fab2_lib.baseboard_fab2(sch_1):page50_i158@mstr_sconn.sconn288_h44441003(chips)!SCONN288_H44441003_PIP-SCONN,HA!!!F224!DQ(45)!!!!
S!M_D_DQ<46>!J6M1!113!@baseboard_fab2_lib.baseboard_fab2(sch_1):page50_i158@mstr_sconn.sconn288_h44441003(chips)!SCONN288_H44441003_PIP-SCONN,HA!!!F224!DQ(46)!!!!
S!M_D_DQ<47>!J6M1!258!@baseboard_fab2_lib.baseboard_fab2(sch_1):page50_i158@mstr_sconn.sconn288_h44441003(chips)!SCONN288_H44441003_PIP-SCONN,HA!!!F224!DQ(47)!!!!
S!M_D_DQ<48>!J6M1!119!@baseboard_fab2_lib.baseboard_fab2(sch_1):page50_i158@mstr_sconn.sconn288_h44441003(chips)!SCONN288_H44441003_PIP-SCONN,HA!!!F224!DQ(48)!!!!
S!M_D_DQ<49>!J6M1!264!@baseboard_fab2_lib.baseboard_fab2(sch_1):page50_i158@mstr_sconn.sconn288_h44441003(chips)!SCONN288_H44441003_PIP-SCONN,HA!!!F224!DQ(49)!!!!
S!M_D_DQ<4>!J6M1!3!@baseboard_fab2_lib.baseboard_fab2(sch_1):page50_i158@mstr_sconn.sconn288_h44441003(chips)!SCONN288_H44441003_PIP-SCONN,HA!!!F224!DQ(4)!!!!
S!M_D_DQ<50>!J6M1!126!@baseboard_fab2_lib.baseboard_fab2(sch_1):page50_i158@mstr_sconn.sconn288_h44441003(chips)!SCONN288_H44441003_PIP-SCONN,HA!!!F224!DQ(50)!!!!
S!M_D_DQ<51>!J6M1!271!@baseboard_fab2_lib.baseboard_fab2(sch_1):page50_i158@mstr_sconn.sconn288_h44441003(chips)!SCONN288_H44441003_PIP-SCONN,HA!!!F224!DQ(51)!!!!
S!M_D_DQ<52>!J6M1!117!@baseboard_fab2_lib.baseboard_fab2(sch_1):page50_i158@mstr_sconn.sconn288_h44441003(chips)!SCONN288_H44441003_PIP-SCONN,HA!!!F224!DQ(52)!!!!
S!M_D_DQ<53>!J6M1!262!@baseboard_fab2_lib.baseboard_fab2(sch_1):page50_i158@mstr_sconn.sconn288_h44441003(chips)!SCONN288_H44441003_PIP-SCONN,HA!!!F224!DQ(53)!!!!
S!M_D_DQ<54>!J6M1!124!@baseboard_fab2_lib.baseboard_fab2(sch_1):page50_i158@mstr_sconn.sconn288_h44441003(chips)!SCONN288_H44441003_PIP-SCONN,HA!!!F224!DQ(54)!!!!
S!M_D_DQ<55>!J6M1!269!@baseboard_fab2_lib.baseboard_fab2(sch_1):page50_i158@mstr_sconn.sconn288_h44441003(chips)!SCONN288_H44441003_PIP-SCONN,HA!!!F224!DQ(55)!!!!
S!M_D_DQ<56>!J6M1!130!@baseboard_fab2_lib.baseboard_fab2(sch_1):page50_i158@mstr_sconn.sconn288_h44441003(chips)!SCONN288_H44441003_PIP-SCONN,HA!!!F224!DQ(56)!!!!
S!M_D_DQ<57>!J6M1!275!@baseboard_fab2_lib.baseboard_fab2(sch_1):page50_i158@mstr_sconn.sconn288_h44441003(chips)!SCONN288_H44441003_PIP-SCONN,HA!!!F224!DQ(57)!!!!
S!M_D_DQ<58>!J6M1!137!@baseboard_fab2_lib.baseboard_fab2(sch_1):page50_i158@mstr_sconn.sconn288_h44441003(chips)!SCONN288_H44441003_PIP-SCONN,HA!!!F224!DQ(58)!!!!
S!M_D_DQ<59>!J6M1!282!@baseboard_fab2_lib.baseboard_fab2(sch_1):page50_i158@mstr_sconn.sconn288_h44441003(chips)!SCONN288_H44441003_PIP-SCONN,HA!!!F224!DQ(59)!!!!
S!M_D_DQ<5>!J6M1!148!@baseboard_fab2_lib.baseboard_fab2(sch_1):page50_i158@mstr_sconn.sconn288_h44441003(chips)!SCONN288_H44441003_PIP-SCONN,HA!!!F224!DQ(5)!!!!
S!M_D_DQ<60>!J6M1!128!@baseboard_fab2_lib.baseboard_fab2(sch_1):page50_i158@mstr_sconn.sconn288_h44441003(chips)!SCONN288_H44441003_PIP-SCONN,HA!!!F224!DQ(60)!!!!
S!M_D_DQ<61>!J6M1!273!@baseboard_fab2_lib.baseboard_fab2(sch_1):page50_i158@mstr_sconn.sconn288_h44441003(chips)!SCONN288_H44441003_PIP-SCONN,HA!!!F224!DQ(61)!!!!
S!M_D_DQ<62>!J6M1!135!@baseboard_fab2_lib.baseboard_fab2(sch_1):page50_i158@mstr_sconn.sconn288_h44441003(chips)!SCONN288_H44441003_PIP-SCONN,HA!!!F224!DQ(62)!!!!
S!M_D_DQ<63>!J6M1!280!@baseboard_fab2_lib.baseboard_fab2(sch_1):page50_i158@mstr_sconn.sconn288_h44441003(chips)!SCONN288_H44441003_PIP-SCONN,HA!!!F224!DQ(63)!!!!
S!M_D_DQ<6>!J6M1!10!@baseboard_fab2_lib.baseboard_fab2(sch_1):page50_i158@mstr_sconn.sconn288_h44441003(chips)!SCONN288_H44441003_PIP-SCONN,HA!!!F224!DQ(6)!!!!
S!M_D_DQ<7>!J6M1!155!@baseboard_fab2_lib.baseboard_fab2(sch_1):page50_i158@mstr_sconn.sconn288_h44441003(chips)!SCONN288_H44441003_PIP-SCONN,HA!!!F224!DQ(7)!!!!
S!M_D_DQ<8>!J6M1!16!@baseboard_fab2_lib.baseboard_fab2(sch_1):page50_i158@mstr_sconn.sconn288_h44441003(chips)!SCONN288_H44441003_PIP-SCONN,HA!!!F224!DQ(8)!!!!
S!M_D_DQ<9>!J6M1!161!@baseboard_fab2_lib.baseboard_fab2(sch_1):page50_i158@mstr_sconn.sconn288_h44441003(chips)!SCONN288_H44441003_PIP-SCONN,HA!!!F224!DQ(9)!!!!
S!FM_DIMM_EVENT_COD_N!J6M1!78!@baseboard_fab2_lib.baseboard_fab2(sch_1):page50_i158@mstr_sconn.sconn288_h44441003(chips)!SCONN288_H44441003_PIP-SCONN,HA!!!F224!EVENT_N!!!!
S!M_D_ODT<2>!J6M1!87!@baseboard_fab2_lib.baseboard_fab2(sch_1):page50_i158@mstr_sconn.sconn288_h44441003(chips)!SCONN288_H44441003_PIP-SCONN,HA!!!F224!ODT(0)!!!!
S!M_D_ODT<3>!J6M1!91!@baseboard_fab2_lib.baseboard_fab2(sch_1):page50_i158@mstr_sconn.sconn288_h44441003(chips)!SCONN288_H44441003_PIP-SCONN,HA!!!F224!ODT(1)!!!!
S!M_D_PAR!J6M1!222!@baseboard_fab2_lib.baseboard_fab2(sch_1):page50_i158@mstr_sconn.sconn288_h44441003(chips)!SCONN288_H44441003_PIP-SCONN,HA!!!F224!PAR!!!!
S!M_DEF_RST_N!J6M1!58!@baseboard_fab2_lib.baseboard_fab2(sch_1):page50_i158@mstr_sconn.sconn288_h44441003(chips)!SCONN288_H44441003_PIP-SCONN,HA!!!F224!RESET_N!!!!
S!TP_CH_D_DIMM_D1_RFU_0!J6M1!205!@baseboard_fab2_lib.baseboard_fab2(sch_1):page50_i158@mstr_sconn.sconn288_h44441003(chips)!SCONN288_H44441003_PIP-SCONN,HA!!!F224!RFU(0)!!!!
S!TP_CH_D_DIMM_D1_RFU_1!J6M1!227!@baseboard_fab2_lib.baseboard_fab2(sch_1):page50_i158@mstr_sconn.sconn288_h44441003(chips)!SCONN288_H44441003_PIP-SCONN,HA!!!F224!RFU(1)!!!!
S!TP_CH_D_DIMM_D1_RFU_2!J6M1!144!@baseboard_fab2_lib.baseboard_fab2(sch_1):page50_i158@mstr_sconn.sconn288_h44441003(chips)!SCONN288_H44441003_PIP-SCONN,HA!!!F224!RFU(2)!!!!
S!M_D_CS_N<4>!J6M1!84!@baseboard_fab2_lib.baseboard_fab2(sch_1):page50_i158@mstr_sconn.sconn288_h44441003(chips)!SCONN288_H44441003_PIP-SCONN,HA!!!F224!S0_N!!!!
S!M_D_CS_N<5>!J6M1!89!@baseboard_fab2_lib.baseboard_fab2(sch_1):page50_i158@mstr_sconn.sconn288_h44441003(chips)!SCONN288_H44441003_PIP-SCONN,HA!!!F224!S1_N!!!!
S!M_D_CS_N<6>!J6M1!93!@baseboard_fab2_lib.baseboard_fab2(sch_1):page50_i158@mstr_sconn.sconn288_h44441003(chips)!SCONN288_H44441003_PIP-SCONN,HA!!!F224!S2_N_C(0)!!!!
S!M_D_CS_N<7>!J6M1!237!@baseboard_fab2_lib.baseboard_fab2(sch_1):page50_i158@mstr_sconn.sconn288_h44441003(chips)!SCONN288_H44441003_PIP-SCONN,HA!!!F224!S3_N_C(1)!!!!
S!PVPP_DEF!J6M1!139!@baseboard_fab2_lib.baseboard_fab2(sch_1):page50_i158@mstr_sconn.sconn288_h44441003(chips)!SCONN288_H44441003_PIP-SCONN,HA!!!F224!SA(0)!!!!
S!GND!J6M1!140!@baseboard_fab2_lib.baseboard_fab2(sch_1):page50_i158@mstr_sconn.sconn288_h44441003(chips)!SCONN288_H44441003_PIP-SCONN,HA!!!F224!SA(1)!!!!
S!GND!J6M1!238!@baseboard_fab2_lib.baseboard_fab2(sch_1):page50_i158@mstr_sconn.sconn288_h44441003(chips)!SCONN288_H44441003_PIP-SCONN,HA!!!F224!SA(2)!!!!
S!FM_ADR_COMPLETE_DEF_N!J6M1!230!@baseboard_fab2_lib.baseboard_fab2(sch_1):page50_i158@mstr_sconn.sconn288_h44441003(chips)!SCONN288_H44441003_PIP-SCONN,HA!!!F224!SAVE_N_NC!!!!
S!SMB_DDR_DEF_VPP_SCL!J6M1!141!@baseboard_fab2_lib.baseboard_fab2(sch_1):page50_i158@mstr_sconn.sconn288_h44441003(chips)!SCONN288_H44441003_PIP-SCONN,HA!!!F224!SCL!!!!
S!SMB_DDR_DEF_VPP_SDA!J6M1!285!@baseboard_fab2_lib.baseboard_fab2(sch_1):page50_i158@mstr_sconn.sconn288_h44441003(chips)!SCONN288_H44441003_PIP-SCONN,HA!!!F224!SDA!!!!
S!PVPP_DEF!J6M1!284!@baseboard_fab2_lib.baseboard_fab2(sch_1):page50_i158@mstr_sconn.sconn288_h44441003(chips)!SCONN288_H44441003_PIP-SCONN,HA!!!F224!VDDSPD!!!!
S!M_D_VREF!J6M1!146!@baseboard_fab2_lib.baseboard_fab2(sch_1):page50_i158@mstr_sconn.sconn288_h44441003(chips)!SCONN288_H44441003_PIP-SCONN,HA!!!F224!VREFCA!!!!
S!M_D_DQS_DN<0>!J6M1!152!@baseboard_fab2_lib.baseboard_fab2(sch_1):page50_i46@mstr_sconn.sconn288_h44441003(chips)!SCONN288_H44441003_PIP-SCONN,HA!!!F223!DQS0N!!!!
S!M_D_DQS_DP<0>!J6M1!153!@baseboard_fab2_lib.baseboard_fab2(sch_1):page50_i46@mstr_sconn.sconn288_h44441003(chips)!SCONN288_H44441003_PIP-SCONN,HA!!!F223!DQS0P!!!!
S!M_D_DQS_DN<10>!J6M1!19!@baseboard_fab2_lib.baseboard_fab2(sch_1):page50_i46@mstr_sconn.sconn288_h44441003(chips)!SCONN288_H44441003_PIP-SCONN,HA!!!F223!DQS10N!!!!
S!M_D_DQS_DP<10>!J6M1!18!@baseboard_fab2_lib.baseboard_fab2(sch_1):page50_i46@mstr_sconn.sconn288_h44441003(chips)!SCONN288_H44441003_PIP-SCONN,HA!!!F223!DQS10P!!!!
S!M_D_DQS_DN<11>!J6M1!30!@baseboard_fab2_lib.baseboard_fab2(sch_1):page50_i46@mstr_sconn.sconn288_h44441003(chips)!SCONN288_H44441003_PIP-SCONN,HA!!!F223!DQS11N!!!!
S!M_D_DQS_DP<11>!J6M1!29!@baseboard_fab2_lib.baseboard_fab2(sch_1):page50_i46@mstr_sconn.sconn288_h44441003(chips)!SCONN288_H44441003_PIP-SCONN,HA!!!F223!DQS11P!!!!
S!M_D_DQS_DN<12>!J6M1!41!@baseboard_fab2_lib.baseboard_fab2(sch_1):page50_i46@mstr_sconn.sconn288_h44441003(chips)!SCONN288_H44441003_PIP-SCONN,HA!!!F223!DQS12N!!!!
S!M_D_DQS_DP<12>!J6M1!40!@baseboard_fab2_lib.baseboard_fab2(sch_1):page50_i46@mstr_sconn.sconn288_h44441003(chips)!SCONN288_H44441003_PIP-SCONN,HA!!!F223!DQS12P!!!!
S!M_D_DQS_DN<13>!J6M1!100!@baseboard_fab2_lib.baseboard_fab2(sch_1):page50_i46@mstr_sconn.sconn288_h44441003(chips)!SCONN288_H44441003_PIP-SCONN,HA!!!F223!DQS13N!!!!
S!M_D_DQS_DP<13>!J6M1!99!@baseboard_fab2_lib.baseboard_fab2(sch_1):page50_i46@mstr_sconn.sconn288_h44441003(chips)!SCONN288_H44441003_PIP-SCONN,HA!!!F223!DQS13P!!!!
S!M_D_DQS_DN<14>!J6M1!111!@baseboard_fab2_lib.baseboard_fab2(sch_1):page50_i46@mstr_sconn.sconn288_h44441003(chips)!SCONN288_H44441003_PIP-SCONN,HA!!!F223!DQS14N!!!!
S!M_D_DQS_DP<14>!J6M1!110!@baseboard_fab2_lib.baseboard_fab2(sch_1):page50_i46@mstr_sconn.sconn288_h44441003(chips)!SCONN288_H44441003_PIP-SCONN,HA!!!F223!DQS14P!!!!
S!M_D_DQS_DN<15>!J6M1!122!@baseboard_fab2_lib.baseboard_fab2(sch_1):page50_i46@mstr_sconn.sconn288_h44441003(chips)!SCONN288_H44441003_PIP-SCONN,HA!!!F223!DQS15N!!!!
S!M_D_DQS_DP<15>!J6M1!121!@baseboard_fab2_lib.baseboard_fab2(sch_1):page50_i46@mstr_sconn.sconn288_h44441003(chips)!SCONN288_H44441003_PIP-SCONN,HA!!!F223!DQS15P!!!!
S!M_D_DQS_DN<16>!J6M1!133!@baseboard_fab2_lib.baseboard_fab2(sch_1):page50_i46@mstr_sconn.sconn288_h44441003(chips)!SCONN288_H44441003_PIP-SCONN,HA!!!F223!DQS16N!!!!
S!M_D_DQS_DP<16>!J6M1!132!@baseboard_fab2_lib.baseboard_fab2(sch_1):page50_i46@mstr_sconn.sconn288_h44441003(chips)!SCONN288_H44441003_PIP-SCONN,HA!!!F223!DQS16P!!!!
S!M_D_DQS_DN<17>!J6M1!52!@baseboard_fab2_lib.baseboard_fab2(sch_1):page50_i46@mstr_sconn.sconn288_h44441003(chips)!SCONN288_H44441003_PIP-SCONN,HA!!!F223!DQS17N!!!!
S!M_D_DQS_DP<17>!J6M1!51!@baseboard_fab2_lib.baseboard_fab2(sch_1):page50_i46@mstr_sconn.sconn288_h44441003(chips)!SCONN288_H44441003_PIP-SCONN,HA!!!F223!DQS17P!!!!
S!M_D_DQS_DN<1>!J6M1!163!@baseboard_fab2_lib.baseboard_fab2(sch_1):page50_i46@mstr_sconn.sconn288_h44441003(chips)!SCONN288_H44441003_PIP-SCONN,HA!!!F223!DQS1N!!!!
S!M_D_DQS_DP<1>!J6M1!164!@baseboard_fab2_lib.baseboard_fab2(sch_1):page50_i46@mstr_sconn.sconn288_h44441003(chips)!SCONN288_H44441003_PIP-SCONN,HA!!!F223!DQS1P!!!!
S!M_D_DQS_DN<2>!J6M1!174!@baseboard_fab2_lib.baseboard_fab2(sch_1):page50_i46@mstr_sconn.sconn288_h44441003(chips)!SCONN288_H44441003_PIP-SCONN,HA!!!F223!DQS2N!!!!
S!M_D_DQS_DP<2>!J6M1!175!@baseboard_fab2_lib.baseboard_fab2(sch_1):page50_i46@mstr_sconn.sconn288_h44441003(chips)!SCONN288_H44441003_PIP-SCONN,HA!!!F223!DQS2P!!!!
S!M_D_DQS_DN<3>!J6M1!185!@baseboard_fab2_lib.baseboard_fab2(sch_1):page50_i46@mstr_sconn.sconn288_h44441003(chips)!SCONN288_H44441003_PIP-SCONN,HA!!!F223!DQS3N!!!!
S!M_D_DQS_DP<3>!J6M1!186!@baseboard_fab2_lib.baseboard_fab2(sch_1):page50_i46@mstr_sconn.sconn288_h44441003(chips)!SCONN288_H44441003_PIP-SCONN,HA!!!F223!DQS3P!!!!
S!M_D_DQS_DN<4>!J6M1!244!@baseboard_fab2_lib.baseboard_fab2(sch_1):page50_i46@mstr_sconn.sconn288_h44441003(chips)!SCONN288_H44441003_PIP-SCONN,HA!!!F223!DQS4N!!!!
S!M_D_DQS_DP<4>!J6M1!245!@baseboard_fab2_lib.baseboard_fab2(sch_1):page50_i46@mstr_sconn.sconn288_h44441003(chips)!SCONN288_H44441003_PIP-SCONN,HA!!!F223!DQS4P!!!!
S!M_D_DQS_DN<5>!J6M1!255!@baseboard_fab2_lib.baseboard_fab2(sch_1):page50_i46@mstr_sconn.sconn288_h44441003(chips)!SCONN288_H44441003_PIP-SCONN,HA!!!F223!DQS5N!!!!
S!M_D_DQS_DP<5>!J6M1!256!@baseboard_fab2_lib.baseboard_fab2(sch_1):page50_i46@mstr_sconn.sconn288_h44441003(chips)!SCONN288_H44441003_PIP-SCONN,HA!!!F223!DQS5P!!!!
S!M_D_DQS_DN<6>!J6M1!266!@baseboard_fab2_lib.baseboard_fab2(sch_1):page50_i46@mstr_sconn.sconn288_h44441003(chips)!SCONN288_H44441003_PIP-SCONN,HA!!!F223!DQS6N!!!!
S!M_D_DQS_DP<6>!J6M1!267!@baseboard_fab2_lib.baseboard_fab2(sch_1):page50_i46@mstr_sconn.sconn288_h44441003(chips)!SCONN288_H44441003_PIP-SCONN,HA!!!F223!DQS6P!!!!
S!M_D_DQS_DN<7>!J6M1!277!@baseboard_fab2_lib.baseboard_fab2(sch_1):page50_i46@mstr_sconn.sconn288_h44441003(chips)!SCONN288_H44441003_PIP-SCONN,HA!!!F223!DQS7N!!!!
S!M_D_DQS_DP<7>!J6M1!278!@baseboard_fab2_lib.baseboard_fab2(sch_1):page50_i46@mstr_sconn.sconn288_h44441003(chips)!SCONN288_H44441003_PIP-SCONN,HA!!!F223!DQS7P!!!!
S!M_D_DQS_DN<8>!J6M1!196!@baseboard_fab2_lib.baseboard_fab2(sch_1):page50_i46@mstr_sconn.sconn288_h44441003(chips)!SCONN288_H44441003_PIP-SCONN,HA!!!F223!DQS8N!!!!
S!M_D_DQS_DP<8>!J6M1!197!@baseboard_fab2_lib.baseboard_fab2(sch_1):page50_i46@mstr_sconn.sconn288_h44441003(chips)!SCONN288_H44441003_PIP-SCONN,HA!!!F223!DQS8P!!!!
S!M_D_DQS_DN<9>!J6M1!8!@baseboard_fab2_lib.baseboard_fab2(sch_1):page50_i46@mstr_sconn.sconn288_h44441003(chips)!SCONN288_H44441003_PIP-SCONN,HA!!!F223!DQS9N!!!!
S!M_D_DQS_DP<9>!J6M1!7!@baseboard_fab2_lib.baseboard_fab2(sch_1):page50_i46@mstr_sconn.sconn288_h44441003(chips)!SCONN288_H44441003_PIP-SCONN,HA!!!F223!DQS9P!!!!
S!GND!J6M1!283!@baseboard_fab2_lib.baseboard_fab2(sch_1):page50_i44@mstr_sconn.sconn288_h44441003(chips)!SCONN288_H44441003_PIP-SCONN,HA!!!F222!VSS(0)!!!!
S!GND!J6M1!261!@baseboard_fab2_lib.baseboard_fab2(sch_1):page50_i44@mstr_sconn.sconn288_h44441003(chips)!SCONN288_H44441003_PIP-SCONN,HA!!!F222!VSS(10)!!!!
S!GND!J6M1!259!@baseboard_fab2_lib.baseboard_fab2(sch_1):page50_i44@mstr_sconn.sconn288_h44441003(chips)!SCONN288_H44441003_PIP-SCONN,HA!!!F222!VSS(11)!!!!
S!GND!J6M1!257!@baseboard_fab2_lib.baseboard_fab2(sch_1):page50_i44@mstr_sconn.sconn288_h44441003(chips)!SCONN288_H44441003_PIP-SCONN,HA!!!F222!VSS(12)!!!!
S!GND!J6M1!254!@baseboard_fab2_lib.baseboard_fab2(sch_1):page50_i44@mstr_sconn.sconn288_h44441003(chips)!SCONN288_H44441003_PIP-SCONN,HA!!!F222!VSS(13)!!!!
S!GND!J6M1!252!@baseboard_fab2_lib.baseboard_fab2(sch_1):page50_i44@mstr_sconn.sconn288_h44441003(chips)!SCONN288_H44441003_PIP-SCONN,HA!!!F222!VSS(14)!!!!
S!GND!J6M1!250!@baseboard_fab2_lib.baseboard_fab2(sch_1):page50_i44@mstr_sconn.sconn288_h44441003(chips)!SCONN288_H44441003_PIP-SCONN,HA!!!F222!VSS(15)!!!!
S!GND!J6M1!248!@baseboard_fab2_lib.baseboard_fab2(sch_1):page50_i44@mstr_sconn.sconn288_h44441003(chips)!SCONN288_H44441003_PIP-SCONN,HA!!!F222!VSS(16)!!!!
S!GND!J6M1!246!@baseboard_fab2_lib.baseboard_fab2(sch_1):page50_i44@mstr_sconn.sconn288_h44441003(chips)!SCONN288_H44441003_PIP-SCONN,HA!!!F222!VSS(17)!!!!
S!GND!J6M1!243!@baseboard_fab2_lib.baseboard_fab2(sch_1):page50_i44@mstr_sconn.sconn288_h44441003(chips)!SCONN288_H44441003_PIP-SCONN,HA!!!F222!VSS(18)!!!!
S!GND!J6M1!241!@baseboard_fab2_lib.baseboard_fab2(sch_1):page50_i44@mstr_sconn.sconn288_h44441003(chips)!SCONN288_H44441003_PIP-SCONN,HA!!!F222!VSS(19)!!!!
S!GND!J6M1!281!@baseboard_fab2_lib.baseboard_fab2(sch_1):page50_i44@mstr_sconn.sconn288_h44441003(chips)!SCONN288_H44441003_PIP-SCONN,HA!!!F222!VSS(1)!!!!
S!GND!J6M1!239!@baseboard_fab2_lib.baseboard_fab2(sch_1):page50_i44@mstr_sconn.sconn288_h44441003(chips)!SCONN288_H44441003_PIP-SCONN,HA!!!F222!VSS(20)!!!!
S!GND!J6M1!202!@baseboard_fab2_lib.baseboard_fab2(sch_1):page50_i44@mstr_sconn.sconn288_h44441003(chips)!SCONN288_H44441003_PIP-SCONN,HA!!!F222!VSS(21)!!!!
S!GND!J6M1!200!@baseboard_fab2_lib.baseboard_fab2(sch_1):page50_i44@mstr_sconn.sconn288_h44441003(chips)!SCONN288_H44441003_PIP-SCONN,HA!!!F222!VSS(22)!!!!
S!GND!J6M1!198!@baseboard_fab2_lib.baseboard_fab2(sch_1):page50_i44@mstr_sconn.sconn288_h44441003(chips)!SCONN288_H44441003_PIP-SCONN,HA!!!F222!VSS(23)!!!!
S!GND!J6M1!195!@baseboard_fab2_lib.baseboard_fab2(sch_1):page50_i44@mstr_sconn.sconn288_h44441003(chips)!SCONN288_H44441003_PIP-SCONN,HA!!!F222!VSS(24)!!!!
S!GND!J6M1!193!@baseboard_fab2_lib.baseboard_fab2(sch_1):page50_i44@mstr_sconn.sconn288_h44441003(chips)!SCONN288_H44441003_PIP-SCONN,HA!!!F222!VSS(25)!!!!
S!GND!J6M1!191!@baseboard_fab2_lib.baseboard_fab2(sch_1):page50_i44@mstr_sconn.sconn288_h44441003(chips)!SCONN288_H44441003_PIP-SCONN,HA!!!F222!VSS(26)!!!!
S!GND!J6M1!189!@baseboard_fab2_lib.baseboard_fab2(sch_1):page50_i44@mstr_sconn.sconn288_h44441003(chips)!SCONN288_H44441003_PIP-SCONN,HA!!!F222!VSS(27)!!!!
S!GND!J6M1!187!@baseboard_fab2_lib.baseboard_fab2(sch_1):page50_i44@mstr_sconn.sconn288_h44441003(chips)!SCONN288_H44441003_PIP-SCONN,HA!!!F222!VSS(28)!!!!
S!GND!J6M1!184!@baseboard_fab2_lib.baseboard_fab2(sch_1):page50_i44@mstr_sconn.sconn288_h44441003(chips)!SCONN288_H44441003_PIP-SCONN,HA!!!F222!VSS(29)!!!!
S!GND!J6M1!279!@baseboard_fab2_lib.baseboard_fab2(sch_1):page50_i44@mstr_sconn.sconn288_h44441003(chips)!SCONN288_H44441003_PIP-SCONN,HA!!!F222!VSS(2)!!!!
S!GND!J6M1!182!@baseboard_fab2_lib.baseboard_fab2(sch_1):page50_i44@mstr_sconn.sconn288_h44441003(chips)!SCONN288_H44441003_PIP-SCONN,HA!!!F222!VSS(30)!!!!
S!GND!J6M1!180!@baseboard_fab2_lib.baseboard_fab2(sch_1):page50_i44@mstr_sconn.sconn288_h44441003(chips)!SCONN288_H44441003_PIP-SCONN,HA!!!F222!VSS(31)!!!!
S!GND!J6M1!178!@baseboard_fab2_lib.baseboard_fab2(sch_1):page50_i44@mstr_sconn.sconn288_h44441003(chips)!SCONN288_H44441003_PIP-SCONN,HA!!!F222!VSS(32)!!!!
S!GND!J6M1!176!@baseboard_fab2_lib.baseboard_fab2(sch_1):page50_i44@mstr_sconn.sconn288_h44441003(chips)!SCONN288_H44441003_PIP-SCONN,HA!!!F222!VSS(33)!!!!
S!GND!J6M1!173!@baseboard_fab2_lib.baseboard_fab2(sch_1):page50_i44@mstr_sconn.sconn288_h44441003(chips)!SCONN288_H44441003_PIP-SCONN,HA!!!F222!VSS(34)!!!!
S!GND!J6M1!171!@baseboard_fab2_lib.baseboard_fab2(sch_1):page50_i44@mstr_sconn.sconn288_h44441003(chips)!SCONN288_H44441003_PIP-SCONN,HA!!!F222!VSS(35)!!!!
S!GND!J6M1!169!@baseboard_fab2_lib.baseboard_fab2(sch_1):page50_i44@mstr_sconn.sconn288_h44441003(chips)!SCONN288_H44441003_PIP-SCONN,HA!!!F222!VSS(36)!!!!
S!GND!J6M1!167!@baseboard_fab2_lib.baseboard_fab2(sch_1):page50_i44@mstr_sconn.sconn288_h44441003(chips)!SCONN288_H44441003_PIP-SCONN,HA!!!F222!VSS(37)!!!!
S!GND!J6M1!165!@baseboard_fab2_lib.baseboard_fab2(sch_1):page50_i44@mstr_sconn.sconn288_h44441003(chips)!SCONN288_H44441003_PIP-SCONN,HA!!!F222!VSS(38)!!!!
S!GND!J6M1!162!@baseboard_fab2_lib.baseboard_fab2(sch_1):page50_i44@mstr_sconn.sconn288_h44441003(chips)!SCONN288_H44441003_PIP-SCONN,HA!!!F222!VSS(39)!!!!
S!GND!J6M1!276!@baseboard_fab2_lib.baseboard_fab2(sch_1):page50_i44@mstr_sconn.sconn288_h44441003(chips)!SCONN288_H44441003_PIP-SCONN,HA!!!F222!VSS(3)!!!!
S!GND!J6M1!160!@baseboard_fab2_lib.baseboard_fab2(sch_1):page50_i44@mstr_sconn.sconn288_h44441003(chips)!SCONN288_H44441003_PIP-SCONN,HA!!!F222!VSS(40)!!!!
S!GND!J6M1!158!@baseboard_fab2_lib.baseboard_fab2(sch_1):page50_i44@mstr_sconn.sconn288_h44441003(chips)!SCONN288_H44441003_PIP-SCONN,HA!!!F222!VSS(41)!!!!
S!GND!J6M1!156!@baseboard_fab2_lib.baseboard_fab2(sch_1):page50_i44@mstr_sconn.sconn288_h44441003(chips)!SCONN288_H44441003_PIP-SCONN,HA!!!F222!VSS(42)!!!!
S!GND!J6M1!154!@baseboard_fab2_lib.baseboard_fab2(sch_1):page50_i44@mstr_sconn.sconn288_h44441003(chips)!SCONN288_H44441003_PIP-SCONN,HA!!!F222!VSS(43)!!!!
S!GND!J6M1!151!@baseboard_fab2_lib.baseboard_fab2(sch_1):page50_i44@mstr_sconn.sconn288_h44441003(chips)!SCONN288_H44441003_PIP-SCONN,HA!!!F222!VSS(44)!!!!
S!GND!J6M1!149!@baseboard_fab2_lib.baseboard_fab2(sch_1):page50_i44@mstr_sconn.sconn288_h44441003(chips)!SCONN288_H44441003_PIP-SCONN,HA!!!F222!VSS(45)!!!!
S!GND!J6M1!147!@baseboard_fab2_lib.baseboard_fab2(sch_1):page50_i44@mstr_sconn.sconn288_h44441003(chips)!SCONN288_H44441003_PIP-SCONN,HA!!!F222!VSS(46)!!!!
S!GND!J6M1!138!@baseboard_fab2_lib.baseboard_fab2(sch_1):page50_i44@mstr_sconn.sconn288_h44441003(chips)!SCONN288_H44441003_PIP-SCONN,HA!!!F222!VSS(47)!!!!
S!GND!J6M1!136!@baseboard_fab2_lib.baseboard_fab2(sch_1):page50_i44@mstr_sconn.sconn288_h44441003(chips)!SCONN288_H44441003_PIP-SCONN,HA!!!F222!VSS(48)!!!!
S!GND!J6M1!134!@baseboard_fab2_lib.baseboard_fab2(sch_1):page50_i44@mstr_sconn.sconn288_h44441003(chips)!SCONN288_H44441003_PIP-SCONN,HA!!!F222!VSS(49)!!!!
S!GND!J6M1!274!@baseboard_fab2_lib.baseboard_fab2(sch_1):page50_i44@mstr_sconn.sconn288_h44441003(chips)!SCONN288_H44441003_PIP-SCONN,HA!!!F222!VSS(4)!!!!
S!GND!J6M1!131!@baseboard_fab2_lib.baseboard_fab2(sch_1):page50_i44@mstr_sconn.sconn288_h44441003(chips)!SCONN288_H44441003_PIP-SCONN,HA!!!F222!VSS(50)!!!!
S!GND!J6M1!129!@baseboard_fab2_lib.baseboard_fab2(sch_1):page50_i44@mstr_sconn.sconn288_h44441003(chips)!SCONN288_H44441003_PIP-SCONN,HA!!!F222!VSS(51)!!!!
S!GND!J6M1!127!@baseboard_fab2_lib.baseboard_fab2(sch_1):page50_i44@mstr_sconn.sconn288_h44441003(chips)!SCONN288_H44441003_PIP-SCONN,HA!!!F222!VSS(52)!!!!
S!GND!J6M1!125!@baseboard_fab2_lib.baseboard_fab2(sch_1):page50_i44@mstr_sconn.sconn288_h44441003(chips)!SCONN288_H44441003_PIP-SCONN,HA!!!F222!VSS(53)!!!!
S!GND!J6M1!123!@baseboard_fab2_lib.baseboard_fab2(sch_1):page50_i44@mstr_sconn.sconn288_h44441003(chips)!SCONN288_H44441003_PIP-SCONN,HA!!!F222!VSS(54)!!!!
S!GND!J6M1!120!@baseboard_fab2_lib.baseboard_fab2(sch_1):page50_i44@mstr_sconn.sconn288_h44441003(chips)!SCONN288_H44441003_PIP-SCONN,HA!!!F222!VSS(55)!!!!
S!GND!J6M1!118!@baseboard_fab2_lib.baseboard_fab2(sch_1):page50_i44@mstr_sconn.sconn288_h44441003(chips)!SCONN288_H44441003_PIP-SCONN,HA!!!F222!VSS(56)!!!!
S!GND!J6M1!116!@baseboard_fab2_lib.baseboard_fab2(sch_1):page50_i44@mstr_sconn.sconn288_h44441003(chips)!SCONN288_H44441003_PIP-SCONN,HA!!!F222!VSS(57)!!!!
S!GND!J6M1!114!@baseboard_fab2_lib.baseboard_fab2(sch_1):page50_i44@mstr_sconn.sconn288_h44441003(chips)!SCONN288_H44441003_PIP-SCONN,HA!!!F222!VSS(58)!!!!
S!GND!J6M1!112!@baseboard_fab2_lib.baseboard_fab2(sch_1):page50_i44@mstr_sconn.sconn288_h44441003(chips)!SCONN288_H44441003_PIP-SCONN,HA!!!F222!VSS(59)!!!!
S!GND!J6M1!272!@baseboard_fab2_lib.baseboard_fab2(sch_1):page50_i44@mstr_sconn.sconn288_h44441003(chips)!SCONN288_H44441003_PIP-SCONN,HA!!!F222!VSS(5)!!!!
S!GND!J6M1!109!@baseboard_fab2_lib.baseboard_fab2(sch_1):page50_i44@mstr_sconn.sconn288_h44441003(chips)!SCONN288_H44441003_PIP-SCONN,HA!!!F222!VSS(60)!!!!
S!GND!J6M1!107!@baseboard_fab2_lib.baseboard_fab2(sch_1):page50_i44@mstr_sconn.sconn288_h44441003(chips)!SCONN288_H44441003_PIP-SCONN,HA!!!F222!VSS(61)!!!!
S!GND!J6M1!105!@baseboard_fab2_lib.baseboard_fab2(sch_1):page50_i44@mstr_sconn.sconn288_h44441003(chips)!SCONN288_H44441003_PIP-SCONN,HA!!!F222!VSS(62)!!!!
S!GND!J6M1!103!@baseboard_fab2_lib.baseboard_fab2(sch_1):page50_i44@mstr_sconn.sconn288_h44441003(chips)!SCONN288_H44441003_PIP-SCONN,HA!!!F222!VSS(63)!!!!
S!GND!J6M1!101!@baseboard_fab2_lib.baseboard_fab2(sch_1):page50_i44@mstr_sconn.sconn288_h44441003(chips)!SCONN288_H44441003_PIP-SCONN,HA!!!F222!VSS(64)!!!!
S!GND!J6M1!98!@baseboard_fab2_lib.baseboard_fab2(sch_1):page50_i44@mstr_sconn.sconn288_h44441003(chips)!SCONN288_H44441003_PIP-SCONN,HA!!!F222!VSS(65)!!!!
S!GND!J6M1!96!@baseboard_fab2_lib.baseboard_fab2(sch_1):page50_i44@mstr_sconn.sconn288_h44441003(chips)!SCONN288_H44441003_PIP-SCONN,HA!!!F222!VSS(66)!!!!
S!GND!J6M1!94!@baseboard_fab2_lib.baseboard_fab2(sch_1):page50_i44@mstr_sconn.sconn288_h44441003(chips)!SCONN288_H44441003_PIP-SCONN,HA!!!F222!VSS(67)!!!!
S!GND!J6M1!57!@baseboard_fab2_lib.baseboard_fab2(sch_1):page50_i44@mstr_sconn.sconn288_h44441003(chips)!SCONN288_H44441003_PIP-SCONN,HA!!!F222!VSS(68)!!!!
S!GND!J6M1!55!@baseboard_fab2_lib.baseboard_fab2(sch_1):page50_i44@mstr_sconn.sconn288_h44441003(chips)!SCONN288_H44441003_PIP-SCONN,HA!!!F222!VSS(69)!!!!
S!GND!J6M1!270!@baseboard_fab2_lib.baseboard_fab2(sch_1):page50_i44@mstr_sconn.sconn288_h44441003(chips)!SCONN288_H44441003_PIP-SCONN,HA!!!F222!VSS(6)!!!!
S!GND!J6M1!53!@baseboard_fab2_lib.baseboard_fab2(sch_1):page50_i44@mstr_sconn.sconn288_h44441003(chips)!SCONN288_H44441003_PIP-SCONN,HA!!!F222!VSS(70)!!!!
S!GND!J6M1!50!@baseboard_fab2_lib.baseboard_fab2(sch_1):page50_i44@mstr_sconn.sconn288_h44441003(chips)!SCONN288_H44441003_PIP-SCONN,HA!!!F222!VSS(71)!!!!
S!GND!J6M1!48!@baseboard_fab2_lib.baseboard_fab2(sch_1):page50_i44@mstr_sconn.sconn288_h44441003(chips)!SCONN288_H44441003_PIP-SCONN,HA!!!F222!VSS(72)!!!!
S!GND!J6M1!46!@baseboard_fab2_lib.baseboard_fab2(sch_1):page50_i44@mstr_sconn.sconn288_h44441003(chips)!SCONN288_H44441003_PIP-SCONN,HA!!!F222!VSS(73)!!!!
S!GND!J6M1!44!@baseboard_fab2_lib.baseboard_fab2(sch_1):page50_i44@mstr_sconn.sconn288_h44441003(chips)!SCONN288_H44441003_PIP-SCONN,HA!!!F222!VSS(74)!!!!
S!GND!J6M1!42!@baseboard_fab2_lib.baseboard_fab2(sch_1):page50_i44@mstr_sconn.sconn288_h44441003(chips)!SCONN288_H44441003_PIP-SCONN,HA!!!F222!VSS(75)!!!!
S!GND!J6M1!39!@baseboard_fab2_lib.baseboard_fab2(sch_1):page50_i44@mstr_sconn.sconn288_h44441003(chips)!SCONN288_H44441003_PIP-SCONN,HA!!!F222!VSS(76)!!!!
S!GND!J6M1!37!@baseboard_fab2_lib.baseboard_fab2(sch_1):page50_i44@mstr_sconn.sconn288_h44441003(chips)!SCONN288_H44441003_PIP-SCONN,HA!!!F222!VSS(77)!!!!
S!GND!J6M1!35!@baseboard_fab2_lib.baseboard_fab2(sch_1):page50_i44@mstr_sconn.sconn288_h44441003(chips)!SCONN288_H44441003_PIP-SCONN,HA!!!F222!VSS(78)!!!!
S!GND!J6M1!33!@baseboard_fab2_lib.baseboard_fab2(sch_1):page50_i44@mstr_sconn.sconn288_h44441003(chips)!SCONN288_H44441003_PIP-SCONN,HA!!!F222!VSS(79)!!!!
S!GND!J6M1!268!@baseboard_fab2_lib.baseboard_fab2(sch_1):page50_i44@mstr_sconn.sconn288_h44441003(chips)!SCONN288_H44441003_PIP-SCONN,HA!!!F222!VSS(7)!!!!
S!GND!J6M1!31!@baseboard_fab2_lib.baseboard_fab2(sch_1):page50_i44@mstr_sconn.sconn288_h44441003(chips)!SCONN288_H44441003_PIP-SCONN,HA!!!F222!VSS(80)!!!!
S!GND!J6M1!28!@baseboard_fab2_lib.baseboard_fab2(sch_1):page50_i44@mstr_sconn.sconn288_h44441003(chips)!SCONN288_H44441003_PIP-SCONN,HA!!!F222!VSS(81)!!!!
S!GND!J6M1!26!@baseboard_fab2_lib.baseboard_fab2(sch_1):page50_i44@mstr_sconn.sconn288_h44441003(chips)!SCONN288_H44441003_PIP-SCONN,HA!!!F222!VSS(82)!!!!
S!GND!J6M1!24!@baseboard_fab2_lib.baseboard_fab2(sch_1):page50_i44@mstr_sconn.sconn288_h44441003(chips)!SCONN288_H44441003_PIP-SCONN,HA!!!F222!VSS(83)!!!!
S!GND!J6M1!22!@baseboard_fab2_lib.baseboard_fab2(sch_1):page50_i44@mstr_sconn.sconn288_h44441003(chips)!SCONN288_H44441003_PIP-SCONN,HA!!!F222!VSS(84)!!!!
S!GND!J6M1!20!@baseboard_fab2_lib.baseboard_fab2(sch_1):page50_i44@mstr_sconn.sconn288_h44441003(chips)!SCONN288_H44441003_PIP-SCONN,HA!!!F222!VSS(85)!!!!
S!GND!J6M1!17!@baseboard_fab2_lib.baseboard_fab2(sch_1):page50_i44@mstr_sconn.sconn288_h44441003(chips)!SCONN288_H44441003_PIP-SCONN,HA!!!F222!VSS(86)!!!!
S!GND!J6M1!15!@baseboard_fab2_lib.baseboard_fab2(sch_1):page50_i44@mstr_sconn.sconn288_h44441003(chips)!SCONN288_H44441003_PIP-SCONN,HA!!!F222!VSS(87)!!!!
S!GND!J6M1!13!@baseboard_fab2_lib.baseboard_fab2(sch_1):page50_i44@mstr_sconn.sconn288_h44441003(chips)!SCONN288_H44441003_PIP-SCONN,HA!!!F222!VSS(88)!!!!
S!GND!J6M1!11!@baseboard_fab2_lib.baseboard_fab2(sch_1):page50_i44@mstr_sconn.sconn288_h44441003(chips)!SCONN288_H44441003_PIP-SCONN,HA!!!F222!VSS(89)!!!!
S!GND!J6M1!265!@baseboard_fab2_lib.baseboard_fab2(sch_1):page50_i44@mstr_sconn.sconn288_h44441003(chips)!SCONN288_H44441003_PIP-SCONN,HA!!!F222!VSS(8)!!!!
S!GND!J6M1!9!@baseboard_fab2_lib.baseboard_fab2(sch_1):page50_i44@mstr_sconn.sconn288_h44441003(chips)!SCONN288_H44441003_PIP-SCONN,HA!!!F222!VSS(90)!!!!
S!GND!J6M1!6!@baseboard_fab2_lib.baseboard_fab2(sch_1):page50_i44@mstr_sconn.sconn288_h44441003(chips)!SCONN288_H44441003_PIP-SCONN,HA!!!F222!VSS(91)!!!!
S!GND!J6M1!4!@baseboard_fab2_lib.baseboard_fab2(sch_1):page50_i44@mstr_sconn.sconn288_h44441003(chips)!SCONN288_H44441003_PIP-SCONN,HA!!!F222!VSS(92)!!!!
S!GND!J6M1!2!@baseboard_fab2_lib.baseboard_fab2(sch_1):page50_i44@mstr_sconn.sconn288_h44441003(chips)!SCONN288_H44441003_PIP-SCONN,HA!!!F222!VSS(93)!!!!
S!GND!J6M1!263!@baseboard_fab2_lib.baseboard_fab2(sch_1):page50_i44@mstr_sconn.sconn288_h44441003(chips)!SCONN288_H44441003_PIP-SCONN,HA!!!F222!VSS(9)!!!!
S!P12V_NVDIMM_DEF!J6M1!145!@baseboard_fab2_lib.baseboard_fab2(sch_1):page50_i50@mstr_sconn.sconn288_h44441003(chips)!SCONN288_H44441003_PIP-SCONN,HA!!!F221!\12v\(0)!!!!
S!P12V_NVDIMM_DEF!J6M1!1!@baseboard_fab2_lib.baseboard_fab2(sch_1):page50_i50@mstr_sconn.sconn288_h44441003(chips)!SCONN288_H44441003_PIP-SCONN,HA!!!F221!\12v\(1)!!!!
S!PVDDQ_DEF!J6M1!236!@baseboard_fab2_lib.baseboard_fab2(sch_1):page50_i50@mstr_sconn.sconn288_h44441003(chips)!SCONN288_H44441003_PIP-SCONN,HA!!!F221!VDD(0)!!!!
S!PVDDQ_DEF!J6M1!209!@baseboard_fab2_lib.baseboard_fab2(sch_1):page50_i50@mstr_sconn.sconn288_h44441003(chips)!SCONN288_H44441003_PIP-SCONN,HA!!!F221!VDD(10)!!!!
S!PVDDQ_DEF!J6M1!206!@baseboard_fab2_lib.baseboard_fab2(sch_1):page50_i50@mstr_sconn.sconn288_h44441003(chips)!SCONN288_H44441003_PIP-SCONN,HA!!!F221!VDD(11)!!!!
S!PVDDQ_DEF!J6M1!204!@baseboard_fab2_lib.baseboard_fab2(sch_1):page50_i50@mstr_sconn.sconn288_h44441003(chips)!SCONN288_H44441003_PIP-SCONN,HA!!!F221!VDD(12)!!!!
S!PVDDQ_DEF!J6M1!92!@baseboard_fab2_lib.baseboard_fab2(sch_1):page50_i50@mstr_sconn.sconn288_h44441003(chips)!SCONN288_H44441003_PIP-SCONN,HA!!!F221!VDD(13)!!!!
S!PVDDQ_DEF!J6M1!90!@baseboard_fab2_lib.baseboard_fab2(sch_1):page50_i50@mstr_sconn.sconn288_h44441003(chips)!SCONN288_H44441003_PIP-SCONN,HA!!!F221!VDD(14)!!!!
S!PVDDQ_DEF!J6M1!88!@baseboard_fab2_lib.baseboard_fab2(sch_1):page50_i50@mstr_sconn.sconn288_h44441003(chips)!SCONN288_H44441003_PIP-SCONN,HA!!!F221!VDD(15)!!!!
S!PVDDQ_DEF!J6M1!85!@baseboard_fab2_lib.baseboard_fab2(sch_1):page50_i50@mstr_sconn.sconn288_h44441003(chips)!SCONN288_H44441003_PIP-SCONN,HA!!!F221!VDD(16)!!!!
S!PVDDQ_DEF!J6M1!83!@baseboard_fab2_lib.baseboard_fab2(sch_1):page50_i50@mstr_sconn.sconn288_h44441003(chips)!SCONN288_H44441003_PIP-SCONN,HA!!!F221!VDD(17)!!!!
S!PVDDQ_DEF!J6M1!80!@baseboard_fab2_lib.baseboard_fab2(sch_1):page50_i50@mstr_sconn.sconn288_h44441003(chips)!SCONN288_H44441003_PIP-SCONN,HA!!!F221!VDD(18)!!!!
S!PVDDQ_DEF!J6M1!76!@baseboard_fab2_lib.baseboard_fab2(sch_1):page50_i50@mstr_sconn.sconn288_h44441003(chips)!SCONN288_H44441003_PIP-SCONN,HA!!!F221!VDD(19)!!!!
S!PVDDQ_DEF!J6M1!233!@baseboard_fab2_lib.baseboard_fab2(sch_1):page50_i50@mstr_sconn.sconn288_h44441003(chips)!SCONN288_H44441003_PIP-SCONN,HA!!!F221!VDD(1)!!!!
S!PVDDQ_DEF!J6M1!73!@baseboard_fab2_lib.baseboard_fab2(sch_1):page50_i50@mstr_sconn.sconn288_h44441003(chips)!SCONN288_H44441003_PIP-SCONN,HA!!!F221!VDD(20)!!!!
S!PVDDQ_DEF!J6M1!70!@baseboard_fab2_lib.baseboard_fab2(sch_1):page50_i50@mstr_sconn.sconn288_h44441003(chips)!SCONN288_H44441003_PIP-SCONN,HA!!!F221!VDD(21)!!!!
S!PVDDQ_DEF!J6M1!67!@baseboard_fab2_lib.baseboard_fab2(sch_1):page50_i50@mstr_sconn.sconn288_h44441003(chips)!SCONN288_H44441003_PIP-SCONN,HA!!!F221!VDD(22)!!!!
S!PVDDQ_DEF!J6M1!64!@baseboard_fab2_lib.baseboard_fab2(sch_1):page50_i50@mstr_sconn.sconn288_h44441003(chips)!SCONN288_H44441003_PIP-SCONN,HA!!!F221!VDD(23)!!!!
S!PVDDQ_DEF!J6M1!61!@baseboard_fab2_lib.baseboard_fab2(sch_1):page50_i50@mstr_sconn.sconn288_h44441003(chips)!SCONN288_H44441003_PIP-SCONN,HA!!!F221!VDD(24)!!!!
S!PVDDQ_DEF!J6M1!59!@baseboard_fab2_lib.baseboard_fab2(sch_1):page50_i50@mstr_sconn.sconn288_h44441003(chips)!SCONN288_H44441003_PIP-SCONN,HA!!!F221!VDD(25)!!!!
S!PVDDQ_DEF!J6M1!231!@baseboard_fab2_lib.baseboard_fab2(sch_1):page50_i50@mstr_sconn.sconn288_h44441003(chips)!SCONN288_H44441003_PIP-SCONN,HA!!!F221!VDD(2)!!!!
S!PVDDQ_DEF!J6M1!229!@baseboard_fab2_lib.baseboard_fab2(sch_1):page50_i50@mstr_sconn.sconn288_h44441003(chips)!SCONN288_H44441003_PIP-SCONN,HA!!!F221!VDD(3)!!!!
S!PVDDQ_DEF!J6M1!226!@baseboard_fab2_lib.baseboard_fab2(sch_1):page50_i50@mstr_sconn.sconn288_h44441003(chips)!SCONN288_H44441003_PIP-SCONN,HA!!!F221!VDD(4)!!!!
S!PVDDQ_DEF!J6M1!223!@baseboard_fab2_lib.baseboard_fab2(sch_1):page50_i50@mstr_sconn.sconn288_h44441003(chips)!SCONN288_H44441003_PIP-SCONN,HA!!!F221!VDD(5)!!!!
S!PVDDQ_DEF!J6M1!220!@baseboard_fab2_lib.baseboard_fab2(sch_1):page50_i50@mstr_sconn.sconn288_h44441003(chips)!SCONN288_H44441003_PIP-SCONN,HA!!!F221!VDD(6)!!!!
S!PVDDQ_DEF!J6M1!217!@baseboard_fab2_lib.baseboard_fab2(sch_1):page50_i50@mstr_sconn.sconn288_h44441003(chips)!SCONN288_H44441003_PIP-SCONN,HA!!!F221!VDD(7)!!!!
S!PVDDQ_DEF!J6M1!215!@baseboard_fab2_lib.baseboard_fab2(sch_1):page50_i50@mstr_sconn.sconn288_h44441003(chips)!SCONN288_H44441003_PIP-SCONN,HA!!!F221!VDD(8)!!!!
S!PVDDQ_DEF!J6M1!212!@baseboard_fab2_lib.baseboard_fab2(sch_1):page50_i50@mstr_sconn.sconn288_h44441003(chips)!SCONN288_H44441003_PIP-SCONN,HA!!!F221!VDD(9)!!!!
S!PVPP_DEF!J6M1!287!@baseboard_fab2_lib.baseboard_fab2(sch_1):page50_i50@mstr_sconn.sconn288_h44441003(chips)!SCONN288_H44441003_PIP-SCONN,HA!!!F221!VPP(0)!!!!
S!PVPP_DEF!J6M1!286!@baseboard_fab2_lib.baseboard_fab2(sch_1):page50_i50@mstr_sconn.sconn288_h44441003(chips)!SCONN288_H44441003_PIP-SCONN,HA!!!F221!VPP(1)!!!!
S!PVPP_DEF!J6M1!288!@baseboard_fab2_lib.baseboard_fab2(sch_1):page50_i50@mstr_sconn.sconn288_h44441003(chips)!SCONN288_H44441003_PIP-SCONN,HA!!!F221!VPP(2)!!!!
S!PVPP_DEF!J6M1!143!@baseboard_fab2_lib.baseboard_fab2(sch_1):page50_i50@mstr_sconn.sconn288_h44441003(chips)!SCONN288_H44441003_PIP-SCONN,HA!!!F221!VPP(3)!!!!
S!PVPP_DEF!J6M1!142!@baseboard_fab2_lib.baseboard_fab2(sch_1):page50_i50@mstr_sconn.sconn288_h44441003(chips)!SCONN288_H44441003_PIP-SCONN,HA!!!F221!VPP(4)!!!!
S!PVTT_DEF!J6M1!221!@baseboard_fab2_lib.baseboard_fab2(sch_1):page50_i50@mstr_sconn.sconn288_h44441003(chips)!SCONN288_H44441003_PIP-SCONN,HA!!!F221!VTT(0)!!!!
S!PVTT_DEF!J6M1!77!@baseboard_fab2_lib.baseboard_fab2(sch_1):page50_i50@mstr_sconn.sconn288_h44441003(chips)!SCONN288_H44441003_PIP-SCONN,HA!!!F221!VTT(1)!!!!
S!M_E_MA<0>!J6L2!79!@baseboard_fab2_lib.baseboard_fab2(sch_1):page52_i12@mstr_sconn.sconn288_h44441003(chips)!SCONN288_H44441003_PIP-SCONN,HA!!!F228!A0!!!!
S!M_E_MA<1>!J6L2!72!@baseboard_fab2_lib.baseboard_fab2(sch_1):page52_i12@mstr_sconn.sconn288_h44441003(chips)!SCONN288_H44441003_PIP-SCONN,HA!!!F228!A1!!!!
S!M_E_MA<10>!J6L2!225!@baseboard_fab2_lib.baseboard_fab2(sch_1):page52_i12@mstr_sconn.sconn288_h44441003(chips)!SCONN288_H44441003_PIP-SCONN,HA!!!F228!A10!!!!
S!M_E_MA<11>!J6L2!210!@baseboard_fab2_lib.baseboard_fab2(sch_1):page52_i12@mstr_sconn.sconn288_h44441003(chips)!SCONN288_H44441003_PIP-SCONN,HA!!!F228!A11!!!!
S!M_E_MA<12>!J6L2!65!@baseboard_fab2_lib.baseboard_fab2(sch_1):page52_i12@mstr_sconn.sconn288_h44441003(chips)!SCONN288_H44441003_PIP-SCONN,HA!!!F228!A12!!!!
S!M_E_MA<13>!J6L2!232!@baseboard_fab2_lib.baseboard_fab2(sch_1):page52_i12@mstr_sconn.sconn288_h44441003(chips)!SCONN288_H44441003_PIP-SCONN,HA!!!F228!A13!!!!
S!M_E_MA<14>!J6L2!228!@baseboard_fab2_lib.baseboard_fab2(sch_1):page52_i12@mstr_sconn.sconn288_h44441003(chips)!SCONN288_H44441003_PIP-SCONN,HA!!!F228!A14_WE_N!!!!
S!M_E_MA<15>!J6L2!86!@baseboard_fab2_lib.baseboard_fab2(sch_1):page52_i12@mstr_sconn.sconn288_h44441003(chips)!SCONN288_H44441003_PIP-SCONN,HA!!!F228!A15_CAS_N!!!!
S!M_E_MA<16>!J6L2!82!@baseboard_fab2_lib.baseboard_fab2(sch_1):page52_i12@mstr_sconn.sconn288_h44441003(chips)!SCONN288_H44441003_PIP-SCONN,HA!!!F228!A16_RAS_N!!!!
S!M_E_MA<17>!J6L2!234!@baseboard_fab2_lib.baseboard_fab2(sch_1):page52_i12@mstr_sconn.sconn288_h44441003(chips)!SCONN288_H44441003_PIP-SCONN,HA!!!F228!A17!!!!
S!M_E_MA<2>!J6L2!216!@baseboard_fab2_lib.baseboard_fab2(sch_1):page52_i12@mstr_sconn.sconn288_h44441003(chips)!SCONN288_H44441003_PIP-SCONN,HA!!!F228!A2!!!!
S!M_E_MA<3>!J6L2!71!@baseboard_fab2_lib.baseboard_fab2(sch_1):page52_i12@mstr_sconn.sconn288_h44441003(chips)!SCONN288_H44441003_PIP-SCONN,HA!!!F228!A3!!!!
S!M_E_MA<4>!J6L2!214!@baseboard_fab2_lib.baseboard_fab2(sch_1):page52_i12@mstr_sconn.sconn288_h44441003(chips)!SCONN288_H44441003_PIP-SCONN,HA!!!F228!A4!!!!
S!M_E_MA<5>!J6L2!213!@baseboard_fab2_lib.baseboard_fab2(sch_1):page52_i12@mstr_sconn.sconn288_h44441003(chips)!SCONN288_H44441003_PIP-SCONN,HA!!!F228!A5!!!!
S!M_E_MA<6>!J6L2!69!@baseboard_fab2_lib.baseboard_fab2(sch_1):page52_i12@mstr_sconn.sconn288_h44441003(chips)!SCONN288_H44441003_PIP-SCONN,HA!!!F228!A6!!!!
S!M_E_MA<7>!J6L2!211!@baseboard_fab2_lib.baseboard_fab2(sch_1):page52_i12@mstr_sconn.sconn288_h44441003(chips)!SCONN288_H44441003_PIP-SCONN,HA!!!F228!A7!!!!
S!M_E_MA<8>!J6L2!68!@baseboard_fab2_lib.baseboard_fab2(sch_1):page52_i12@mstr_sconn.sconn288_h44441003(chips)!SCONN288_H44441003_PIP-SCONN,HA!!!F228!A8!!!!
S!M_E_MA<9>!J6L2!66!@baseboard_fab2_lib.baseboard_fab2(sch_1):page52_i12@mstr_sconn.sconn288_h44441003(chips)!SCONN288_H44441003_PIP-SCONN,HA!!!F228!A9!!!!
S!M_E_ACT_N!J6L2!62!@baseboard_fab2_lib.baseboard_fab2(sch_1):page52_i12@mstr_sconn.sconn288_h44441003(chips)!SCONN288_H44441003_PIP-SCONN,HA!!!F228!ACT_N!!!!
S!M_E_ALERT_N!J6L2!208!@baseboard_fab2_lib.baseboard_fab2(sch_1):page52_i12@mstr_sconn.sconn288_h44441003(chips)!SCONN288_H44441003_PIP-SCONN,HA!!!F228!ALERT_N!!!!
S!M_E_BA<0>!J6L2!81!@baseboard_fab2_lib.baseboard_fab2(sch_1):page52_i12@mstr_sconn.sconn288_h44441003(chips)!SCONN288_H44441003_PIP-SCONN,HA!!!F228!BA(0)!!!!
S!M_E_BA<1>!J6L2!224!@baseboard_fab2_lib.baseboard_fab2(sch_1):page52_i12@mstr_sconn.sconn288_h44441003(chips)!SCONN288_H44441003_PIP-SCONN,HA!!!F228!BA(1)!!!!
S!M_E_BG<0>!J6L2!63!@baseboard_fab2_lib.baseboard_fab2(sch_1):page52_i12@mstr_sconn.sconn288_h44441003(chips)!SCONN288_H44441003_PIP-SCONN,HA!!!F228!BG(0)!!!!
S!M_E_BG<1>!J6L2!207!@baseboard_fab2_lib.baseboard_fab2(sch_1):page52_i12@mstr_sconn.sconn288_h44441003(chips)!SCONN288_H44441003_PIP-SCONN,HA!!!F228!BG(1)!!!!
S!M_E_C<2>!J6L2!235!@baseboard_fab2_lib.baseboard_fab2(sch_1):page52_i12@mstr_sconn.sconn288_h44441003(chips)!SCONN288_H44441003_PIP-SCONN,HA!!!F228!C(2)!!!!
S!M_E_ECC<0>!J6L2!49!@baseboard_fab2_lib.baseboard_fab2(sch_1):page52_i12@mstr_sconn.sconn288_h44441003(chips)!SCONN288_H44441003_PIP-SCONN,HA!!!F228!CB(0)!!!!
S!M_E_ECC<1>!J6L2!194!@baseboard_fab2_lib.baseboard_fab2(sch_1):page52_i12@mstr_sconn.sconn288_h44441003(chips)!SCONN288_H44441003_PIP-SCONN,HA!!!F228!CB(1)!!!!
S!M_E_ECC<2>!J6L2!56!@baseboard_fab2_lib.baseboard_fab2(sch_1):page52_i12@mstr_sconn.sconn288_h44441003(chips)!SCONN288_H44441003_PIP-SCONN,HA!!!F228!CB(2)!!!!
S!M_E_ECC<3>!J6L2!201!@baseboard_fab2_lib.baseboard_fab2(sch_1):page52_i12@mstr_sconn.sconn288_h44441003(chips)!SCONN288_H44441003_PIP-SCONN,HA!!!F228!CB(3)!!!!
S!M_E_ECC<4>!J6L2!47!@baseboard_fab2_lib.baseboard_fab2(sch_1):page52_i12@mstr_sconn.sconn288_h44441003(chips)!SCONN288_H44441003_PIP-SCONN,HA!!!F228!CB(4)!!!!
S!M_E_ECC<5>!J6L2!192!@baseboard_fab2_lib.baseboard_fab2(sch_1):page52_i12@mstr_sconn.sconn288_h44441003(chips)!SCONN288_H44441003_PIP-SCONN,HA!!!F228!CB(5)!!!!
S!M_E_ECC<6>!J6L2!54!@baseboard_fab2_lib.baseboard_fab2(sch_1):page52_i12@mstr_sconn.sconn288_h44441003(chips)!SCONN288_H44441003_PIP-SCONN,HA!!!F228!CB(6)!!!!
S!M_E_ECC<7>!J6L2!199!@baseboard_fab2_lib.baseboard_fab2(sch_1):page52_i12@mstr_sconn.sconn288_h44441003(chips)!SCONN288_H44441003_PIP-SCONN,HA!!!F228!CB(7)!!!!
S!M_E_CLK_DN<2>!J6L2!75!@baseboard_fab2_lib.baseboard_fab2(sch_1):page52_i12@mstr_sconn.sconn288_h44441003(chips)!SCONN288_H44441003_PIP-SCONN,HA!!!F228!CK0N!!!!
S!M_E_CLK_DP<2>!J6L2!74!@baseboard_fab2_lib.baseboard_fab2(sch_1):page52_i12@mstr_sconn.sconn288_h44441003(chips)!SCONN288_H44441003_PIP-SCONN,HA!!!F228!CK0P!!!!
S!M_E_CLK_DN<3>!J6L2!219!@baseboard_fab2_lib.baseboard_fab2(sch_1):page52_i12@mstr_sconn.sconn288_h44441003(chips)!SCONN288_H44441003_PIP-SCONN,HA!!!F228!CK1N!!!!
S!M_E_CLK_DP<3>!J6L2!218!@baseboard_fab2_lib.baseboard_fab2(sch_1):page52_i12@mstr_sconn.sconn288_h44441003(chips)!SCONN288_H44441003_PIP-SCONN,HA!!!F228!CK1P!!!!
S!M_E_CKE<2>!J6L2!60!@baseboard_fab2_lib.baseboard_fab2(sch_1):page52_i12@mstr_sconn.sconn288_h44441003(chips)!SCONN288_H44441003_PIP-SCONN,HA!!!F228!CKE(0)!!!!
S!M_E_CKE<3>!J6L2!203!@baseboard_fab2_lib.baseboard_fab2(sch_1):page52_i12@mstr_sconn.sconn288_h44441003(chips)!SCONN288_H44441003_PIP-SCONN,HA!!!F228!CKE(1)!!!!
S!M_E_DQ<0>!J6L2!5!@baseboard_fab2_lib.baseboard_fab2(sch_1):page52_i12@mstr_sconn.sconn288_h44441003(chips)!SCONN288_H44441003_PIP-SCONN,HA!!!F228!DQ(0)!!!!
S!M_E_DQ<10>!J6L2!23!@baseboard_fab2_lib.baseboard_fab2(sch_1):page52_i12@mstr_sconn.sconn288_h44441003(chips)!SCONN288_H44441003_PIP-SCONN,HA!!!F228!DQ(10)!!!!
S!M_E_DQ<11>!J6L2!168!@baseboard_fab2_lib.baseboard_fab2(sch_1):page52_i12@mstr_sconn.sconn288_h44441003(chips)!SCONN288_H44441003_PIP-SCONN,HA!!!F228!DQ(11)!!!!
S!M_E_DQ<12>!J6L2!14!@baseboard_fab2_lib.baseboard_fab2(sch_1):page52_i12@mstr_sconn.sconn288_h44441003(chips)!SCONN288_H44441003_PIP-SCONN,HA!!!F228!DQ(12)!!!!
S!M_E_DQ<13>!J6L2!159!@baseboard_fab2_lib.baseboard_fab2(sch_1):page52_i12@mstr_sconn.sconn288_h44441003(chips)!SCONN288_H44441003_PIP-SCONN,HA!!!F228!DQ(13)!!!!
S!M_E_DQ<14>!J6L2!21!@baseboard_fab2_lib.baseboard_fab2(sch_1):page52_i12@mstr_sconn.sconn288_h44441003(chips)!SCONN288_H44441003_PIP-SCONN,HA!!!F228!DQ(14)!!!!
S!M_E_DQ<15>!J6L2!166!@baseboard_fab2_lib.baseboard_fab2(sch_1):page52_i12@mstr_sconn.sconn288_h44441003(chips)!SCONN288_H44441003_PIP-SCONN,HA!!!F228!DQ(15)!!!!
S!M_E_DQ<16>!J6L2!27!@baseboard_fab2_lib.baseboard_fab2(sch_1):page52_i12@mstr_sconn.sconn288_h44441003(chips)!SCONN288_H44441003_PIP-SCONN,HA!!!F228!DQ(16)!!!!
S!M_E_DQ<17>!J6L2!172!@baseboard_fab2_lib.baseboard_fab2(sch_1):page52_i12@mstr_sconn.sconn288_h44441003(chips)!SCONN288_H44441003_PIP-SCONN,HA!!!F228!DQ(17)!!!!
S!M_E_DQ<18>!J6L2!34!@baseboard_fab2_lib.baseboard_fab2(sch_1):page52_i12@mstr_sconn.sconn288_h44441003(chips)!SCONN288_H44441003_PIP-SCONN,HA!!!F228!DQ(18)!!!!
S!M_E_DQ<19>!J6L2!179!@baseboard_fab2_lib.baseboard_fab2(sch_1):page52_i12@mstr_sconn.sconn288_h44441003(chips)!SCONN288_H44441003_PIP-SCONN,HA!!!F228!DQ(19)!!!!
S!M_E_DQ<1>!J6L2!150!@baseboard_fab2_lib.baseboard_fab2(sch_1):page52_i12@mstr_sconn.sconn288_h44441003(chips)!SCONN288_H44441003_PIP-SCONN,HA!!!F228!DQ(1)!!!!
S!M_E_DQ<20>!J6L2!25!@baseboard_fab2_lib.baseboard_fab2(sch_1):page52_i12@mstr_sconn.sconn288_h44441003(chips)!SCONN288_H44441003_PIP-SCONN,HA!!!F228!DQ(20)!!!!
S!M_E_DQ<21>!J6L2!170!@baseboard_fab2_lib.baseboard_fab2(sch_1):page52_i12@mstr_sconn.sconn288_h44441003(chips)!SCONN288_H44441003_PIP-SCONN,HA!!!F228!DQ(21)!!!!
S!M_E_DQ<22>!J6L2!32!@baseboard_fab2_lib.baseboard_fab2(sch_1):page52_i12@mstr_sconn.sconn288_h44441003(chips)!SCONN288_H44441003_PIP-SCONN,HA!!!F228!DQ(22)!!!!
S!M_E_DQ<23>!J6L2!177!@baseboard_fab2_lib.baseboard_fab2(sch_1):page52_i12@mstr_sconn.sconn288_h44441003(chips)!SCONN288_H44441003_PIP-SCONN,HA!!!F228!DQ(23)!!!!
S!M_E_DQ<24>!J6L2!38!@baseboard_fab2_lib.baseboard_fab2(sch_1):page52_i12@mstr_sconn.sconn288_h44441003(chips)!SCONN288_H44441003_PIP-SCONN,HA!!!F228!DQ(24)!!!!
S!M_E_DQ<25>!J6L2!183!@baseboard_fab2_lib.baseboard_fab2(sch_1):page52_i12@mstr_sconn.sconn288_h44441003(chips)!SCONN288_H44441003_PIP-SCONN,HA!!!F228!DQ(25)!!!!
S!M_E_DQ<26>!J6L2!45!@baseboard_fab2_lib.baseboard_fab2(sch_1):page52_i12@mstr_sconn.sconn288_h44441003(chips)!SCONN288_H44441003_PIP-SCONN,HA!!!F228!DQ(26)!!!!
S!M_E_DQ<27>!J6L2!190!@baseboard_fab2_lib.baseboard_fab2(sch_1):page52_i12@mstr_sconn.sconn288_h44441003(chips)!SCONN288_H44441003_PIP-SCONN,HA!!!F228!DQ(27)!!!!
S!M_E_DQ<28>!J6L2!36!@baseboard_fab2_lib.baseboard_fab2(sch_1):page52_i12@mstr_sconn.sconn288_h44441003(chips)!SCONN288_H44441003_PIP-SCONN,HA!!!F228!DQ(28)!!!!
S!M_E_DQ<29>!J6L2!181!@baseboard_fab2_lib.baseboard_fab2(sch_1):page52_i12@mstr_sconn.sconn288_h44441003(chips)!SCONN288_H44441003_PIP-SCONN,HA!!!F228!DQ(29)!!!!
S!M_E_DQ<2>!J6L2!12!@baseboard_fab2_lib.baseboard_fab2(sch_1):page52_i12@mstr_sconn.sconn288_h44441003(chips)!SCONN288_H44441003_PIP-SCONN,HA!!!F228!DQ(2)!!!!
S!M_E_DQ<30>!J6L2!43!@baseboard_fab2_lib.baseboard_fab2(sch_1):page52_i12@mstr_sconn.sconn288_h44441003(chips)!SCONN288_H44441003_PIP-SCONN,HA!!!F228!DQ(30)!!!!
S!M_E_DQ<31>!J6L2!188!@baseboard_fab2_lib.baseboard_fab2(sch_1):page52_i12@mstr_sconn.sconn288_h44441003(chips)!SCONN288_H44441003_PIP-SCONN,HA!!!F228!DQ(31)!!!!
S!M_E_DQ<32>!J6L2!97!@baseboard_fab2_lib.baseboard_fab2(sch_1):page52_i12@mstr_sconn.sconn288_h44441003(chips)!SCONN288_H44441003_PIP-SCONN,HA!!!F228!DQ(32)!!!!
S!M_E_DQ<33>!J6L2!242!@baseboard_fab2_lib.baseboard_fab2(sch_1):page52_i12@mstr_sconn.sconn288_h44441003(chips)!SCONN288_H44441003_PIP-SCONN,HA!!!F228!DQ(33)!!!!
S!M_E_DQ<34>!J6L2!104!@baseboard_fab2_lib.baseboard_fab2(sch_1):page52_i12@mstr_sconn.sconn288_h44441003(chips)!SCONN288_H44441003_PIP-SCONN,HA!!!F228!DQ(34)!!!!
S!M_E_DQ<35>!J6L2!249!@baseboard_fab2_lib.baseboard_fab2(sch_1):page52_i12@mstr_sconn.sconn288_h44441003(chips)!SCONN288_H44441003_PIP-SCONN,HA!!!F228!DQ(35)!!!!
S!M_E_DQ<36>!J6L2!95!@baseboard_fab2_lib.baseboard_fab2(sch_1):page52_i12@mstr_sconn.sconn288_h44441003(chips)!SCONN288_H44441003_PIP-SCONN,HA!!!F228!DQ(36)!!!!
S!M_E_DQ<37>!J6L2!240!@baseboard_fab2_lib.baseboard_fab2(sch_1):page52_i12@mstr_sconn.sconn288_h44441003(chips)!SCONN288_H44441003_PIP-SCONN,HA!!!F228!DQ(37)!!!!
S!M_E_DQ<38>!J6L2!102!@baseboard_fab2_lib.baseboard_fab2(sch_1):page52_i12@mstr_sconn.sconn288_h44441003(chips)!SCONN288_H44441003_PIP-SCONN,HA!!!F228!DQ(38)!!!!
S!M_E_DQ<39>!J6L2!247!@baseboard_fab2_lib.baseboard_fab2(sch_1):page52_i12@mstr_sconn.sconn288_h44441003(chips)!SCONN288_H44441003_PIP-SCONN,HA!!!F228!DQ(39)!!!!
S!M_E_DQ<3>!J6L2!157!@baseboard_fab2_lib.baseboard_fab2(sch_1):page52_i12@mstr_sconn.sconn288_h44441003(chips)!SCONN288_H44441003_PIP-SCONN,HA!!!F228!DQ(3)!!!!
S!M_E_DQ<40>!J6L2!108!@baseboard_fab2_lib.baseboard_fab2(sch_1):page52_i12@mstr_sconn.sconn288_h44441003(chips)!SCONN288_H44441003_PIP-SCONN,HA!!!F228!DQ(40)!!!!
S!M_E_DQ<41>!J6L2!253!@baseboard_fab2_lib.baseboard_fab2(sch_1):page52_i12@mstr_sconn.sconn288_h44441003(chips)!SCONN288_H44441003_PIP-SCONN,HA!!!F228!DQ(41)!!!!
S!M_E_DQ<42>!J6L2!115!@baseboard_fab2_lib.baseboard_fab2(sch_1):page52_i12@mstr_sconn.sconn288_h44441003(chips)!SCONN288_H44441003_PIP-SCONN,HA!!!F228!DQ(42)!!!!
S!M_E_DQ<43>!J6L2!260!@baseboard_fab2_lib.baseboard_fab2(sch_1):page52_i12@mstr_sconn.sconn288_h44441003(chips)!SCONN288_H44441003_PIP-SCONN,HA!!!F228!DQ(43)!!!!
S!M_E_DQ<44>!J6L2!106!@baseboard_fab2_lib.baseboard_fab2(sch_1):page52_i12@mstr_sconn.sconn288_h44441003(chips)!SCONN288_H44441003_PIP-SCONN,HA!!!F228!DQ(44)!!!!
S!M_E_DQ<45>!J6L2!251!@baseboard_fab2_lib.baseboard_fab2(sch_1):page52_i12@mstr_sconn.sconn288_h44441003(chips)!SCONN288_H44441003_PIP-SCONN,HA!!!F228!DQ(45)!!!!
S!M_E_DQ<46>!J6L2!113!@baseboard_fab2_lib.baseboard_fab2(sch_1):page52_i12@mstr_sconn.sconn288_h44441003(chips)!SCONN288_H44441003_PIP-SCONN,HA!!!F228!DQ(46)!!!!
S!M_E_DQ<47>!J6L2!258!@baseboard_fab2_lib.baseboard_fab2(sch_1):page52_i12@mstr_sconn.sconn288_h44441003(chips)!SCONN288_H44441003_PIP-SCONN,HA!!!F228!DQ(47)!!!!
S!M_E_DQ<48>!J6L2!119!@baseboard_fab2_lib.baseboard_fab2(sch_1):page52_i12@mstr_sconn.sconn288_h44441003(chips)!SCONN288_H44441003_PIP-SCONN,HA!!!F228!DQ(48)!!!!
S!M_E_DQ<49>!J6L2!264!@baseboard_fab2_lib.baseboard_fab2(sch_1):page52_i12@mstr_sconn.sconn288_h44441003(chips)!SCONN288_H44441003_PIP-SCONN,HA!!!F228!DQ(49)!!!!
S!M_E_DQ<4>!J6L2!3!@baseboard_fab2_lib.baseboard_fab2(sch_1):page52_i12@mstr_sconn.sconn288_h44441003(chips)!SCONN288_H44441003_PIP-SCONN,HA!!!F228!DQ(4)!!!!
S!M_E_DQ<50>!J6L2!126!@baseboard_fab2_lib.baseboard_fab2(sch_1):page52_i12@mstr_sconn.sconn288_h44441003(chips)!SCONN288_H44441003_PIP-SCONN,HA!!!F228!DQ(50)!!!!
S!M_E_DQ<51>!J6L2!271!@baseboard_fab2_lib.baseboard_fab2(sch_1):page52_i12@mstr_sconn.sconn288_h44441003(chips)!SCONN288_H44441003_PIP-SCONN,HA!!!F228!DQ(51)!!!!
S!M_E_DQ<52>!J6L2!117!@baseboard_fab2_lib.baseboard_fab2(sch_1):page52_i12@mstr_sconn.sconn288_h44441003(chips)!SCONN288_H44441003_PIP-SCONN,HA!!!F228!DQ(52)!!!!
S!M_E_DQ<53>!J6L2!262!@baseboard_fab2_lib.baseboard_fab2(sch_1):page52_i12@mstr_sconn.sconn288_h44441003(chips)!SCONN288_H44441003_PIP-SCONN,HA!!!F228!DQ(53)!!!!
S!M_E_DQ<54>!J6L2!124!@baseboard_fab2_lib.baseboard_fab2(sch_1):page52_i12@mstr_sconn.sconn288_h44441003(chips)!SCONN288_H44441003_PIP-SCONN,HA!!!F228!DQ(54)!!!!
S!M_E_DQ<55>!J6L2!269!@baseboard_fab2_lib.baseboard_fab2(sch_1):page52_i12@mstr_sconn.sconn288_h44441003(chips)!SCONN288_H44441003_PIP-SCONN,HA!!!F228!DQ(55)!!!!
S!M_E_DQ<56>!J6L2!130!@baseboard_fab2_lib.baseboard_fab2(sch_1):page52_i12@mstr_sconn.sconn288_h44441003(chips)!SCONN288_H44441003_PIP-SCONN,HA!!!F228!DQ(56)!!!!
S!M_E_DQ<57>!J6L2!275!@baseboard_fab2_lib.baseboard_fab2(sch_1):page52_i12@mstr_sconn.sconn288_h44441003(chips)!SCONN288_H44441003_PIP-SCONN,HA!!!F228!DQ(57)!!!!
S!M_E_DQ<58>!J6L2!137!@baseboard_fab2_lib.baseboard_fab2(sch_1):page52_i12@mstr_sconn.sconn288_h44441003(chips)!SCONN288_H44441003_PIP-SCONN,HA!!!F228!DQ(58)!!!!
S!M_E_DQ<59>!J6L2!282!@baseboard_fab2_lib.baseboard_fab2(sch_1):page52_i12@mstr_sconn.sconn288_h44441003(chips)!SCONN288_H44441003_PIP-SCONN,HA!!!F228!DQ(59)!!!!
S!M_E_DQ<5>!J6L2!148!@baseboard_fab2_lib.baseboard_fab2(sch_1):page52_i12@mstr_sconn.sconn288_h44441003(chips)!SCONN288_H44441003_PIP-SCONN,HA!!!F228!DQ(5)!!!!
S!M_E_DQ<60>!J6L2!128!@baseboard_fab2_lib.baseboard_fab2(sch_1):page52_i12@mstr_sconn.sconn288_h44441003(chips)!SCONN288_H44441003_PIP-SCONN,HA!!!F228!DQ(60)!!!!
S!M_E_DQ<61>!J6L2!273!@baseboard_fab2_lib.baseboard_fab2(sch_1):page52_i12@mstr_sconn.sconn288_h44441003(chips)!SCONN288_H44441003_PIP-SCONN,HA!!!F228!DQ(61)!!!!
S!M_E_DQ<62>!J6L2!135!@baseboard_fab2_lib.baseboard_fab2(sch_1):page52_i12@mstr_sconn.sconn288_h44441003(chips)!SCONN288_H44441003_PIP-SCONN,HA!!!F228!DQ(62)!!!!
S!M_E_DQ<63>!J6L2!280!@baseboard_fab2_lib.baseboard_fab2(sch_1):page52_i12@mstr_sconn.sconn288_h44441003(chips)!SCONN288_H44441003_PIP-SCONN,HA!!!F228!DQ(63)!!!!
S!M_E_DQ<6>!J6L2!10!@baseboard_fab2_lib.baseboard_fab2(sch_1):page52_i12@mstr_sconn.sconn288_h44441003(chips)!SCONN288_H44441003_PIP-SCONN,HA!!!F228!DQ(6)!!!!
S!M_E_DQ<7>!J6L2!155!@baseboard_fab2_lib.baseboard_fab2(sch_1):page52_i12@mstr_sconn.sconn288_h44441003(chips)!SCONN288_H44441003_PIP-SCONN,HA!!!F228!DQ(7)!!!!
S!M_E_DQ<8>!J6L2!16!@baseboard_fab2_lib.baseboard_fab2(sch_1):page52_i12@mstr_sconn.sconn288_h44441003(chips)!SCONN288_H44441003_PIP-SCONN,HA!!!F228!DQ(8)!!!!
S!M_E_DQ<9>!J6L2!161!@baseboard_fab2_lib.baseboard_fab2(sch_1):page52_i12@mstr_sconn.sconn288_h44441003(chips)!SCONN288_H44441003_PIP-SCONN,HA!!!F228!DQ(9)!!!!
S!FM_DIMM_EVENT_COD_N!J6L2!78!@baseboard_fab2_lib.baseboard_fab2(sch_1):page52_i12@mstr_sconn.sconn288_h44441003(chips)!SCONN288_H44441003_PIP-SCONN,HA!!!F228!EVENT_N!!!!
S!M_E_ODT<2>!J6L2!87!@baseboard_fab2_lib.baseboard_fab2(sch_1):page52_i12@mstr_sconn.sconn288_h44441003(chips)!SCONN288_H44441003_PIP-SCONN,HA!!!F228!ODT(0)!!!!
S!M_E_ODT<3>!J6L2!91!@baseboard_fab2_lib.baseboard_fab2(sch_1):page52_i12@mstr_sconn.sconn288_h44441003(chips)!SCONN288_H44441003_PIP-SCONN,HA!!!F228!ODT(1)!!!!
S!M_E_PAR!J6L2!222!@baseboard_fab2_lib.baseboard_fab2(sch_1):page52_i12@mstr_sconn.sconn288_h44441003(chips)!SCONN288_H44441003_PIP-SCONN,HA!!!F228!PAR!!!!
S!M_DEF_RST_N!J6L2!58!@baseboard_fab2_lib.baseboard_fab2(sch_1):page52_i12@mstr_sconn.sconn288_h44441003(chips)!SCONN288_H44441003_PIP-SCONN,HA!!!F228!RESET_N!!!!
S!TP_CH_E_DIMM_E1_RFU_0!J6L2!205!@baseboard_fab2_lib.baseboard_fab2(sch_1):page52_i12@mstr_sconn.sconn288_h44441003(chips)!SCONN288_H44441003_PIP-SCONN,HA!!!F228!RFU(0)!!!!
S!TP_CH_E_DIMM_E1_RFU_1!J6L2!227!@baseboard_fab2_lib.baseboard_fab2(sch_1):page52_i12@mstr_sconn.sconn288_h44441003(chips)!SCONN288_H44441003_PIP-SCONN,HA!!!F228!RFU(1)!!!!
S!TP_CH_E_DIMM_E1_RFU_2!J6L2!144!@baseboard_fab2_lib.baseboard_fab2(sch_1):page52_i12@mstr_sconn.sconn288_h44441003(chips)!SCONN288_H44441003_PIP-SCONN,HA!!!F228!RFU(2)!!!!
S!M_E_CS_N<4>!J6L2!84!@baseboard_fab2_lib.baseboard_fab2(sch_1):page52_i12@mstr_sconn.sconn288_h44441003(chips)!SCONN288_H44441003_PIP-SCONN,HA!!!F228!S0_N!!!!
S!M_E_CS_N<5>!J6L2!89!@baseboard_fab2_lib.baseboard_fab2(sch_1):page52_i12@mstr_sconn.sconn288_h44441003(chips)!SCONN288_H44441003_PIP-SCONN,HA!!!F228!S1_N!!!!
S!M_E_CS_N<6>!J6L2!93!@baseboard_fab2_lib.baseboard_fab2(sch_1):page52_i12@mstr_sconn.sconn288_h44441003(chips)!SCONN288_H44441003_PIP-SCONN,HA!!!F228!S2_N_C(0)!!!!
S!M_E_CS_N<7>!J6L2!237!@baseboard_fab2_lib.baseboard_fab2(sch_1):page52_i12@mstr_sconn.sconn288_h44441003(chips)!SCONN288_H44441003_PIP-SCONN,HA!!!F228!S3_N_C(1)!!!!
S!PVPP_DEF!J6L2!139!@baseboard_fab2_lib.baseboard_fab2(sch_1):page52_i12@mstr_sconn.sconn288_h44441003(chips)!SCONN288_H44441003_PIP-SCONN,HA!!!F228!SA(0)!!!!
S!PVPP_DEF!J6L2!140!@baseboard_fab2_lib.baseboard_fab2(sch_1):page52_i12@mstr_sconn.sconn288_h44441003(chips)!SCONN288_H44441003_PIP-SCONN,HA!!!F228!SA(1)!!!!
S!GND!J6L2!238!@baseboard_fab2_lib.baseboard_fab2(sch_1):page52_i12@mstr_sconn.sconn288_h44441003(chips)!SCONN288_H44441003_PIP-SCONN,HA!!!F228!SA(2)!!!!
S!FM_ADR_COMPLETE_DEF_N!J6L2!230!@baseboard_fab2_lib.baseboard_fab2(sch_1):page52_i12@mstr_sconn.sconn288_h44441003(chips)!SCONN288_H44441003_PIP-SCONN,HA!!!F228!SAVE_N_NC!!!!
S!SMB_DDR_DEF_VPP_SCL!J6L2!141!@baseboard_fab2_lib.baseboard_fab2(sch_1):page52_i12@mstr_sconn.sconn288_h44441003(chips)!SCONN288_H44441003_PIP-SCONN,HA!!!F228!SCL!!!!
S!SMB_DDR_DEF_VPP_SDA!J6L2!285!@baseboard_fab2_lib.baseboard_fab2(sch_1):page52_i12@mstr_sconn.sconn288_h44441003(chips)!SCONN288_H44441003_PIP-SCONN,HA!!!F228!SDA!!!!
S!PVPP_DEF!J6L2!284!@baseboard_fab2_lib.baseboard_fab2(sch_1):page52_i12@mstr_sconn.sconn288_h44441003(chips)!SCONN288_H44441003_PIP-SCONN,HA!!!F228!VDDSPD!!!!
S!M_E_VREF!J6L2!146!@baseboard_fab2_lib.baseboard_fab2(sch_1):page52_i12@mstr_sconn.sconn288_h44441003(chips)!SCONN288_H44441003_PIP-SCONN,HA!!!F228!VREFCA!!!!
S!M_E_DQS_DN<0>!J6L2!152!@baseboard_fab2_lib.baseboard_fab2(sch_1):page52_i100@mstr_sconn.sconn288_h44441003(chips)!SCONN288_H44441003_PIP-SCONN,HA!!!F227!DQS0N!!!!
S!M_E_DQS_DP<0>!J6L2!153!@baseboard_fab2_lib.baseboard_fab2(sch_1):page52_i100@mstr_sconn.sconn288_h44441003(chips)!SCONN288_H44441003_PIP-SCONN,HA!!!F227!DQS0P!!!!
S!M_E_DQS_DN<10>!J6L2!19!@baseboard_fab2_lib.baseboard_fab2(sch_1):page52_i100@mstr_sconn.sconn288_h44441003(chips)!SCONN288_H44441003_PIP-SCONN,HA!!!F227!DQS10N!!!!
S!M_E_DQS_DP<10>!J6L2!18!@baseboard_fab2_lib.baseboard_fab2(sch_1):page52_i100@mstr_sconn.sconn288_h44441003(chips)!SCONN288_H44441003_PIP-SCONN,HA!!!F227!DQS10P!!!!
S!M_E_DQS_DN<11>!J6L2!30!@baseboard_fab2_lib.baseboard_fab2(sch_1):page52_i100@mstr_sconn.sconn288_h44441003(chips)!SCONN288_H44441003_PIP-SCONN,HA!!!F227!DQS11N!!!!
S!M_E_DQS_DP<11>!J6L2!29!@baseboard_fab2_lib.baseboard_fab2(sch_1):page52_i100@mstr_sconn.sconn288_h44441003(chips)!SCONN288_H44441003_PIP-SCONN,HA!!!F227!DQS11P!!!!
S!M_E_DQS_DN<12>!J6L2!41!@baseboard_fab2_lib.baseboard_fab2(sch_1):page52_i100@mstr_sconn.sconn288_h44441003(chips)!SCONN288_H44441003_PIP-SCONN,HA!!!F227!DQS12N!!!!
S!M_E_DQS_DP<12>!J6L2!40!@baseboard_fab2_lib.baseboard_fab2(sch_1):page52_i100@mstr_sconn.sconn288_h44441003(chips)!SCONN288_H44441003_PIP-SCONN,HA!!!F227!DQS12P!!!!
S!M_E_DQS_DN<13>!J6L2!100!@baseboard_fab2_lib.baseboard_fab2(sch_1):page52_i100@mstr_sconn.sconn288_h44441003(chips)!SCONN288_H44441003_PIP-SCONN,HA!!!F227!DQS13N!!!!
S!M_E_DQS_DP<13>!J6L2!99!@baseboard_fab2_lib.baseboard_fab2(sch_1):page52_i100@mstr_sconn.sconn288_h44441003(chips)!SCONN288_H44441003_PIP-SCONN,HA!!!F227!DQS13P!!!!
S!M_E_DQS_DN<14>!J6L2!111!@baseboard_fab2_lib.baseboard_fab2(sch_1):page52_i100@mstr_sconn.sconn288_h44441003(chips)!SCONN288_H44441003_PIP-SCONN,HA!!!F227!DQS14N!!!!
S!M_E_DQS_DP<14>!J6L2!110!@baseboard_fab2_lib.baseboard_fab2(sch_1):page52_i100@mstr_sconn.sconn288_h44441003(chips)!SCONN288_H44441003_PIP-SCONN,HA!!!F227!DQS14P!!!!
S!M_E_DQS_DN<15>!J6L2!122!@baseboard_fab2_lib.baseboard_fab2(sch_1):page52_i100@mstr_sconn.sconn288_h44441003(chips)!SCONN288_H44441003_PIP-SCONN,HA!!!F227!DQS15N!!!!
S!M_E_DQS_DP<15>!J6L2!121!@baseboard_fab2_lib.baseboard_fab2(sch_1):page52_i100@mstr_sconn.sconn288_h44441003(chips)!SCONN288_H44441003_PIP-SCONN,HA!!!F227!DQS15P!!!!
S!M_E_DQS_DN<16>!J6L2!133!@baseboard_fab2_lib.baseboard_fab2(sch_1):page52_i100@mstr_sconn.sconn288_h44441003(chips)!SCONN288_H44441003_PIP-SCONN,HA!!!F227!DQS16N!!!!
S!M_E_DQS_DP<16>!J6L2!132!@baseboard_fab2_lib.baseboard_fab2(sch_1):page52_i100@mstr_sconn.sconn288_h44441003(chips)!SCONN288_H44441003_PIP-SCONN,HA!!!F227!DQS16P!!!!
S!M_E_DQS_DN<17>!J6L2!52!@baseboard_fab2_lib.baseboard_fab2(sch_1):page52_i100@mstr_sconn.sconn288_h44441003(chips)!SCONN288_H44441003_PIP-SCONN,HA!!!F227!DQS17N!!!!
S!M_E_DQS_DP<17>!J6L2!51!@baseboard_fab2_lib.baseboard_fab2(sch_1):page52_i100@mstr_sconn.sconn288_h44441003(chips)!SCONN288_H44441003_PIP-SCONN,HA!!!F227!DQS17P!!!!
S!M_E_DQS_DN<1>!J6L2!163!@baseboard_fab2_lib.baseboard_fab2(sch_1):page52_i100@mstr_sconn.sconn288_h44441003(chips)!SCONN288_H44441003_PIP-SCONN,HA!!!F227!DQS1N!!!!
S!M_E_DQS_DP<1>!J6L2!164!@baseboard_fab2_lib.baseboard_fab2(sch_1):page52_i100@mstr_sconn.sconn288_h44441003(chips)!SCONN288_H44441003_PIP-SCONN,HA!!!F227!DQS1P!!!!
S!M_E_DQS_DN<2>!J6L2!174!@baseboard_fab2_lib.baseboard_fab2(sch_1):page52_i100@mstr_sconn.sconn288_h44441003(chips)!SCONN288_H44441003_PIP-SCONN,HA!!!F227!DQS2N!!!!
S!M_E_DQS_DP<2>!J6L2!175!@baseboard_fab2_lib.baseboard_fab2(sch_1):page52_i100@mstr_sconn.sconn288_h44441003(chips)!SCONN288_H44441003_PIP-SCONN,HA!!!F227!DQS2P!!!!
S!M_E_DQS_DN<3>!J6L2!185!@baseboard_fab2_lib.baseboard_fab2(sch_1):page52_i100@mstr_sconn.sconn288_h44441003(chips)!SCONN288_H44441003_PIP-SCONN,HA!!!F227!DQS3N!!!!
S!M_E_DQS_DP<3>!J6L2!186!@baseboard_fab2_lib.baseboard_fab2(sch_1):page52_i100@mstr_sconn.sconn288_h44441003(chips)!SCONN288_H44441003_PIP-SCONN,HA!!!F227!DQS3P!!!!
S!M_E_DQS_DN<4>!J6L2!244!@baseboard_fab2_lib.baseboard_fab2(sch_1):page52_i100@mstr_sconn.sconn288_h44441003(chips)!SCONN288_H44441003_PIP-SCONN,HA!!!F227!DQS4N!!!!
S!M_E_DQS_DP<4>!J6L2!245!@baseboard_fab2_lib.baseboard_fab2(sch_1):page52_i100@mstr_sconn.sconn288_h44441003(chips)!SCONN288_H44441003_PIP-SCONN,HA!!!F227!DQS4P!!!!
S!M_E_DQS_DN<5>!J6L2!255!@baseboard_fab2_lib.baseboard_fab2(sch_1):page52_i100@mstr_sconn.sconn288_h44441003(chips)!SCONN288_H44441003_PIP-SCONN,HA!!!F227!DQS5N!!!!
S!M_E_DQS_DP<5>!J6L2!256!@baseboard_fab2_lib.baseboard_fab2(sch_1):page52_i100@mstr_sconn.sconn288_h44441003(chips)!SCONN288_H44441003_PIP-SCONN,HA!!!F227!DQS5P!!!!
S!M_E_DQS_DN<6>!J6L2!266!@baseboard_fab2_lib.baseboard_fab2(sch_1):page52_i100@mstr_sconn.sconn288_h44441003(chips)!SCONN288_H44441003_PIP-SCONN,HA!!!F227!DQS6N!!!!
S!M_E_DQS_DP<6>!J6L2!267!@baseboard_fab2_lib.baseboard_fab2(sch_1):page52_i100@mstr_sconn.sconn288_h44441003(chips)!SCONN288_H44441003_PIP-SCONN,HA!!!F227!DQS6P!!!!
S!M_E_DQS_DN<7>!J6L2!277!@baseboard_fab2_lib.baseboard_fab2(sch_1):page52_i100@mstr_sconn.sconn288_h44441003(chips)!SCONN288_H44441003_PIP-SCONN,HA!!!F227!DQS7N!!!!
S!M_E_DQS_DP<7>!J6L2!278!@baseboard_fab2_lib.baseboard_fab2(sch_1):page52_i100@mstr_sconn.sconn288_h44441003(chips)!SCONN288_H44441003_PIP-SCONN,HA!!!F227!DQS7P!!!!
S!M_E_DQS_DN<8>!J6L2!196!@baseboard_fab2_lib.baseboard_fab2(sch_1):page52_i100@mstr_sconn.sconn288_h44441003(chips)!SCONN288_H44441003_PIP-SCONN,HA!!!F227!DQS8N!!!!
S!M_E_DQS_DP<8>!J6L2!197!@baseboard_fab2_lib.baseboard_fab2(sch_1):page52_i100@mstr_sconn.sconn288_h44441003(chips)!SCONN288_H44441003_PIP-SCONN,HA!!!F227!DQS8P!!!!
S!M_E_DQS_DN<9>!J6L2!8!@baseboard_fab2_lib.baseboard_fab2(sch_1):page52_i100@mstr_sconn.sconn288_h44441003(chips)!SCONN288_H44441003_PIP-SCONN,HA!!!F227!DQS9N!!!!
S!M_E_DQS_DP<9>!J6L2!7!@baseboard_fab2_lib.baseboard_fab2(sch_1):page52_i100@mstr_sconn.sconn288_h44441003(chips)!SCONN288_H44441003_PIP-SCONN,HA!!!F227!DQS9P!!!!
S!GND!J6L2!283!@baseboard_fab2_lib.baseboard_fab2(sch_1):page52_i138@mstr_sconn.sconn288_h44441003(chips)!SCONN288_H44441003_PIP-SCONN,HA!!!F226!VSS(0)!!!!
S!GND!J6L2!261!@baseboard_fab2_lib.baseboard_fab2(sch_1):page52_i138@mstr_sconn.sconn288_h44441003(chips)!SCONN288_H44441003_PIP-SCONN,HA!!!F226!VSS(10)!!!!
S!GND!J6L2!259!@baseboard_fab2_lib.baseboard_fab2(sch_1):page52_i138@mstr_sconn.sconn288_h44441003(chips)!SCONN288_H44441003_PIP-SCONN,HA!!!F226!VSS(11)!!!!
S!GND!J6L2!257!@baseboard_fab2_lib.baseboard_fab2(sch_1):page52_i138@mstr_sconn.sconn288_h44441003(chips)!SCONN288_H44441003_PIP-SCONN,HA!!!F226!VSS(12)!!!!
S!GND!J6L2!254!@baseboard_fab2_lib.baseboard_fab2(sch_1):page52_i138@mstr_sconn.sconn288_h44441003(chips)!SCONN288_H44441003_PIP-SCONN,HA!!!F226!VSS(13)!!!!
S!GND!J6L2!252!@baseboard_fab2_lib.baseboard_fab2(sch_1):page52_i138@mstr_sconn.sconn288_h44441003(chips)!SCONN288_H44441003_PIP-SCONN,HA!!!F226!VSS(14)!!!!
S!GND!J6L2!250!@baseboard_fab2_lib.baseboard_fab2(sch_1):page52_i138@mstr_sconn.sconn288_h44441003(chips)!SCONN288_H44441003_PIP-SCONN,HA!!!F226!VSS(15)!!!!
S!GND!J6L2!248!@baseboard_fab2_lib.baseboard_fab2(sch_1):page52_i138@mstr_sconn.sconn288_h44441003(chips)!SCONN288_H44441003_PIP-SCONN,HA!!!F226!VSS(16)!!!!
S!GND!J6L2!246!@baseboard_fab2_lib.baseboard_fab2(sch_1):page52_i138@mstr_sconn.sconn288_h44441003(chips)!SCONN288_H44441003_PIP-SCONN,HA!!!F226!VSS(17)!!!!
S!GND!J6L2!243!@baseboard_fab2_lib.baseboard_fab2(sch_1):page52_i138@mstr_sconn.sconn288_h44441003(chips)!SCONN288_H44441003_PIP-SCONN,HA!!!F226!VSS(18)!!!!
S!GND!J6L2!241!@baseboard_fab2_lib.baseboard_fab2(sch_1):page52_i138@mstr_sconn.sconn288_h44441003(chips)!SCONN288_H44441003_PIP-SCONN,HA!!!F226!VSS(19)!!!!
S!GND!J6L2!281!@baseboard_fab2_lib.baseboard_fab2(sch_1):page52_i138@mstr_sconn.sconn288_h44441003(chips)!SCONN288_H44441003_PIP-SCONN,HA!!!F226!VSS(1)!!!!
S!GND!J6L2!239!@baseboard_fab2_lib.baseboard_fab2(sch_1):page52_i138@mstr_sconn.sconn288_h44441003(chips)!SCONN288_H44441003_PIP-SCONN,HA!!!F226!VSS(20)!!!!
S!GND!J6L2!202!@baseboard_fab2_lib.baseboard_fab2(sch_1):page52_i138@mstr_sconn.sconn288_h44441003(chips)!SCONN288_H44441003_PIP-SCONN,HA!!!F226!VSS(21)!!!!
S!GND!J6L2!200!@baseboard_fab2_lib.baseboard_fab2(sch_1):page52_i138@mstr_sconn.sconn288_h44441003(chips)!SCONN288_H44441003_PIP-SCONN,HA!!!F226!VSS(22)!!!!
S!GND!J6L2!198!@baseboard_fab2_lib.baseboard_fab2(sch_1):page52_i138@mstr_sconn.sconn288_h44441003(chips)!SCONN288_H44441003_PIP-SCONN,HA!!!F226!VSS(23)!!!!
S!GND!J6L2!195!@baseboard_fab2_lib.baseboard_fab2(sch_1):page52_i138@mstr_sconn.sconn288_h44441003(chips)!SCONN288_H44441003_PIP-SCONN,HA!!!F226!VSS(24)!!!!
S!GND!J6L2!193!@baseboard_fab2_lib.baseboard_fab2(sch_1):page52_i138@mstr_sconn.sconn288_h44441003(chips)!SCONN288_H44441003_PIP-SCONN,HA!!!F226!VSS(25)!!!!
S!GND!J6L2!191!@baseboard_fab2_lib.baseboard_fab2(sch_1):page52_i138@mstr_sconn.sconn288_h44441003(chips)!SCONN288_H44441003_PIP-SCONN,HA!!!F226!VSS(26)!!!!
S!GND!J6L2!189!@baseboard_fab2_lib.baseboard_fab2(sch_1):page52_i138@mstr_sconn.sconn288_h44441003(chips)!SCONN288_H44441003_PIP-SCONN,HA!!!F226!VSS(27)!!!!
S!GND!J6L2!187!@baseboard_fab2_lib.baseboard_fab2(sch_1):page52_i138@mstr_sconn.sconn288_h44441003(chips)!SCONN288_H44441003_PIP-SCONN,HA!!!F226!VSS(28)!!!!
S!GND!J6L2!184!@baseboard_fab2_lib.baseboard_fab2(sch_1):page52_i138@mstr_sconn.sconn288_h44441003(chips)!SCONN288_H44441003_PIP-SCONN,HA!!!F226!VSS(29)!!!!
S!GND!J6L2!279!@baseboard_fab2_lib.baseboard_fab2(sch_1):page52_i138@mstr_sconn.sconn288_h44441003(chips)!SCONN288_H44441003_PIP-SCONN,HA!!!F226!VSS(2)!!!!
S!GND!J6L2!182!@baseboard_fab2_lib.baseboard_fab2(sch_1):page52_i138@mstr_sconn.sconn288_h44441003(chips)!SCONN288_H44441003_PIP-SCONN,HA!!!F226!VSS(30)!!!!
S!GND!J6L2!180!@baseboard_fab2_lib.baseboard_fab2(sch_1):page52_i138@mstr_sconn.sconn288_h44441003(chips)!SCONN288_H44441003_PIP-SCONN,HA!!!F226!VSS(31)!!!!
S!GND!J6L2!178!@baseboard_fab2_lib.baseboard_fab2(sch_1):page52_i138@mstr_sconn.sconn288_h44441003(chips)!SCONN288_H44441003_PIP-SCONN,HA!!!F226!VSS(32)!!!!
S!GND!J6L2!176!@baseboard_fab2_lib.baseboard_fab2(sch_1):page52_i138@mstr_sconn.sconn288_h44441003(chips)!SCONN288_H44441003_PIP-SCONN,HA!!!F226!VSS(33)!!!!
S!GND!J6L2!173!@baseboard_fab2_lib.baseboard_fab2(sch_1):page52_i138@mstr_sconn.sconn288_h44441003(chips)!SCONN288_H44441003_PIP-SCONN,HA!!!F226!VSS(34)!!!!
S!GND!J6L2!171!@baseboard_fab2_lib.baseboard_fab2(sch_1):page52_i138@mstr_sconn.sconn288_h44441003(chips)!SCONN288_H44441003_PIP-SCONN,HA!!!F226!VSS(35)!!!!
S!GND!J6L2!169!@baseboard_fab2_lib.baseboard_fab2(sch_1):page52_i138@mstr_sconn.sconn288_h44441003(chips)!SCONN288_H44441003_PIP-SCONN,HA!!!F226!VSS(36)!!!!
S!GND!J6L2!167!@baseboard_fab2_lib.baseboard_fab2(sch_1):page52_i138@mstr_sconn.sconn288_h44441003(chips)!SCONN288_H44441003_PIP-SCONN,HA!!!F226!VSS(37)!!!!
S!GND!J6L2!165!@baseboard_fab2_lib.baseboard_fab2(sch_1):page52_i138@mstr_sconn.sconn288_h44441003(chips)!SCONN288_H44441003_PIP-SCONN,HA!!!F226!VSS(38)!!!!
S!GND!J6L2!162!@baseboard_fab2_lib.baseboard_fab2(sch_1):page52_i138@mstr_sconn.sconn288_h44441003(chips)!SCONN288_H44441003_PIP-SCONN,HA!!!F226!VSS(39)!!!!
S!GND!J6L2!276!@baseboard_fab2_lib.baseboard_fab2(sch_1):page52_i138@mstr_sconn.sconn288_h44441003(chips)!SCONN288_H44441003_PIP-SCONN,HA!!!F226!VSS(3)!!!!
S!GND!J6L2!160!@baseboard_fab2_lib.baseboard_fab2(sch_1):page52_i138@mstr_sconn.sconn288_h44441003(chips)!SCONN288_H44441003_PIP-SCONN,HA!!!F226!VSS(40)!!!!
S!GND!J6L2!158!@baseboard_fab2_lib.baseboard_fab2(sch_1):page52_i138@mstr_sconn.sconn288_h44441003(chips)!SCONN288_H44441003_PIP-SCONN,HA!!!F226!VSS(41)!!!!
S!GND!J6L2!156!@baseboard_fab2_lib.baseboard_fab2(sch_1):page52_i138@mstr_sconn.sconn288_h44441003(chips)!SCONN288_H44441003_PIP-SCONN,HA!!!F226!VSS(42)!!!!
S!GND!J6L2!154!@baseboard_fab2_lib.baseboard_fab2(sch_1):page52_i138@mstr_sconn.sconn288_h44441003(chips)!SCONN288_H44441003_PIP-SCONN,HA!!!F226!VSS(43)!!!!
S!GND!J6L2!151!@baseboard_fab2_lib.baseboard_fab2(sch_1):page52_i138@mstr_sconn.sconn288_h44441003(chips)!SCONN288_H44441003_PIP-SCONN,HA!!!F226!VSS(44)!!!!
S!GND!J6L2!149!@baseboard_fab2_lib.baseboard_fab2(sch_1):page52_i138@mstr_sconn.sconn288_h44441003(chips)!SCONN288_H44441003_PIP-SCONN,HA!!!F226!VSS(45)!!!!
S!GND!J6L2!147!@baseboard_fab2_lib.baseboard_fab2(sch_1):page52_i138@mstr_sconn.sconn288_h44441003(chips)!SCONN288_H44441003_PIP-SCONN,HA!!!F226!VSS(46)!!!!
S!GND!J6L2!138!@baseboard_fab2_lib.baseboard_fab2(sch_1):page52_i138@mstr_sconn.sconn288_h44441003(chips)!SCONN288_H44441003_PIP-SCONN,HA!!!F226!VSS(47)!!!!
S!GND!J6L2!136!@baseboard_fab2_lib.baseboard_fab2(sch_1):page52_i138@mstr_sconn.sconn288_h44441003(chips)!SCONN288_H44441003_PIP-SCONN,HA!!!F226!VSS(48)!!!!
S!GND!J6L2!134!@baseboard_fab2_lib.baseboard_fab2(sch_1):page52_i138@mstr_sconn.sconn288_h44441003(chips)!SCONN288_H44441003_PIP-SCONN,HA!!!F226!VSS(49)!!!!
S!GND!J6L2!274!@baseboard_fab2_lib.baseboard_fab2(sch_1):page52_i138@mstr_sconn.sconn288_h44441003(chips)!SCONN288_H44441003_PIP-SCONN,HA!!!F226!VSS(4)!!!!
S!GND!J6L2!131!@baseboard_fab2_lib.baseboard_fab2(sch_1):page52_i138@mstr_sconn.sconn288_h44441003(chips)!SCONN288_H44441003_PIP-SCONN,HA!!!F226!VSS(50)!!!!
S!GND!J6L2!129!@baseboard_fab2_lib.baseboard_fab2(sch_1):page52_i138@mstr_sconn.sconn288_h44441003(chips)!SCONN288_H44441003_PIP-SCONN,HA!!!F226!VSS(51)!!!!
S!GND!J6L2!127!@baseboard_fab2_lib.baseboard_fab2(sch_1):page52_i138@mstr_sconn.sconn288_h44441003(chips)!SCONN288_H44441003_PIP-SCONN,HA!!!F226!VSS(52)!!!!
S!GND!J6L2!125!@baseboard_fab2_lib.baseboard_fab2(sch_1):page52_i138@mstr_sconn.sconn288_h44441003(chips)!SCONN288_H44441003_PIP-SCONN,HA!!!F226!VSS(53)!!!!
S!GND!J6L2!123!@baseboard_fab2_lib.baseboard_fab2(sch_1):page52_i138@mstr_sconn.sconn288_h44441003(chips)!SCONN288_H44441003_PIP-SCONN,HA!!!F226!VSS(54)!!!!
S!GND!J6L2!120!@baseboard_fab2_lib.baseboard_fab2(sch_1):page52_i138@mstr_sconn.sconn288_h44441003(chips)!SCONN288_H44441003_PIP-SCONN,HA!!!F226!VSS(55)!!!!
S!GND!J6L2!118!@baseboard_fab2_lib.baseboard_fab2(sch_1):page52_i138@mstr_sconn.sconn288_h44441003(chips)!SCONN288_H44441003_PIP-SCONN,HA!!!F226!VSS(56)!!!!
S!GND!J6L2!116!@baseboard_fab2_lib.baseboard_fab2(sch_1):page52_i138@mstr_sconn.sconn288_h44441003(chips)!SCONN288_H44441003_PIP-SCONN,HA!!!F226!VSS(57)!!!!
S!GND!J6L2!114!@baseboard_fab2_lib.baseboard_fab2(sch_1):page52_i138@mstr_sconn.sconn288_h44441003(chips)!SCONN288_H44441003_PIP-SCONN,HA!!!F226!VSS(58)!!!!
S!GND!J6L2!112!@baseboard_fab2_lib.baseboard_fab2(sch_1):page52_i138@mstr_sconn.sconn288_h44441003(chips)!SCONN288_H44441003_PIP-SCONN,HA!!!F226!VSS(59)!!!!
S!GND!J6L2!272!@baseboard_fab2_lib.baseboard_fab2(sch_1):page52_i138@mstr_sconn.sconn288_h44441003(chips)!SCONN288_H44441003_PIP-SCONN,HA!!!F226!VSS(5)!!!!
S!GND!J6L2!109!@baseboard_fab2_lib.baseboard_fab2(sch_1):page52_i138@mstr_sconn.sconn288_h44441003(chips)!SCONN288_H44441003_PIP-SCONN,HA!!!F226!VSS(60)!!!!
S!GND!J6L2!107!@baseboard_fab2_lib.baseboard_fab2(sch_1):page52_i138@mstr_sconn.sconn288_h44441003(chips)!SCONN288_H44441003_PIP-SCONN,HA!!!F226!VSS(61)!!!!
S!GND!J6L2!105!@baseboard_fab2_lib.baseboard_fab2(sch_1):page52_i138@mstr_sconn.sconn288_h44441003(chips)!SCONN288_H44441003_PIP-SCONN,HA!!!F226!VSS(62)!!!!
S!GND!J6L2!103!@baseboard_fab2_lib.baseboard_fab2(sch_1):page52_i138@mstr_sconn.sconn288_h44441003(chips)!SCONN288_H44441003_PIP-SCONN,HA!!!F226!VSS(63)!!!!
S!GND!J6L2!101!@baseboard_fab2_lib.baseboard_fab2(sch_1):page52_i138@mstr_sconn.sconn288_h44441003(chips)!SCONN288_H44441003_PIP-SCONN,HA!!!F226!VSS(64)!!!!
S!GND!J6L2!98!@baseboard_fab2_lib.baseboard_fab2(sch_1):page52_i138@mstr_sconn.sconn288_h44441003(chips)!SCONN288_H44441003_PIP-SCONN,HA!!!F226!VSS(65)!!!!
S!GND!J6L2!96!@baseboard_fab2_lib.baseboard_fab2(sch_1):page52_i138@mstr_sconn.sconn288_h44441003(chips)!SCONN288_H44441003_PIP-SCONN,HA!!!F226!VSS(66)!!!!
S!GND!J6L2!94!@baseboard_fab2_lib.baseboard_fab2(sch_1):page52_i138@mstr_sconn.sconn288_h44441003(chips)!SCONN288_H44441003_PIP-SCONN,HA!!!F226!VSS(67)!!!!
S!GND!J6L2!57!@baseboard_fab2_lib.baseboard_fab2(sch_1):page52_i138@mstr_sconn.sconn288_h44441003(chips)!SCONN288_H44441003_PIP-SCONN,HA!!!F226!VSS(68)!!!!
S!GND!J6L2!55!@baseboard_fab2_lib.baseboard_fab2(sch_1):page52_i138@mstr_sconn.sconn288_h44441003(chips)!SCONN288_H44441003_PIP-SCONN,HA!!!F226!VSS(69)!!!!
S!GND!J6L2!270!@baseboard_fab2_lib.baseboard_fab2(sch_1):page52_i138@mstr_sconn.sconn288_h44441003(chips)!SCONN288_H44441003_PIP-SCONN,HA!!!F226!VSS(6)!!!!
S!GND!J6L2!53!@baseboard_fab2_lib.baseboard_fab2(sch_1):page52_i138@mstr_sconn.sconn288_h44441003(chips)!SCONN288_H44441003_PIP-SCONN,HA!!!F226!VSS(70)!!!!
S!GND!J6L2!50!@baseboard_fab2_lib.baseboard_fab2(sch_1):page52_i138@mstr_sconn.sconn288_h44441003(chips)!SCONN288_H44441003_PIP-SCONN,HA!!!F226!VSS(71)!!!!
S!GND!J6L2!48!@baseboard_fab2_lib.baseboard_fab2(sch_1):page52_i138@mstr_sconn.sconn288_h44441003(chips)!SCONN288_H44441003_PIP-SCONN,HA!!!F226!VSS(72)!!!!
S!GND!J6L2!46!@baseboard_fab2_lib.baseboard_fab2(sch_1):page52_i138@mstr_sconn.sconn288_h44441003(chips)!SCONN288_H44441003_PIP-SCONN,HA!!!F226!VSS(73)!!!!
S!GND!J6L2!44!@baseboard_fab2_lib.baseboard_fab2(sch_1):page52_i138@mstr_sconn.sconn288_h44441003(chips)!SCONN288_H44441003_PIP-SCONN,HA!!!F226!VSS(74)!!!!
S!GND!J6L2!42!@baseboard_fab2_lib.baseboard_fab2(sch_1):page52_i138@mstr_sconn.sconn288_h44441003(chips)!SCONN288_H44441003_PIP-SCONN,HA!!!F226!VSS(75)!!!!
S!GND!J6L2!39!@baseboard_fab2_lib.baseboard_fab2(sch_1):page52_i138@mstr_sconn.sconn288_h44441003(chips)!SCONN288_H44441003_PIP-SCONN,HA!!!F226!VSS(76)!!!!
S!GND!J6L2!37!@baseboard_fab2_lib.baseboard_fab2(sch_1):page52_i138@mstr_sconn.sconn288_h44441003(chips)!SCONN288_H44441003_PIP-SCONN,HA!!!F226!VSS(77)!!!!
S!GND!J6L2!35!@baseboard_fab2_lib.baseboard_fab2(sch_1):page52_i138@mstr_sconn.sconn288_h44441003(chips)!SCONN288_H44441003_PIP-SCONN,HA!!!F226!VSS(78)!!!!
S!GND!J6L2!33!@baseboard_fab2_lib.baseboard_fab2(sch_1):page52_i138@mstr_sconn.sconn288_h44441003(chips)!SCONN288_H44441003_PIP-SCONN,HA!!!F226!VSS(79)!!!!
S!GND!J6L2!268!@baseboard_fab2_lib.baseboard_fab2(sch_1):page52_i138@mstr_sconn.sconn288_h44441003(chips)!SCONN288_H44441003_PIP-SCONN,HA!!!F226!VSS(7)!!!!
S!GND!J6L2!31!@baseboard_fab2_lib.baseboard_fab2(sch_1):page52_i138@mstr_sconn.sconn288_h44441003(chips)!SCONN288_H44441003_PIP-SCONN,HA!!!F226!VSS(80)!!!!
S!GND!J6L2!28!@baseboard_fab2_lib.baseboard_fab2(sch_1):page52_i138@mstr_sconn.sconn288_h44441003(chips)!SCONN288_H44441003_PIP-SCONN,HA!!!F226!VSS(81)!!!!
S!GND!J6L2!26!@baseboard_fab2_lib.baseboard_fab2(sch_1):page52_i138@mstr_sconn.sconn288_h44441003(chips)!SCONN288_H44441003_PIP-SCONN,HA!!!F226!VSS(82)!!!!
S!GND!J6L2!24!@baseboard_fab2_lib.baseboard_fab2(sch_1):page52_i138@mstr_sconn.sconn288_h44441003(chips)!SCONN288_H44441003_PIP-SCONN,HA!!!F226!VSS(83)!!!!
S!GND!J6L2!22!@baseboard_fab2_lib.baseboard_fab2(sch_1):page52_i138@mstr_sconn.sconn288_h44441003(chips)!SCONN288_H44441003_PIP-SCONN,HA!!!F226!VSS(84)!!!!
S!GND!J6L2!20!@baseboard_fab2_lib.baseboard_fab2(sch_1):page52_i138@mstr_sconn.sconn288_h44441003(chips)!SCONN288_H44441003_PIP-SCONN,HA!!!F226!VSS(85)!!!!
S!GND!J6L2!17!@baseboard_fab2_lib.baseboard_fab2(sch_1):page52_i138@mstr_sconn.sconn288_h44441003(chips)!SCONN288_H44441003_PIP-SCONN,HA!!!F226!VSS(86)!!!!
S!GND!J6L2!15!@baseboard_fab2_lib.baseboard_fab2(sch_1):page52_i138@mstr_sconn.sconn288_h44441003(chips)!SCONN288_H44441003_PIP-SCONN,HA!!!F226!VSS(87)!!!!
S!GND!J6L2!13!@baseboard_fab2_lib.baseboard_fab2(sch_1):page52_i138@mstr_sconn.sconn288_h44441003(chips)!SCONN288_H44441003_PIP-SCONN,HA!!!F226!VSS(88)!!!!
S!GND!J6L2!11!@baseboard_fab2_lib.baseboard_fab2(sch_1):page52_i138@mstr_sconn.sconn288_h44441003(chips)!SCONN288_H44441003_PIP-SCONN,HA!!!F226!VSS(89)!!!!
S!GND!J6L2!265!@baseboard_fab2_lib.baseboard_fab2(sch_1):page52_i138@mstr_sconn.sconn288_h44441003(chips)!SCONN288_H44441003_PIP-SCONN,HA!!!F226!VSS(8)!!!!
S!GND!J6L2!9!@baseboard_fab2_lib.baseboard_fab2(sch_1):page52_i138@mstr_sconn.sconn288_h44441003(chips)!SCONN288_H44441003_PIP-SCONN,HA!!!F226!VSS(90)!!!!
S!GND!J6L2!6!@baseboard_fab2_lib.baseboard_fab2(sch_1):page52_i138@mstr_sconn.sconn288_h44441003(chips)!SCONN288_H44441003_PIP-SCONN,HA!!!F226!VSS(91)!!!!
S!GND!J6L2!4!@baseboard_fab2_lib.baseboard_fab2(sch_1):page52_i138@mstr_sconn.sconn288_h44441003(chips)!SCONN288_H44441003_PIP-SCONN,HA!!!F226!VSS(92)!!!!
S!GND!J6L2!2!@baseboard_fab2_lib.baseboard_fab2(sch_1):page52_i138@mstr_sconn.sconn288_h44441003(chips)!SCONN288_H44441003_PIP-SCONN,HA!!!F226!VSS(93)!!!!
S!GND!J6L2!263!@baseboard_fab2_lib.baseboard_fab2(sch_1):page52_i138@mstr_sconn.sconn288_h44441003(chips)!SCONN288_H44441003_PIP-SCONN,HA!!!F226!VSS(9)!!!!
S!P12V_NVDIMM_DEF!J6L2!145!@baseboard_fab2_lib.baseboard_fab2(sch_1):page52_i55@mstr_sconn.sconn288_h44441003(chips)!SCONN288_H44441003_PIP-SCONN,HA!!!F225!\12v\(0)!!!!
S!P12V_NVDIMM_DEF!J6L2!1!@baseboard_fab2_lib.baseboard_fab2(sch_1):page52_i55@mstr_sconn.sconn288_h44441003(chips)!SCONN288_H44441003_PIP-SCONN,HA!!!F225!\12v\(1)!!!!
S!PVDDQ_DEF!J6L2!236!@baseboard_fab2_lib.baseboard_fab2(sch_1):page52_i55@mstr_sconn.sconn288_h44441003(chips)!SCONN288_H44441003_PIP-SCONN,HA!!!F225!VDD(0)!!!!
S!PVDDQ_DEF!J6L2!209!@baseboard_fab2_lib.baseboard_fab2(sch_1):page52_i55@mstr_sconn.sconn288_h44441003(chips)!SCONN288_H44441003_PIP-SCONN,HA!!!F225!VDD(10)!!!!
S!PVDDQ_DEF!J6L2!206!@baseboard_fab2_lib.baseboard_fab2(sch_1):page52_i55@mstr_sconn.sconn288_h44441003(chips)!SCONN288_H44441003_PIP-SCONN,HA!!!F225!VDD(11)!!!!
S!PVDDQ_DEF!J6L2!204!@baseboard_fab2_lib.baseboard_fab2(sch_1):page52_i55@mstr_sconn.sconn288_h44441003(chips)!SCONN288_H44441003_PIP-SCONN,HA!!!F225!VDD(12)!!!!
S!PVDDQ_DEF!J6L2!92!@baseboard_fab2_lib.baseboard_fab2(sch_1):page52_i55@mstr_sconn.sconn288_h44441003(chips)!SCONN288_H44441003_PIP-SCONN,HA!!!F225!VDD(13)!!!!
S!PVDDQ_DEF!J6L2!90!@baseboard_fab2_lib.baseboard_fab2(sch_1):page52_i55@mstr_sconn.sconn288_h44441003(chips)!SCONN288_H44441003_PIP-SCONN,HA!!!F225!VDD(14)!!!!
S!PVDDQ_DEF!J6L2!88!@baseboard_fab2_lib.baseboard_fab2(sch_1):page52_i55@mstr_sconn.sconn288_h44441003(chips)!SCONN288_H44441003_PIP-SCONN,HA!!!F225!VDD(15)!!!!
S!PVDDQ_DEF!J6L2!85!@baseboard_fab2_lib.baseboard_fab2(sch_1):page52_i55@mstr_sconn.sconn288_h44441003(chips)!SCONN288_H44441003_PIP-SCONN,HA!!!F225!VDD(16)!!!!
S!PVDDQ_DEF!J6L2!83!@baseboard_fab2_lib.baseboard_fab2(sch_1):page52_i55@mstr_sconn.sconn288_h44441003(chips)!SCONN288_H44441003_PIP-SCONN,HA!!!F225!VDD(17)!!!!
S!PVDDQ_DEF!J6L2!80!@baseboard_fab2_lib.baseboard_fab2(sch_1):page52_i55@mstr_sconn.sconn288_h44441003(chips)!SCONN288_H44441003_PIP-SCONN,HA!!!F225!VDD(18)!!!!
S!PVDDQ_DEF!J6L2!76!@baseboard_fab2_lib.baseboard_fab2(sch_1):page52_i55@mstr_sconn.sconn288_h44441003(chips)!SCONN288_H44441003_PIP-SCONN,HA!!!F225!VDD(19)!!!!
S!PVDDQ_DEF!J6L2!233!@baseboard_fab2_lib.baseboard_fab2(sch_1):page52_i55@mstr_sconn.sconn288_h44441003(chips)!SCONN288_H44441003_PIP-SCONN,HA!!!F225!VDD(1)!!!!
S!PVDDQ_DEF!J6L2!73!@baseboard_fab2_lib.baseboard_fab2(sch_1):page52_i55@mstr_sconn.sconn288_h44441003(chips)!SCONN288_H44441003_PIP-SCONN,HA!!!F225!VDD(20)!!!!
S!PVDDQ_DEF!J6L2!70!@baseboard_fab2_lib.baseboard_fab2(sch_1):page52_i55@mstr_sconn.sconn288_h44441003(chips)!SCONN288_H44441003_PIP-SCONN,HA!!!F225!VDD(21)!!!!
S!PVDDQ_DEF!J6L2!67!@baseboard_fab2_lib.baseboard_fab2(sch_1):page52_i55@mstr_sconn.sconn288_h44441003(chips)!SCONN288_H44441003_PIP-SCONN,HA!!!F225!VDD(22)!!!!
S!PVDDQ_DEF!J6L2!64!@baseboard_fab2_lib.baseboard_fab2(sch_1):page52_i55@mstr_sconn.sconn288_h44441003(chips)!SCONN288_H44441003_PIP-SCONN,HA!!!F225!VDD(23)!!!!
S!PVDDQ_DEF!J6L2!61!@baseboard_fab2_lib.baseboard_fab2(sch_1):page52_i55@mstr_sconn.sconn288_h44441003(chips)!SCONN288_H44441003_PIP-SCONN,HA!!!F225!VDD(24)!!!!
S!PVDDQ_DEF!J6L2!59!@baseboard_fab2_lib.baseboard_fab2(sch_1):page52_i55@mstr_sconn.sconn288_h44441003(chips)!SCONN288_H44441003_PIP-SCONN,HA!!!F225!VDD(25)!!!!
S!PVDDQ_DEF!J6L2!231!@baseboard_fab2_lib.baseboard_fab2(sch_1):page52_i55@mstr_sconn.sconn288_h44441003(chips)!SCONN288_H44441003_PIP-SCONN,HA!!!F225!VDD(2)!!!!
S!PVDDQ_DEF!J6L2!229!@baseboard_fab2_lib.baseboard_fab2(sch_1):page52_i55@mstr_sconn.sconn288_h44441003(chips)!SCONN288_H44441003_PIP-SCONN,HA!!!F225!VDD(3)!!!!
S!PVDDQ_DEF!J6L2!226!@baseboard_fab2_lib.baseboard_fab2(sch_1):page52_i55@mstr_sconn.sconn288_h44441003(chips)!SCONN288_H44441003_PIP-SCONN,HA!!!F225!VDD(4)!!!!
S!PVDDQ_DEF!J6L2!223!@baseboard_fab2_lib.baseboard_fab2(sch_1):page52_i55@mstr_sconn.sconn288_h44441003(chips)!SCONN288_H44441003_PIP-SCONN,HA!!!F225!VDD(5)!!!!
S!PVDDQ_DEF!J6L2!220!@baseboard_fab2_lib.baseboard_fab2(sch_1):page52_i55@mstr_sconn.sconn288_h44441003(chips)!SCONN288_H44441003_PIP-SCONN,HA!!!F225!VDD(6)!!!!
S!PVDDQ_DEF!J6L2!217!@baseboard_fab2_lib.baseboard_fab2(sch_1):page52_i55@mstr_sconn.sconn288_h44441003(chips)!SCONN288_H44441003_PIP-SCONN,HA!!!F225!VDD(7)!!!!
S!PVDDQ_DEF!J6L2!215!@baseboard_fab2_lib.baseboard_fab2(sch_1):page52_i55@mstr_sconn.sconn288_h44441003(chips)!SCONN288_H44441003_PIP-SCONN,HA!!!F225!VDD(8)!!!!
S!PVDDQ_DEF!J6L2!212!@baseboard_fab2_lib.baseboard_fab2(sch_1):page52_i55@mstr_sconn.sconn288_h44441003(chips)!SCONN288_H44441003_PIP-SCONN,HA!!!F225!VDD(9)!!!!
S!PVPP_DEF!J6L2!287!@baseboard_fab2_lib.baseboard_fab2(sch_1):page52_i55@mstr_sconn.sconn288_h44441003(chips)!SCONN288_H44441003_PIP-SCONN,HA!!!F225!VPP(0)!!!!
S!PVPP_DEF!J6L2!286!@baseboard_fab2_lib.baseboard_fab2(sch_1):page52_i55@mstr_sconn.sconn288_h44441003(chips)!SCONN288_H44441003_PIP-SCONN,HA!!!F225!VPP(1)!!!!
S!PVPP_DEF!J6L2!288!@baseboard_fab2_lib.baseboard_fab2(sch_1):page52_i55@mstr_sconn.sconn288_h44441003(chips)!SCONN288_H44441003_PIP-SCONN,HA!!!F225!VPP(2)!!!!
S!PVPP_DEF!J6L2!143!@baseboard_fab2_lib.baseboard_fab2(sch_1):page52_i55@mstr_sconn.sconn288_h44441003(chips)!SCONN288_H44441003_PIP-SCONN,HA!!!F225!VPP(3)!!!!
S!PVPP_DEF!J6L2!142!@baseboard_fab2_lib.baseboard_fab2(sch_1):page52_i55@mstr_sconn.sconn288_h44441003(chips)!SCONN288_H44441003_PIP-SCONN,HA!!!F225!VPP(4)!!!!
S!PVTT_DEF!J6L2!221!@baseboard_fab2_lib.baseboard_fab2(sch_1):page52_i55@mstr_sconn.sconn288_h44441003(chips)!SCONN288_H44441003_PIP-SCONN,HA!!!F225!VTT(0)!!!!
S!PVTT_DEF!J6L2!77!@baseboard_fab2_lib.baseboard_fab2(sch_1):page52_i55@mstr_sconn.sconn288_h44441003(chips)!SCONN288_H44441003_PIP-SCONN,HA!!!F225!VTT(1)!!!!
S!M_F_MA<0>!J6L1!79!@baseboard_fab2_lib.baseboard_fab2(sch_1):page54_i111@mstr_sconn.sconn288_h44441003(chips)!SCONN288_H44441003_PIP-SCONN,HA!!!F232!A0!!!!
S!M_F_MA<1>!J6L1!72!@baseboard_fab2_lib.baseboard_fab2(sch_1):page54_i111@mstr_sconn.sconn288_h44441003(chips)!SCONN288_H44441003_PIP-SCONN,HA!!!F232!A1!!!!
S!M_F_MA<10>!J6L1!225!@baseboard_fab2_lib.baseboard_fab2(sch_1):page54_i111@mstr_sconn.sconn288_h44441003(chips)!SCONN288_H44441003_PIP-SCONN,HA!!!F232!A10!!!!
S!M_F_MA<11>!J6L1!210!@baseboard_fab2_lib.baseboard_fab2(sch_1):page54_i111@mstr_sconn.sconn288_h44441003(chips)!SCONN288_H44441003_PIP-SCONN,HA!!!F232!A11!!!!
S!M_F_MA<12>!J6L1!65!@baseboard_fab2_lib.baseboard_fab2(sch_1):page54_i111@mstr_sconn.sconn288_h44441003(chips)!SCONN288_H44441003_PIP-SCONN,HA!!!F232!A12!!!!
S!M_F_MA<13>!J6L1!232!@baseboard_fab2_lib.baseboard_fab2(sch_1):page54_i111@mstr_sconn.sconn288_h44441003(chips)!SCONN288_H44441003_PIP-SCONN,HA!!!F232!A13!!!!
S!M_F_MA<14>!J6L1!228!@baseboard_fab2_lib.baseboard_fab2(sch_1):page54_i111@mstr_sconn.sconn288_h44441003(chips)!SCONN288_H44441003_PIP-SCONN,HA!!!F232!A14_WE_N!!!!
S!M_F_MA<15>!J6L1!86!@baseboard_fab2_lib.baseboard_fab2(sch_1):page54_i111@mstr_sconn.sconn288_h44441003(chips)!SCONN288_H44441003_PIP-SCONN,HA!!!F232!A15_CAS_N!!!!
S!M_F_MA<16>!J6L1!82!@baseboard_fab2_lib.baseboard_fab2(sch_1):page54_i111@mstr_sconn.sconn288_h44441003(chips)!SCONN288_H44441003_PIP-SCONN,HA!!!F232!A16_RAS_N!!!!
S!M_F_MA<17>!J6L1!234!@baseboard_fab2_lib.baseboard_fab2(sch_1):page54_i111@mstr_sconn.sconn288_h44441003(chips)!SCONN288_H44441003_PIP-SCONN,HA!!!F232!A17!!!!
S!M_F_MA<2>!J6L1!216!@baseboard_fab2_lib.baseboard_fab2(sch_1):page54_i111@mstr_sconn.sconn288_h44441003(chips)!SCONN288_H44441003_PIP-SCONN,HA!!!F232!A2!!!!
S!M_F_MA<3>!J6L1!71!@baseboard_fab2_lib.baseboard_fab2(sch_1):page54_i111@mstr_sconn.sconn288_h44441003(chips)!SCONN288_H44441003_PIP-SCONN,HA!!!F232!A3!!!!
S!M_F_MA<4>!J6L1!214!@baseboard_fab2_lib.baseboard_fab2(sch_1):page54_i111@mstr_sconn.sconn288_h44441003(chips)!SCONN288_H44441003_PIP-SCONN,HA!!!F232!A4!!!!
S!M_F_MA<5>!J6L1!213!@baseboard_fab2_lib.baseboard_fab2(sch_1):page54_i111@mstr_sconn.sconn288_h44441003(chips)!SCONN288_H44441003_PIP-SCONN,HA!!!F232!A5!!!!
S!M_F_MA<6>!J6L1!69!@baseboard_fab2_lib.baseboard_fab2(sch_1):page54_i111@mstr_sconn.sconn288_h44441003(chips)!SCONN288_H44441003_PIP-SCONN,HA!!!F232!A6!!!!
S!M_F_MA<7>!J6L1!211!@baseboard_fab2_lib.baseboard_fab2(sch_1):page54_i111@mstr_sconn.sconn288_h44441003(chips)!SCONN288_H44441003_PIP-SCONN,HA!!!F232!A7!!!!
S!M_F_MA<8>!J6L1!68!@baseboard_fab2_lib.baseboard_fab2(sch_1):page54_i111@mstr_sconn.sconn288_h44441003(chips)!SCONN288_H44441003_PIP-SCONN,HA!!!F232!A8!!!!
S!M_F_MA<9>!J6L1!66!@baseboard_fab2_lib.baseboard_fab2(sch_1):page54_i111@mstr_sconn.sconn288_h44441003(chips)!SCONN288_H44441003_PIP-SCONN,HA!!!F232!A9!!!!
S!M_F_ACT_N!J6L1!62!@baseboard_fab2_lib.baseboard_fab2(sch_1):page54_i111@mstr_sconn.sconn288_h44441003(chips)!SCONN288_H44441003_PIP-SCONN,HA!!!F232!ACT_N!!!!
S!M_F_ALERT_N!J6L1!208!@baseboard_fab2_lib.baseboard_fab2(sch_1):page54_i111@mstr_sconn.sconn288_h44441003(chips)!SCONN288_H44441003_PIP-SCONN,HA!!!F232!ALERT_N!!!!
S!M_F_BA<0>!J6L1!81!@baseboard_fab2_lib.baseboard_fab2(sch_1):page54_i111@mstr_sconn.sconn288_h44441003(chips)!SCONN288_H44441003_PIP-SCONN,HA!!!F232!BA(0)!!!!
S!M_F_BA<1>!J6L1!224!@baseboard_fab2_lib.baseboard_fab2(sch_1):page54_i111@mstr_sconn.sconn288_h44441003(chips)!SCONN288_H44441003_PIP-SCONN,HA!!!F232!BA(1)!!!!
S!M_F_BG<0>!J6L1!63!@baseboard_fab2_lib.baseboard_fab2(sch_1):page54_i111@mstr_sconn.sconn288_h44441003(chips)!SCONN288_H44441003_PIP-SCONN,HA!!!F232!BG(0)!!!!
S!M_F_BG<1>!J6L1!207!@baseboard_fab2_lib.baseboard_fab2(sch_1):page54_i111@mstr_sconn.sconn288_h44441003(chips)!SCONN288_H44441003_PIP-SCONN,HA!!!F232!BG(1)!!!!
S!M_F_C<2>!J6L1!235!@baseboard_fab2_lib.baseboard_fab2(sch_1):page54_i111@mstr_sconn.sconn288_h44441003(chips)!SCONN288_H44441003_PIP-SCONN,HA!!!F232!C(2)!!!!
S!M_F_ECC<0>!J6L1!49!@baseboard_fab2_lib.baseboard_fab2(sch_1):page54_i111@mstr_sconn.sconn288_h44441003(chips)!SCONN288_H44441003_PIP-SCONN,HA!!!F232!CB(0)!!!!
S!M_F_ECC<1>!J6L1!194!@baseboard_fab2_lib.baseboard_fab2(sch_1):page54_i111@mstr_sconn.sconn288_h44441003(chips)!SCONN288_H44441003_PIP-SCONN,HA!!!F232!CB(1)!!!!
S!M_F_ECC<2>!J6L1!56!@baseboard_fab2_lib.baseboard_fab2(sch_1):page54_i111@mstr_sconn.sconn288_h44441003(chips)!SCONN288_H44441003_PIP-SCONN,HA!!!F232!CB(2)!!!!
S!M_F_ECC<3>!J6L1!201!@baseboard_fab2_lib.baseboard_fab2(sch_1):page54_i111@mstr_sconn.sconn288_h44441003(chips)!SCONN288_H44441003_PIP-SCONN,HA!!!F232!CB(3)!!!!
S!M_F_ECC<4>!J6L1!47!@baseboard_fab2_lib.baseboard_fab2(sch_1):page54_i111@mstr_sconn.sconn288_h44441003(chips)!SCONN288_H44441003_PIP-SCONN,HA!!!F232!CB(4)!!!!
S!M_F_ECC<5>!J6L1!192!@baseboard_fab2_lib.baseboard_fab2(sch_1):page54_i111@mstr_sconn.sconn288_h44441003(chips)!SCONN288_H44441003_PIP-SCONN,HA!!!F232!CB(5)!!!!
S!M_F_ECC<6>!J6L1!54!@baseboard_fab2_lib.baseboard_fab2(sch_1):page54_i111@mstr_sconn.sconn288_h44441003(chips)!SCONN288_H44441003_PIP-SCONN,HA!!!F232!CB(6)!!!!
S!M_F_ECC<7>!J6L1!199!@baseboard_fab2_lib.baseboard_fab2(sch_1):page54_i111@mstr_sconn.sconn288_h44441003(chips)!SCONN288_H44441003_PIP-SCONN,HA!!!F232!CB(7)!!!!
S!M_F_CLK_DN<2>!J6L1!75!@baseboard_fab2_lib.baseboard_fab2(sch_1):page54_i111@mstr_sconn.sconn288_h44441003(chips)!SCONN288_H44441003_PIP-SCONN,HA!!!F232!CK0N!!!!
S!M_F_CLK_DP<2>!J6L1!74!@baseboard_fab2_lib.baseboard_fab2(sch_1):page54_i111@mstr_sconn.sconn288_h44441003(chips)!SCONN288_H44441003_PIP-SCONN,HA!!!F232!CK0P!!!!
S!M_F_CLK_DN<3>!J6L1!219!@baseboard_fab2_lib.baseboard_fab2(sch_1):page54_i111@mstr_sconn.sconn288_h44441003(chips)!SCONN288_H44441003_PIP-SCONN,HA!!!F232!CK1N!!!!
S!M_F_CLK_DP<3>!J6L1!218!@baseboard_fab2_lib.baseboard_fab2(sch_1):page54_i111@mstr_sconn.sconn288_h44441003(chips)!SCONN288_H44441003_PIP-SCONN,HA!!!F232!CK1P!!!!
S!M_F_CKE<2>!J6L1!60!@baseboard_fab2_lib.baseboard_fab2(sch_1):page54_i111@mstr_sconn.sconn288_h44441003(chips)!SCONN288_H44441003_PIP-SCONN,HA!!!F232!CKE(0)!!!!
S!M_F_CKE<3>!J6L1!203!@baseboard_fab2_lib.baseboard_fab2(sch_1):page54_i111@mstr_sconn.sconn288_h44441003(chips)!SCONN288_H44441003_PIP-SCONN,HA!!!F232!CKE(1)!!!!
S!M_F_DQ<0>!J6L1!5!@baseboard_fab2_lib.baseboard_fab2(sch_1):page54_i111@mstr_sconn.sconn288_h44441003(chips)!SCONN288_H44441003_PIP-SCONN,HA!!!F232!DQ(0)!!!!
S!M_F_DQ<10>!J6L1!23!@baseboard_fab2_lib.baseboard_fab2(sch_1):page54_i111@mstr_sconn.sconn288_h44441003(chips)!SCONN288_H44441003_PIP-SCONN,HA!!!F232!DQ(10)!!!!
S!M_F_DQ<11>!J6L1!168!@baseboard_fab2_lib.baseboard_fab2(sch_1):page54_i111@mstr_sconn.sconn288_h44441003(chips)!SCONN288_H44441003_PIP-SCONN,HA!!!F232!DQ(11)!!!!
S!M_F_DQ<12>!J6L1!14!@baseboard_fab2_lib.baseboard_fab2(sch_1):page54_i111@mstr_sconn.sconn288_h44441003(chips)!SCONN288_H44441003_PIP-SCONN,HA!!!F232!DQ(12)!!!!
S!M_F_DQ<13>!J6L1!159!@baseboard_fab2_lib.baseboard_fab2(sch_1):page54_i111@mstr_sconn.sconn288_h44441003(chips)!SCONN288_H44441003_PIP-SCONN,HA!!!F232!DQ(13)!!!!
S!M_F_DQ<14>!J6L1!21!@baseboard_fab2_lib.baseboard_fab2(sch_1):page54_i111@mstr_sconn.sconn288_h44441003(chips)!SCONN288_H44441003_PIP-SCONN,HA!!!F232!DQ(14)!!!!
S!M_F_DQ<15>!J6L1!166!@baseboard_fab2_lib.baseboard_fab2(sch_1):page54_i111@mstr_sconn.sconn288_h44441003(chips)!SCONN288_H44441003_PIP-SCONN,HA!!!F232!DQ(15)!!!!
S!M_F_DQ<16>!J6L1!27!@baseboard_fab2_lib.baseboard_fab2(sch_1):page54_i111@mstr_sconn.sconn288_h44441003(chips)!SCONN288_H44441003_PIP-SCONN,HA!!!F232!DQ(16)!!!!
S!M_F_DQ<17>!J6L1!172!@baseboard_fab2_lib.baseboard_fab2(sch_1):page54_i111@mstr_sconn.sconn288_h44441003(chips)!SCONN288_H44441003_PIP-SCONN,HA!!!F232!DQ(17)!!!!
S!M_F_DQ<18>!J6L1!34!@baseboard_fab2_lib.baseboard_fab2(sch_1):page54_i111@mstr_sconn.sconn288_h44441003(chips)!SCONN288_H44441003_PIP-SCONN,HA!!!F232!DQ(18)!!!!
S!M_F_DQ<19>!J6L1!179!@baseboard_fab2_lib.baseboard_fab2(sch_1):page54_i111@mstr_sconn.sconn288_h44441003(chips)!SCONN288_H44441003_PIP-SCONN,HA!!!F232!DQ(19)!!!!
S!M_F_DQ<1>!J6L1!150!@baseboard_fab2_lib.baseboard_fab2(sch_1):page54_i111@mstr_sconn.sconn288_h44441003(chips)!SCONN288_H44441003_PIP-SCONN,HA!!!F232!DQ(1)!!!!
S!M_F_DQ<20>!J6L1!25!@baseboard_fab2_lib.baseboard_fab2(sch_1):page54_i111@mstr_sconn.sconn288_h44441003(chips)!SCONN288_H44441003_PIP-SCONN,HA!!!F232!DQ(20)!!!!
S!M_F_DQ<21>!J6L1!170!@baseboard_fab2_lib.baseboard_fab2(sch_1):page54_i111@mstr_sconn.sconn288_h44441003(chips)!SCONN288_H44441003_PIP-SCONN,HA!!!F232!DQ(21)!!!!
S!M_F_DQ<22>!J6L1!32!@baseboard_fab2_lib.baseboard_fab2(sch_1):page54_i111@mstr_sconn.sconn288_h44441003(chips)!SCONN288_H44441003_PIP-SCONN,HA!!!F232!DQ(22)!!!!
S!M_F_DQ<23>!J6L1!177!@baseboard_fab2_lib.baseboard_fab2(sch_1):page54_i111@mstr_sconn.sconn288_h44441003(chips)!SCONN288_H44441003_PIP-SCONN,HA!!!F232!DQ(23)!!!!
S!M_F_DQ<24>!J6L1!38!@baseboard_fab2_lib.baseboard_fab2(sch_1):page54_i111@mstr_sconn.sconn288_h44441003(chips)!SCONN288_H44441003_PIP-SCONN,HA!!!F232!DQ(24)!!!!
S!M_F_DQ<25>!J6L1!183!@baseboard_fab2_lib.baseboard_fab2(sch_1):page54_i111@mstr_sconn.sconn288_h44441003(chips)!SCONN288_H44441003_PIP-SCONN,HA!!!F232!DQ(25)!!!!
S!M_F_DQ<26>!J6L1!45!@baseboard_fab2_lib.baseboard_fab2(sch_1):page54_i111@mstr_sconn.sconn288_h44441003(chips)!SCONN288_H44441003_PIP-SCONN,HA!!!F232!DQ(26)!!!!
S!M_F_DQ<27>!J6L1!190!@baseboard_fab2_lib.baseboard_fab2(sch_1):page54_i111@mstr_sconn.sconn288_h44441003(chips)!SCONN288_H44441003_PIP-SCONN,HA!!!F232!DQ(27)!!!!
S!M_F_DQ<28>!J6L1!36!@baseboard_fab2_lib.baseboard_fab2(sch_1):page54_i111@mstr_sconn.sconn288_h44441003(chips)!SCONN288_H44441003_PIP-SCONN,HA!!!F232!DQ(28)!!!!
S!M_F_DQ<29>!J6L1!181!@baseboard_fab2_lib.baseboard_fab2(sch_1):page54_i111@mstr_sconn.sconn288_h44441003(chips)!SCONN288_H44441003_PIP-SCONN,HA!!!F232!DQ(29)!!!!
S!M_F_DQ<2>!J6L1!12!@baseboard_fab2_lib.baseboard_fab2(sch_1):page54_i111@mstr_sconn.sconn288_h44441003(chips)!SCONN288_H44441003_PIP-SCONN,HA!!!F232!DQ(2)!!!!
S!M_F_DQ<30>!J6L1!43!@baseboard_fab2_lib.baseboard_fab2(sch_1):page54_i111@mstr_sconn.sconn288_h44441003(chips)!SCONN288_H44441003_PIP-SCONN,HA!!!F232!DQ(30)!!!!
S!M_F_DQ<31>!J6L1!188!@baseboard_fab2_lib.baseboard_fab2(sch_1):page54_i111@mstr_sconn.sconn288_h44441003(chips)!SCONN288_H44441003_PIP-SCONN,HA!!!F232!DQ(31)!!!!
S!M_F_DQ<32>!J6L1!97!@baseboard_fab2_lib.baseboard_fab2(sch_1):page54_i111@mstr_sconn.sconn288_h44441003(chips)!SCONN288_H44441003_PIP-SCONN,HA!!!F232!DQ(32)!!!!
S!M_F_DQ<33>!J6L1!242!@baseboard_fab2_lib.baseboard_fab2(sch_1):page54_i111@mstr_sconn.sconn288_h44441003(chips)!SCONN288_H44441003_PIP-SCONN,HA!!!F232!DQ(33)!!!!
S!M_F_DQ<34>!J6L1!104!@baseboard_fab2_lib.baseboard_fab2(sch_1):page54_i111@mstr_sconn.sconn288_h44441003(chips)!SCONN288_H44441003_PIP-SCONN,HA!!!F232!DQ(34)!!!!
S!M_F_DQ<35>!J6L1!249!@baseboard_fab2_lib.baseboard_fab2(sch_1):page54_i111@mstr_sconn.sconn288_h44441003(chips)!SCONN288_H44441003_PIP-SCONN,HA!!!F232!DQ(35)!!!!
S!M_F_DQ<36>!J6L1!95!@baseboard_fab2_lib.baseboard_fab2(sch_1):page54_i111@mstr_sconn.sconn288_h44441003(chips)!SCONN288_H44441003_PIP-SCONN,HA!!!F232!DQ(36)!!!!
S!M_F_DQ<37>!J6L1!240!@baseboard_fab2_lib.baseboard_fab2(sch_1):page54_i111@mstr_sconn.sconn288_h44441003(chips)!SCONN288_H44441003_PIP-SCONN,HA!!!F232!DQ(37)!!!!
S!M_F_DQ<38>!J6L1!102!@baseboard_fab2_lib.baseboard_fab2(sch_1):page54_i111@mstr_sconn.sconn288_h44441003(chips)!SCONN288_H44441003_PIP-SCONN,HA!!!F232!DQ(38)!!!!
S!M_F_DQ<39>!J6L1!247!@baseboard_fab2_lib.baseboard_fab2(sch_1):page54_i111@mstr_sconn.sconn288_h44441003(chips)!SCONN288_H44441003_PIP-SCONN,HA!!!F232!DQ(39)!!!!
S!M_F_DQ<3>!J6L1!157!@baseboard_fab2_lib.baseboard_fab2(sch_1):page54_i111@mstr_sconn.sconn288_h44441003(chips)!SCONN288_H44441003_PIP-SCONN,HA!!!F232!DQ(3)!!!!
S!M_F_DQ<40>!J6L1!108!@baseboard_fab2_lib.baseboard_fab2(sch_1):page54_i111@mstr_sconn.sconn288_h44441003(chips)!SCONN288_H44441003_PIP-SCONN,HA!!!F232!DQ(40)!!!!
S!M_F_DQ<41>!J6L1!253!@baseboard_fab2_lib.baseboard_fab2(sch_1):page54_i111@mstr_sconn.sconn288_h44441003(chips)!SCONN288_H44441003_PIP-SCONN,HA!!!F232!DQ(41)!!!!
S!M_F_DQ<42>!J6L1!115!@baseboard_fab2_lib.baseboard_fab2(sch_1):page54_i111@mstr_sconn.sconn288_h44441003(chips)!SCONN288_H44441003_PIP-SCONN,HA!!!F232!DQ(42)!!!!
S!M_F_DQ<43>!J6L1!260!@baseboard_fab2_lib.baseboard_fab2(sch_1):page54_i111@mstr_sconn.sconn288_h44441003(chips)!SCONN288_H44441003_PIP-SCONN,HA!!!F232!DQ(43)!!!!
S!M_F_DQ<44>!J6L1!106!@baseboard_fab2_lib.baseboard_fab2(sch_1):page54_i111@mstr_sconn.sconn288_h44441003(chips)!SCONN288_H44441003_PIP-SCONN,HA!!!F232!DQ(44)!!!!
S!M_F_DQ<45>!J6L1!251!@baseboard_fab2_lib.baseboard_fab2(sch_1):page54_i111@mstr_sconn.sconn288_h44441003(chips)!SCONN288_H44441003_PIP-SCONN,HA!!!F232!DQ(45)!!!!
S!M_F_DQ<46>!J6L1!113!@baseboard_fab2_lib.baseboard_fab2(sch_1):page54_i111@mstr_sconn.sconn288_h44441003(chips)!SCONN288_H44441003_PIP-SCONN,HA!!!F232!DQ(46)!!!!
S!M_F_DQ<47>!J6L1!258!@baseboard_fab2_lib.baseboard_fab2(sch_1):page54_i111@mstr_sconn.sconn288_h44441003(chips)!SCONN288_H44441003_PIP-SCONN,HA!!!F232!DQ(47)!!!!
S!M_F_DQ<48>!J6L1!119!@baseboard_fab2_lib.baseboard_fab2(sch_1):page54_i111@mstr_sconn.sconn288_h44441003(chips)!SCONN288_H44441003_PIP-SCONN,HA!!!F232!DQ(48)!!!!
S!M_F_DQ<49>!J6L1!264!@baseboard_fab2_lib.baseboard_fab2(sch_1):page54_i111@mstr_sconn.sconn288_h44441003(chips)!SCONN288_H44441003_PIP-SCONN,HA!!!F232!DQ(49)!!!!
S!M_F_DQ<4>!J6L1!3!@baseboard_fab2_lib.baseboard_fab2(sch_1):page54_i111@mstr_sconn.sconn288_h44441003(chips)!SCONN288_H44441003_PIP-SCONN,HA!!!F232!DQ(4)!!!!
S!M_F_DQ<50>!J6L1!126!@baseboard_fab2_lib.baseboard_fab2(sch_1):page54_i111@mstr_sconn.sconn288_h44441003(chips)!SCONN288_H44441003_PIP-SCONN,HA!!!F232!DQ(50)!!!!
S!M_F_DQ<51>!J6L1!271!@baseboard_fab2_lib.baseboard_fab2(sch_1):page54_i111@mstr_sconn.sconn288_h44441003(chips)!SCONN288_H44441003_PIP-SCONN,HA!!!F232!DQ(51)!!!!
S!M_F_DQ<52>!J6L1!117!@baseboard_fab2_lib.baseboard_fab2(sch_1):page54_i111@mstr_sconn.sconn288_h44441003(chips)!SCONN288_H44441003_PIP-SCONN,HA!!!F232!DQ(52)!!!!
S!M_F_DQ<53>!J6L1!262!@baseboard_fab2_lib.baseboard_fab2(sch_1):page54_i111@mstr_sconn.sconn288_h44441003(chips)!SCONN288_H44441003_PIP-SCONN,HA!!!F232!DQ(53)!!!!
S!M_F_DQ<54>!J6L1!124!@baseboard_fab2_lib.baseboard_fab2(sch_1):page54_i111@mstr_sconn.sconn288_h44441003(chips)!SCONN288_H44441003_PIP-SCONN,HA!!!F232!DQ(54)!!!!
S!M_F_DQ<55>!J6L1!269!@baseboard_fab2_lib.baseboard_fab2(sch_1):page54_i111@mstr_sconn.sconn288_h44441003(chips)!SCONN288_H44441003_PIP-SCONN,HA!!!F232!DQ(55)!!!!
S!M_F_DQ<56>!J6L1!130!@baseboard_fab2_lib.baseboard_fab2(sch_1):page54_i111@mstr_sconn.sconn288_h44441003(chips)!SCONN288_H44441003_PIP-SCONN,HA!!!F232!DQ(56)!!!!
S!M_F_DQ<57>!J6L1!275!@baseboard_fab2_lib.baseboard_fab2(sch_1):page54_i111@mstr_sconn.sconn288_h44441003(chips)!SCONN288_H44441003_PIP-SCONN,HA!!!F232!DQ(57)!!!!
S!M_F_DQ<58>!J6L1!137!@baseboard_fab2_lib.baseboard_fab2(sch_1):page54_i111@mstr_sconn.sconn288_h44441003(chips)!SCONN288_H44441003_PIP-SCONN,HA!!!F232!DQ(58)!!!!
S!M_F_DQ<59>!J6L1!282!@baseboard_fab2_lib.baseboard_fab2(sch_1):page54_i111@mstr_sconn.sconn288_h44441003(chips)!SCONN288_H44441003_PIP-SCONN,HA!!!F232!DQ(59)!!!!
S!M_F_DQ<5>!J6L1!148!@baseboard_fab2_lib.baseboard_fab2(sch_1):page54_i111@mstr_sconn.sconn288_h44441003(chips)!SCONN288_H44441003_PIP-SCONN,HA!!!F232!DQ(5)!!!!
S!M_F_DQ<60>!J6L1!128!@baseboard_fab2_lib.baseboard_fab2(sch_1):page54_i111@mstr_sconn.sconn288_h44441003(chips)!SCONN288_H44441003_PIP-SCONN,HA!!!F232!DQ(60)!!!!
S!M_F_DQ<61>!J6L1!273!@baseboard_fab2_lib.baseboard_fab2(sch_1):page54_i111@mstr_sconn.sconn288_h44441003(chips)!SCONN288_H44441003_PIP-SCONN,HA!!!F232!DQ(61)!!!!
S!M_F_DQ<62>!J6L1!135!@baseboard_fab2_lib.baseboard_fab2(sch_1):page54_i111@mstr_sconn.sconn288_h44441003(chips)!SCONN288_H44441003_PIP-SCONN,HA!!!F232!DQ(62)!!!!
S!M_F_DQ<63>!J6L1!280!@baseboard_fab2_lib.baseboard_fab2(sch_1):page54_i111@mstr_sconn.sconn288_h44441003(chips)!SCONN288_H44441003_PIP-SCONN,HA!!!F232!DQ(63)!!!!
S!M_F_DQ<6>!J6L1!10!@baseboard_fab2_lib.baseboard_fab2(sch_1):page54_i111@mstr_sconn.sconn288_h44441003(chips)!SCONN288_H44441003_PIP-SCONN,HA!!!F232!DQ(6)!!!!
S!M_F_DQ<7>!J6L1!155!@baseboard_fab2_lib.baseboard_fab2(sch_1):page54_i111@mstr_sconn.sconn288_h44441003(chips)!SCONN288_H44441003_PIP-SCONN,HA!!!F232!DQ(7)!!!!
S!M_F_DQ<8>!J6L1!16!@baseboard_fab2_lib.baseboard_fab2(sch_1):page54_i111@mstr_sconn.sconn288_h44441003(chips)!SCONN288_H44441003_PIP-SCONN,HA!!!F232!DQ(8)!!!!
S!M_F_DQ<9>!J6L1!161!@baseboard_fab2_lib.baseboard_fab2(sch_1):page54_i111@mstr_sconn.sconn288_h44441003(chips)!SCONN288_H44441003_PIP-SCONN,HA!!!F232!DQ(9)!!!!
S!FM_DIMM_EVENT_COD_N!J6L1!78!@baseboard_fab2_lib.baseboard_fab2(sch_1):page54_i111@mstr_sconn.sconn288_h44441003(chips)!SCONN288_H44441003_PIP-SCONN,HA!!!F232!EVENT_N!!!!
S!M_F_ODT<2>!J6L1!87!@baseboard_fab2_lib.baseboard_fab2(sch_1):page54_i111@mstr_sconn.sconn288_h44441003(chips)!SCONN288_H44441003_PIP-SCONN,HA!!!F232!ODT(0)!!!!
S!M_F_ODT<3>!J6L1!91!@baseboard_fab2_lib.baseboard_fab2(sch_1):page54_i111@mstr_sconn.sconn288_h44441003(chips)!SCONN288_H44441003_PIP-SCONN,HA!!!F232!ODT(1)!!!!
S!M_F_PAR!J6L1!222!@baseboard_fab2_lib.baseboard_fab2(sch_1):page54_i111@mstr_sconn.sconn288_h44441003(chips)!SCONN288_H44441003_PIP-SCONN,HA!!!F232!PAR!!!!
S!M_DEF_RST_N!J6L1!58!@baseboard_fab2_lib.baseboard_fab2(sch_1):page54_i111@mstr_sconn.sconn288_h44441003(chips)!SCONN288_H44441003_PIP-SCONN,HA!!!F232!RESET_N!!!!
S!TP_CH_F_DIMM_F1_RFU_0!J6L1!205!@baseboard_fab2_lib.baseboard_fab2(sch_1):page54_i111@mstr_sconn.sconn288_h44441003(chips)!SCONN288_H44441003_PIP-SCONN,HA!!!F232!RFU(0)!!!!
S!TP_CH_F_DIMM_F1_RFU_1!J6L1!227!@baseboard_fab2_lib.baseboard_fab2(sch_1):page54_i111@mstr_sconn.sconn288_h44441003(chips)!SCONN288_H44441003_PIP-SCONN,HA!!!F232!RFU(1)!!!!
S!TP_CH_F_DIMM_F1_RFU_2!J6L1!144!@baseboard_fab2_lib.baseboard_fab2(sch_1):page54_i111@mstr_sconn.sconn288_h44441003(chips)!SCONN288_H44441003_PIP-SCONN,HA!!!F232!RFU(2)!!!!
S!M_F_CS_N<4>!J6L1!84!@baseboard_fab2_lib.baseboard_fab2(sch_1):page54_i111@mstr_sconn.sconn288_h44441003(chips)!SCONN288_H44441003_PIP-SCONN,HA!!!F232!S0_N!!!!
S!M_F_CS_N<5>!J6L1!89!@baseboard_fab2_lib.baseboard_fab2(sch_1):page54_i111@mstr_sconn.sconn288_h44441003(chips)!SCONN288_H44441003_PIP-SCONN,HA!!!F232!S1_N!!!!
S!M_F_CS_N<6>!J6L1!93!@baseboard_fab2_lib.baseboard_fab2(sch_1):page54_i111@mstr_sconn.sconn288_h44441003(chips)!SCONN288_H44441003_PIP-SCONN,HA!!!F232!S2_N_C(0)!!!!
S!M_F_CS_N<7>!J6L1!237!@baseboard_fab2_lib.baseboard_fab2(sch_1):page54_i111@mstr_sconn.sconn288_h44441003(chips)!SCONN288_H44441003_PIP-SCONN,HA!!!F232!S3_N_C(1)!!!!
S!PVPP_DEF!J6L1!139!@baseboard_fab2_lib.baseboard_fab2(sch_1):page54_i111@mstr_sconn.sconn288_h44441003(chips)!SCONN288_H44441003_PIP-SCONN,HA!!!F232!SA(0)!!!!
S!GND!J6L1!140!@baseboard_fab2_lib.baseboard_fab2(sch_1):page54_i111@mstr_sconn.sconn288_h44441003(chips)!SCONN288_H44441003_PIP-SCONN,HA!!!F232!SA(1)!!!!
S!PVPP_DEF!J6L1!238!@baseboard_fab2_lib.baseboard_fab2(sch_1):page54_i111@mstr_sconn.sconn288_h44441003(chips)!SCONN288_H44441003_PIP-SCONN,HA!!!F232!SA(2)!!!!
S!FM_ADR_COMPLETE_DEF_N!J6L1!230!@baseboard_fab2_lib.baseboard_fab2(sch_1):page54_i111@mstr_sconn.sconn288_h44441003(chips)!SCONN288_H44441003_PIP-SCONN,HA!!!F232!SAVE_N_NC!!!!
S!SMB_DDR_DEF_VPP_SCL!J6L1!141!@baseboard_fab2_lib.baseboard_fab2(sch_1):page54_i111@mstr_sconn.sconn288_h44441003(chips)!SCONN288_H44441003_PIP-SCONN,HA!!!F232!SCL!!!!
S!SMB_DDR_DEF_VPP_SDA!J6L1!285!@baseboard_fab2_lib.baseboard_fab2(sch_1):page54_i111@mstr_sconn.sconn288_h44441003(chips)!SCONN288_H44441003_PIP-SCONN,HA!!!F232!SDA!!!!
S!PVPP_DEF!J6L1!284!@baseboard_fab2_lib.baseboard_fab2(sch_1):page54_i111@mstr_sconn.sconn288_h44441003(chips)!SCONN288_H44441003_PIP-SCONN,HA!!!F232!VDDSPD!!!!
S!M_F_VREF!J6L1!146!@baseboard_fab2_lib.baseboard_fab2(sch_1):page54_i111@mstr_sconn.sconn288_h44441003(chips)!SCONN288_H44441003_PIP-SCONN,HA!!!F232!VREFCA!!!!
S!M_F_DQS_DN<0>!J6L1!152!@baseboard_fab2_lib.baseboard_fab2(sch_1):page54_i66@mstr_sconn.sconn288_h44441003(chips)!SCONN288_H44441003_PIP-SCONN,HA!!!F231!DQS0N!!!!
S!M_F_DQS_DP<0>!J6L1!153!@baseboard_fab2_lib.baseboard_fab2(sch_1):page54_i66@mstr_sconn.sconn288_h44441003(chips)!SCONN288_H44441003_PIP-SCONN,HA!!!F231!DQS0P!!!!
S!M_F_DQS_DN<10>!J6L1!19!@baseboard_fab2_lib.baseboard_fab2(sch_1):page54_i66@mstr_sconn.sconn288_h44441003(chips)!SCONN288_H44441003_PIP-SCONN,HA!!!F231!DQS10N!!!!
S!M_F_DQS_DP<10>!J6L1!18!@baseboard_fab2_lib.baseboard_fab2(sch_1):page54_i66@mstr_sconn.sconn288_h44441003(chips)!SCONN288_H44441003_PIP-SCONN,HA!!!F231!DQS10P!!!!
S!M_F_DQS_DN<11>!J6L1!30!@baseboard_fab2_lib.baseboard_fab2(sch_1):page54_i66@mstr_sconn.sconn288_h44441003(chips)!SCONN288_H44441003_PIP-SCONN,HA!!!F231!DQS11N!!!!
S!M_F_DQS_DP<11>!J6L1!29!@baseboard_fab2_lib.baseboard_fab2(sch_1):page54_i66@mstr_sconn.sconn288_h44441003(chips)!SCONN288_H44441003_PIP-SCONN,HA!!!F231!DQS11P!!!!
S!M_F_DQS_DN<12>!J6L1!41!@baseboard_fab2_lib.baseboard_fab2(sch_1):page54_i66@mstr_sconn.sconn288_h44441003(chips)!SCONN288_H44441003_PIP-SCONN,HA!!!F231!DQS12N!!!!
S!M_F_DQS_DP<12>!J6L1!40!@baseboard_fab2_lib.baseboard_fab2(sch_1):page54_i66@mstr_sconn.sconn288_h44441003(chips)!SCONN288_H44441003_PIP-SCONN,HA!!!F231!DQS12P!!!!
S!M_F_DQS_DN<13>!J6L1!100!@baseboard_fab2_lib.baseboard_fab2(sch_1):page54_i66@mstr_sconn.sconn288_h44441003(chips)!SCONN288_H44441003_PIP-SCONN,HA!!!F231!DQS13N!!!!
S!M_F_DQS_DP<13>!J6L1!99!@baseboard_fab2_lib.baseboard_fab2(sch_1):page54_i66@mstr_sconn.sconn288_h44441003(chips)!SCONN288_H44441003_PIP-SCONN,HA!!!F231!DQS13P!!!!
S!M_F_DQS_DN<14>!J6L1!111!@baseboard_fab2_lib.baseboard_fab2(sch_1):page54_i66@mstr_sconn.sconn288_h44441003(chips)!SCONN288_H44441003_PIP-SCONN,HA!!!F231!DQS14N!!!!
S!M_F_DQS_DP<14>!J6L1!110!@baseboard_fab2_lib.baseboard_fab2(sch_1):page54_i66@mstr_sconn.sconn288_h44441003(chips)!SCONN288_H44441003_PIP-SCONN,HA!!!F231!DQS14P!!!!
S!M_F_DQS_DN<15>!J6L1!122!@baseboard_fab2_lib.baseboard_fab2(sch_1):page54_i66@mstr_sconn.sconn288_h44441003(chips)!SCONN288_H44441003_PIP-SCONN,HA!!!F231!DQS15N!!!!
S!M_F_DQS_DP<15>!J6L1!121!@baseboard_fab2_lib.baseboard_fab2(sch_1):page54_i66@mstr_sconn.sconn288_h44441003(chips)!SCONN288_H44441003_PIP-SCONN,HA!!!F231!DQS15P!!!!
S!M_F_DQS_DN<16>!J6L1!133!@baseboard_fab2_lib.baseboard_fab2(sch_1):page54_i66@mstr_sconn.sconn288_h44441003(chips)!SCONN288_H44441003_PIP-SCONN,HA!!!F231!DQS16N!!!!
S!M_F_DQS_DP<16>!J6L1!132!@baseboard_fab2_lib.baseboard_fab2(sch_1):page54_i66@mstr_sconn.sconn288_h44441003(chips)!SCONN288_H44441003_PIP-SCONN,HA!!!F231!DQS16P!!!!
S!M_F_DQS_DN<17>!J6L1!52!@baseboard_fab2_lib.baseboard_fab2(sch_1):page54_i66@mstr_sconn.sconn288_h44441003(chips)!SCONN288_H44441003_PIP-SCONN,HA!!!F231!DQS17N!!!!
S!M_F_DQS_DP<17>!J6L1!51!@baseboard_fab2_lib.baseboard_fab2(sch_1):page54_i66@mstr_sconn.sconn288_h44441003(chips)!SCONN288_H44441003_PIP-SCONN,HA!!!F231!DQS17P!!!!
S!M_F_DQS_DN<1>!J6L1!163!@baseboard_fab2_lib.baseboard_fab2(sch_1):page54_i66@mstr_sconn.sconn288_h44441003(chips)!SCONN288_H44441003_PIP-SCONN,HA!!!F231!DQS1N!!!!
S!M_F_DQS_DP<1>!J6L1!164!@baseboard_fab2_lib.baseboard_fab2(sch_1):page54_i66@mstr_sconn.sconn288_h44441003(chips)!SCONN288_H44441003_PIP-SCONN,HA!!!F231!DQS1P!!!!
S!M_F_DQS_DN<2>!J6L1!174!@baseboard_fab2_lib.baseboard_fab2(sch_1):page54_i66@mstr_sconn.sconn288_h44441003(chips)!SCONN288_H44441003_PIP-SCONN,HA!!!F231!DQS2N!!!!
S!M_F_DQS_DP<2>!J6L1!175!@baseboard_fab2_lib.baseboard_fab2(sch_1):page54_i66@mstr_sconn.sconn288_h44441003(chips)!SCONN288_H44441003_PIP-SCONN,HA!!!F231!DQS2P!!!!
S!M_F_DQS_DN<3>!J6L1!185!@baseboard_fab2_lib.baseboard_fab2(sch_1):page54_i66@mstr_sconn.sconn288_h44441003(chips)!SCONN288_H44441003_PIP-SCONN,HA!!!F231!DQS3N!!!!
S!M_F_DQS_DP<3>!J6L1!186!@baseboard_fab2_lib.baseboard_fab2(sch_1):page54_i66@mstr_sconn.sconn288_h44441003(chips)!SCONN288_H44441003_PIP-SCONN,HA!!!F231!DQS3P!!!!
S!M_F_DQS_DN<4>!J6L1!244!@baseboard_fab2_lib.baseboard_fab2(sch_1):page54_i66@mstr_sconn.sconn288_h44441003(chips)!SCONN288_H44441003_PIP-SCONN,HA!!!F231!DQS4N!!!!
S!M_F_DQS_DP<4>!J6L1!245!@baseboard_fab2_lib.baseboard_fab2(sch_1):page54_i66@mstr_sconn.sconn288_h44441003(chips)!SCONN288_H44441003_PIP-SCONN,HA!!!F231!DQS4P!!!!
S!M_F_DQS_DN<5>!J6L1!255!@baseboard_fab2_lib.baseboard_fab2(sch_1):page54_i66@mstr_sconn.sconn288_h44441003(chips)!SCONN288_H44441003_PIP-SCONN,HA!!!F231!DQS5N!!!!
S!M_F_DQS_DP<5>!J6L1!256!@baseboard_fab2_lib.baseboard_fab2(sch_1):page54_i66@mstr_sconn.sconn288_h44441003(chips)!SCONN288_H44441003_PIP-SCONN,HA!!!F231!DQS5P!!!!
S!M_F_DQS_DN<6>!J6L1!266!@baseboard_fab2_lib.baseboard_fab2(sch_1):page54_i66@mstr_sconn.sconn288_h44441003(chips)!SCONN288_H44441003_PIP-SCONN,HA!!!F231!DQS6N!!!!
S!M_F_DQS_DP<6>!J6L1!267!@baseboard_fab2_lib.baseboard_fab2(sch_1):page54_i66@mstr_sconn.sconn288_h44441003(chips)!SCONN288_H44441003_PIP-SCONN,HA!!!F231!DQS6P!!!!
S!M_F_DQS_DN<7>!J6L1!277!@baseboard_fab2_lib.baseboard_fab2(sch_1):page54_i66@mstr_sconn.sconn288_h44441003(chips)!SCONN288_H44441003_PIP-SCONN,HA!!!F231!DQS7N!!!!
S!M_F_DQS_DP<7>!J6L1!278!@baseboard_fab2_lib.baseboard_fab2(sch_1):page54_i66@mstr_sconn.sconn288_h44441003(chips)!SCONN288_H44441003_PIP-SCONN,HA!!!F231!DQS7P!!!!
S!M_F_DQS_DN<8>!J6L1!196!@baseboard_fab2_lib.baseboard_fab2(sch_1):page54_i66@mstr_sconn.sconn288_h44441003(chips)!SCONN288_H44441003_PIP-SCONN,HA!!!F231!DQS8N!!!!
S!M_F_DQS_DP<8>!J6L1!197!@baseboard_fab2_lib.baseboard_fab2(sch_1):page54_i66@mstr_sconn.sconn288_h44441003(chips)!SCONN288_H44441003_PIP-SCONN,HA!!!F231!DQS8P!!!!
S!M_F_DQS_DN<9>!J6L1!8!@baseboard_fab2_lib.baseboard_fab2(sch_1):page54_i66@mstr_sconn.sconn288_h44441003(chips)!SCONN288_H44441003_PIP-SCONN,HA!!!F231!DQS9N!!!!
S!M_F_DQS_DP<9>!J6L1!7!@baseboard_fab2_lib.baseboard_fab2(sch_1):page54_i66@mstr_sconn.sconn288_h44441003(chips)!SCONN288_H44441003_PIP-SCONN,HA!!!F231!DQS9P!!!!
S!GND!J6L1!283!@baseboard_fab2_lib.baseboard_fab2(sch_1):page54_i43@mstr_sconn.sconn288_h44441003(chips)!SCONN288_H44441003_PIP-SCONN,HA!!!F230!VSS(0)!!!!
S!GND!J6L1!261!@baseboard_fab2_lib.baseboard_fab2(sch_1):page54_i43@mstr_sconn.sconn288_h44441003(chips)!SCONN288_H44441003_PIP-SCONN,HA!!!F230!VSS(10)!!!!
S!GND!J6L1!259!@baseboard_fab2_lib.baseboard_fab2(sch_1):page54_i43@mstr_sconn.sconn288_h44441003(chips)!SCONN288_H44441003_PIP-SCONN,HA!!!F230!VSS(11)!!!!
S!GND!J6L1!257!@baseboard_fab2_lib.baseboard_fab2(sch_1):page54_i43@mstr_sconn.sconn288_h44441003(chips)!SCONN288_H44441003_PIP-SCONN,HA!!!F230!VSS(12)!!!!
S!GND!J6L1!254!@baseboard_fab2_lib.baseboard_fab2(sch_1):page54_i43@mstr_sconn.sconn288_h44441003(chips)!SCONN288_H44441003_PIP-SCONN,HA!!!F230!VSS(13)!!!!
S!GND!J6L1!252!@baseboard_fab2_lib.baseboard_fab2(sch_1):page54_i43@mstr_sconn.sconn288_h44441003(chips)!SCONN288_H44441003_PIP-SCONN,HA!!!F230!VSS(14)!!!!
S!GND!J6L1!250!@baseboard_fab2_lib.baseboard_fab2(sch_1):page54_i43@mstr_sconn.sconn288_h44441003(chips)!SCONN288_H44441003_PIP-SCONN,HA!!!F230!VSS(15)!!!!
S!GND!J6L1!248!@baseboard_fab2_lib.baseboard_fab2(sch_1):page54_i43@mstr_sconn.sconn288_h44441003(chips)!SCONN288_H44441003_PIP-SCONN,HA!!!F230!VSS(16)!!!!
S!GND!J6L1!246!@baseboard_fab2_lib.baseboard_fab2(sch_1):page54_i43@mstr_sconn.sconn288_h44441003(chips)!SCONN288_H44441003_PIP-SCONN,HA!!!F230!VSS(17)!!!!
S!GND!J6L1!243!@baseboard_fab2_lib.baseboard_fab2(sch_1):page54_i43@mstr_sconn.sconn288_h44441003(chips)!SCONN288_H44441003_PIP-SCONN,HA!!!F230!VSS(18)!!!!
S!GND!J6L1!241!@baseboard_fab2_lib.baseboard_fab2(sch_1):page54_i43@mstr_sconn.sconn288_h44441003(chips)!SCONN288_H44441003_PIP-SCONN,HA!!!F230!VSS(19)!!!!
S!GND!J6L1!281!@baseboard_fab2_lib.baseboard_fab2(sch_1):page54_i43@mstr_sconn.sconn288_h44441003(chips)!SCONN288_H44441003_PIP-SCONN,HA!!!F230!VSS(1)!!!!
S!GND!J6L1!239!@baseboard_fab2_lib.baseboard_fab2(sch_1):page54_i43@mstr_sconn.sconn288_h44441003(chips)!SCONN288_H44441003_PIP-SCONN,HA!!!F230!VSS(20)!!!!
S!GND!J6L1!202!@baseboard_fab2_lib.baseboard_fab2(sch_1):page54_i43@mstr_sconn.sconn288_h44441003(chips)!SCONN288_H44441003_PIP-SCONN,HA!!!F230!VSS(21)!!!!
S!GND!J6L1!200!@baseboard_fab2_lib.baseboard_fab2(sch_1):page54_i43@mstr_sconn.sconn288_h44441003(chips)!SCONN288_H44441003_PIP-SCONN,HA!!!F230!VSS(22)!!!!
S!GND!J6L1!198!@baseboard_fab2_lib.baseboard_fab2(sch_1):page54_i43@mstr_sconn.sconn288_h44441003(chips)!SCONN288_H44441003_PIP-SCONN,HA!!!F230!VSS(23)!!!!
S!GND!J6L1!195!@baseboard_fab2_lib.baseboard_fab2(sch_1):page54_i43@mstr_sconn.sconn288_h44441003(chips)!SCONN288_H44441003_PIP-SCONN,HA!!!F230!VSS(24)!!!!
S!GND!J6L1!193!@baseboard_fab2_lib.baseboard_fab2(sch_1):page54_i43@mstr_sconn.sconn288_h44441003(chips)!SCONN288_H44441003_PIP-SCONN,HA!!!F230!VSS(25)!!!!
S!GND!J6L1!191!@baseboard_fab2_lib.baseboard_fab2(sch_1):page54_i43@mstr_sconn.sconn288_h44441003(chips)!SCONN288_H44441003_PIP-SCONN,HA!!!F230!VSS(26)!!!!
S!GND!J6L1!189!@baseboard_fab2_lib.baseboard_fab2(sch_1):page54_i43@mstr_sconn.sconn288_h44441003(chips)!SCONN288_H44441003_PIP-SCONN,HA!!!F230!VSS(27)!!!!
S!GND!J6L1!187!@baseboard_fab2_lib.baseboard_fab2(sch_1):page54_i43@mstr_sconn.sconn288_h44441003(chips)!SCONN288_H44441003_PIP-SCONN,HA!!!F230!VSS(28)!!!!
S!GND!J6L1!184!@baseboard_fab2_lib.baseboard_fab2(sch_1):page54_i43@mstr_sconn.sconn288_h44441003(chips)!SCONN288_H44441003_PIP-SCONN,HA!!!F230!VSS(29)!!!!
S!GND!J6L1!279!@baseboard_fab2_lib.baseboard_fab2(sch_1):page54_i43@mstr_sconn.sconn288_h44441003(chips)!SCONN288_H44441003_PIP-SCONN,HA!!!F230!VSS(2)!!!!
S!GND!J6L1!182!@baseboard_fab2_lib.baseboard_fab2(sch_1):page54_i43@mstr_sconn.sconn288_h44441003(chips)!SCONN288_H44441003_PIP-SCONN,HA!!!F230!VSS(30)!!!!
S!GND!J6L1!180!@baseboard_fab2_lib.baseboard_fab2(sch_1):page54_i43@mstr_sconn.sconn288_h44441003(chips)!SCONN288_H44441003_PIP-SCONN,HA!!!F230!VSS(31)!!!!
S!GND!J6L1!178!@baseboard_fab2_lib.baseboard_fab2(sch_1):page54_i43@mstr_sconn.sconn288_h44441003(chips)!SCONN288_H44441003_PIP-SCONN,HA!!!F230!VSS(32)!!!!
S!GND!J6L1!176!@baseboard_fab2_lib.baseboard_fab2(sch_1):page54_i43@mstr_sconn.sconn288_h44441003(chips)!SCONN288_H44441003_PIP-SCONN,HA!!!F230!VSS(33)!!!!
S!GND!J6L1!173!@baseboard_fab2_lib.baseboard_fab2(sch_1):page54_i43@mstr_sconn.sconn288_h44441003(chips)!SCONN288_H44441003_PIP-SCONN,HA!!!F230!VSS(34)!!!!
S!GND!J6L1!171!@baseboard_fab2_lib.baseboard_fab2(sch_1):page54_i43@mstr_sconn.sconn288_h44441003(chips)!SCONN288_H44441003_PIP-SCONN,HA!!!F230!VSS(35)!!!!
S!GND!J6L1!169!@baseboard_fab2_lib.baseboard_fab2(sch_1):page54_i43@mstr_sconn.sconn288_h44441003(chips)!SCONN288_H44441003_PIP-SCONN,HA!!!F230!VSS(36)!!!!
S!GND!J6L1!167!@baseboard_fab2_lib.baseboard_fab2(sch_1):page54_i43@mstr_sconn.sconn288_h44441003(chips)!SCONN288_H44441003_PIP-SCONN,HA!!!F230!VSS(37)!!!!
S!GND!J6L1!165!@baseboard_fab2_lib.baseboard_fab2(sch_1):page54_i43@mstr_sconn.sconn288_h44441003(chips)!SCONN288_H44441003_PIP-SCONN,HA!!!F230!VSS(38)!!!!
S!GND!J6L1!162!@baseboard_fab2_lib.baseboard_fab2(sch_1):page54_i43@mstr_sconn.sconn288_h44441003(chips)!SCONN288_H44441003_PIP-SCONN,HA!!!F230!VSS(39)!!!!
S!GND!J6L1!276!@baseboard_fab2_lib.baseboard_fab2(sch_1):page54_i43@mstr_sconn.sconn288_h44441003(chips)!SCONN288_H44441003_PIP-SCONN,HA!!!F230!VSS(3)!!!!
S!GND!J6L1!160!@baseboard_fab2_lib.baseboard_fab2(sch_1):page54_i43@mstr_sconn.sconn288_h44441003(chips)!SCONN288_H44441003_PIP-SCONN,HA!!!F230!VSS(40)!!!!
S!GND!J6L1!158!@baseboard_fab2_lib.baseboard_fab2(sch_1):page54_i43@mstr_sconn.sconn288_h44441003(chips)!SCONN288_H44441003_PIP-SCONN,HA!!!F230!VSS(41)!!!!
S!GND!J6L1!156!@baseboard_fab2_lib.baseboard_fab2(sch_1):page54_i43@mstr_sconn.sconn288_h44441003(chips)!SCONN288_H44441003_PIP-SCONN,HA!!!F230!VSS(42)!!!!
S!GND!J6L1!154!@baseboard_fab2_lib.baseboard_fab2(sch_1):page54_i43@mstr_sconn.sconn288_h44441003(chips)!SCONN288_H44441003_PIP-SCONN,HA!!!F230!VSS(43)!!!!
S!GND!J6L1!151!@baseboard_fab2_lib.baseboard_fab2(sch_1):page54_i43@mstr_sconn.sconn288_h44441003(chips)!SCONN288_H44441003_PIP-SCONN,HA!!!F230!VSS(44)!!!!
S!GND!J6L1!149!@baseboard_fab2_lib.baseboard_fab2(sch_1):page54_i43@mstr_sconn.sconn288_h44441003(chips)!SCONN288_H44441003_PIP-SCONN,HA!!!F230!VSS(45)!!!!
S!GND!J6L1!147!@baseboard_fab2_lib.baseboard_fab2(sch_1):page54_i43@mstr_sconn.sconn288_h44441003(chips)!SCONN288_H44441003_PIP-SCONN,HA!!!F230!VSS(46)!!!!
S!GND!J6L1!138!@baseboard_fab2_lib.baseboard_fab2(sch_1):page54_i43@mstr_sconn.sconn288_h44441003(chips)!SCONN288_H44441003_PIP-SCONN,HA!!!F230!VSS(47)!!!!
S!GND!J6L1!136!@baseboard_fab2_lib.baseboard_fab2(sch_1):page54_i43@mstr_sconn.sconn288_h44441003(chips)!SCONN288_H44441003_PIP-SCONN,HA!!!F230!VSS(48)!!!!
S!GND!J6L1!134!@baseboard_fab2_lib.baseboard_fab2(sch_1):page54_i43@mstr_sconn.sconn288_h44441003(chips)!SCONN288_H44441003_PIP-SCONN,HA!!!F230!VSS(49)!!!!
S!GND!J6L1!274!@baseboard_fab2_lib.baseboard_fab2(sch_1):page54_i43@mstr_sconn.sconn288_h44441003(chips)!SCONN288_H44441003_PIP-SCONN,HA!!!F230!VSS(4)!!!!
S!GND!J6L1!131!@baseboard_fab2_lib.baseboard_fab2(sch_1):page54_i43@mstr_sconn.sconn288_h44441003(chips)!SCONN288_H44441003_PIP-SCONN,HA!!!F230!VSS(50)!!!!
S!GND!J6L1!129!@baseboard_fab2_lib.baseboard_fab2(sch_1):page54_i43@mstr_sconn.sconn288_h44441003(chips)!SCONN288_H44441003_PIP-SCONN,HA!!!F230!VSS(51)!!!!
S!GND!J6L1!127!@baseboard_fab2_lib.baseboard_fab2(sch_1):page54_i43@mstr_sconn.sconn288_h44441003(chips)!SCONN288_H44441003_PIP-SCONN,HA!!!F230!VSS(52)!!!!
S!GND!J6L1!125!@baseboard_fab2_lib.baseboard_fab2(sch_1):page54_i43@mstr_sconn.sconn288_h44441003(chips)!SCONN288_H44441003_PIP-SCONN,HA!!!F230!VSS(53)!!!!
S!GND!J6L1!123!@baseboard_fab2_lib.baseboard_fab2(sch_1):page54_i43@mstr_sconn.sconn288_h44441003(chips)!SCONN288_H44441003_PIP-SCONN,HA!!!F230!VSS(54)!!!!
S!GND!J6L1!120!@baseboard_fab2_lib.baseboard_fab2(sch_1):page54_i43@mstr_sconn.sconn288_h44441003(chips)!SCONN288_H44441003_PIP-SCONN,HA!!!F230!VSS(55)!!!!
S!GND!J6L1!118!@baseboard_fab2_lib.baseboard_fab2(sch_1):page54_i43@mstr_sconn.sconn288_h44441003(chips)!SCONN288_H44441003_PIP-SCONN,HA!!!F230!VSS(56)!!!!
S!GND!J6L1!116!@baseboard_fab2_lib.baseboard_fab2(sch_1):page54_i43@mstr_sconn.sconn288_h44441003(chips)!SCONN288_H44441003_PIP-SCONN,HA!!!F230!VSS(57)!!!!
S!GND!J6L1!114!@baseboard_fab2_lib.baseboard_fab2(sch_1):page54_i43@mstr_sconn.sconn288_h44441003(chips)!SCONN288_H44441003_PIP-SCONN,HA!!!F230!VSS(58)!!!!
S!GND!J6L1!112!@baseboard_fab2_lib.baseboard_fab2(sch_1):page54_i43@mstr_sconn.sconn288_h44441003(chips)!SCONN288_H44441003_PIP-SCONN,HA!!!F230!VSS(59)!!!!
S!GND!J6L1!272!@baseboard_fab2_lib.baseboard_fab2(sch_1):page54_i43@mstr_sconn.sconn288_h44441003(chips)!SCONN288_H44441003_PIP-SCONN,HA!!!F230!VSS(5)!!!!
S!GND!J6L1!109!@baseboard_fab2_lib.baseboard_fab2(sch_1):page54_i43@mstr_sconn.sconn288_h44441003(chips)!SCONN288_H44441003_PIP-SCONN,HA!!!F230!VSS(60)!!!!
S!GND!J6L1!107!@baseboard_fab2_lib.baseboard_fab2(sch_1):page54_i43@mstr_sconn.sconn288_h44441003(chips)!SCONN288_H44441003_PIP-SCONN,HA!!!F230!VSS(61)!!!!
S!GND!J6L1!105!@baseboard_fab2_lib.baseboard_fab2(sch_1):page54_i43@mstr_sconn.sconn288_h44441003(chips)!SCONN288_H44441003_PIP-SCONN,HA!!!F230!VSS(62)!!!!
S!GND!J6L1!103!@baseboard_fab2_lib.baseboard_fab2(sch_1):page54_i43@mstr_sconn.sconn288_h44441003(chips)!SCONN288_H44441003_PIP-SCONN,HA!!!F230!VSS(63)!!!!
S!GND!J6L1!101!@baseboard_fab2_lib.baseboard_fab2(sch_1):page54_i43@mstr_sconn.sconn288_h44441003(chips)!SCONN288_H44441003_PIP-SCONN,HA!!!F230!VSS(64)!!!!
S!GND!J6L1!98!@baseboard_fab2_lib.baseboard_fab2(sch_1):page54_i43@mstr_sconn.sconn288_h44441003(chips)!SCONN288_H44441003_PIP-SCONN,HA!!!F230!VSS(65)!!!!
S!GND!J6L1!96!@baseboard_fab2_lib.baseboard_fab2(sch_1):page54_i43@mstr_sconn.sconn288_h44441003(chips)!SCONN288_H44441003_PIP-SCONN,HA!!!F230!VSS(66)!!!!
S!GND!J6L1!94!@baseboard_fab2_lib.baseboard_fab2(sch_1):page54_i43@mstr_sconn.sconn288_h44441003(chips)!SCONN288_H44441003_PIP-SCONN,HA!!!F230!VSS(67)!!!!
S!GND!J6L1!57!@baseboard_fab2_lib.baseboard_fab2(sch_1):page54_i43@mstr_sconn.sconn288_h44441003(chips)!SCONN288_H44441003_PIP-SCONN,HA!!!F230!VSS(68)!!!!
S!GND!J6L1!55!@baseboard_fab2_lib.baseboard_fab2(sch_1):page54_i43@mstr_sconn.sconn288_h44441003(chips)!SCONN288_H44441003_PIP-SCONN,HA!!!F230!VSS(69)!!!!
S!GND!J6L1!270!@baseboard_fab2_lib.baseboard_fab2(sch_1):page54_i43@mstr_sconn.sconn288_h44441003(chips)!SCONN288_H44441003_PIP-SCONN,HA!!!F230!VSS(6)!!!!
S!GND!J6L1!53!@baseboard_fab2_lib.baseboard_fab2(sch_1):page54_i43@mstr_sconn.sconn288_h44441003(chips)!SCONN288_H44441003_PIP-SCONN,HA!!!F230!VSS(70)!!!!
S!GND!J6L1!50!@baseboard_fab2_lib.baseboard_fab2(sch_1):page54_i43@mstr_sconn.sconn288_h44441003(chips)!SCONN288_H44441003_PIP-SCONN,HA!!!F230!VSS(71)!!!!
S!GND!J6L1!48!@baseboard_fab2_lib.baseboard_fab2(sch_1):page54_i43@mstr_sconn.sconn288_h44441003(chips)!SCONN288_H44441003_PIP-SCONN,HA!!!F230!VSS(72)!!!!
S!GND!J6L1!46!@baseboard_fab2_lib.baseboard_fab2(sch_1):page54_i43@mstr_sconn.sconn288_h44441003(chips)!SCONN288_H44441003_PIP-SCONN,HA!!!F230!VSS(73)!!!!
S!GND!J6L1!44!@baseboard_fab2_lib.baseboard_fab2(sch_1):page54_i43@mstr_sconn.sconn288_h44441003(chips)!SCONN288_H44441003_PIP-SCONN,HA!!!F230!VSS(74)!!!!
S!GND!J6L1!42!@baseboard_fab2_lib.baseboard_fab2(sch_1):page54_i43@mstr_sconn.sconn288_h44441003(chips)!SCONN288_H44441003_PIP-SCONN,HA!!!F230!VSS(75)!!!!
S!GND!J6L1!39!@baseboard_fab2_lib.baseboard_fab2(sch_1):page54_i43@mstr_sconn.sconn288_h44441003(chips)!SCONN288_H44441003_PIP-SCONN,HA!!!F230!VSS(76)!!!!
S!GND!J6L1!37!@baseboard_fab2_lib.baseboard_fab2(sch_1):page54_i43@mstr_sconn.sconn288_h44441003(chips)!SCONN288_H44441003_PIP-SCONN,HA!!!F230!VSS(77)!!!!
S!GND!J6L1!35!@baseboard_fab2_lib.baseboard_fab2(sch_1):page54_i43@mstr_sconn.sconn288_h44441003(chips)!SCONN288_H44441003_PIP-SCONN,HA!!!F230!VSS(78)!!!!
S!GND!J6L1!33!@baseboard_fab2_lib.baseboard_fab2(sch_1):page54_i43@mstr_sconn.sconn288_h44441003(chips)!SCONN288_H44441003_PIP-SCONN,HA!!!F230!VSS(79)!!!!
S!GND!J6L1!268!@baseboard_fab2_lib.baseboard_fab2(sch_1):page54_i43@mstr_sconn.sconn288_h44441003(chips)!SCONN288_H44441003_PIP-SCONN,HA!!!F230!VSS(7)!!!!
S!GND!J6L1!31!@baseboard_fab2_lib.baseboard_fab2(sch_1):page54_i43@mstr_sconn.sconn288_h44441003(chips)!SCONN288_H44441003_PIP-SCONN,HA!!!F230!VSS(80)!!!!
S!GND!J6L1!28!@baseboard_fab2_lib.baseboard_fab2(sch_1):page54_i43@mstr_sconn.sconn288_h44441003(chips)!SCONN288_H44441003_PIP-SCONN,HA!!!F230!VSS(81)!!!!
S!GND!J6L1!26!@baseboard_fab2_lib.baseboard_fab2(sch_1):page54_i43@mstr_sconn.sconn288_h44441003(chips)!SCONN288_H44441003_PIP-SCONN,HA!!!F230!VSS(82)!!!!
S!GND!J6L1!24!@baseboard_fab2_lib.baseboard_fab2(sch_1):page54_i43@mstr_sconn.sconn288_h44441003(chips)!SCONN288_H44441003_PIP-SCONN,HA!!!F230!VSS(83)!!!!
S!GND!J6L1!22!@baseboard_fab2_lib.baseboard_fab2(sch_1):page54_i43@mstr_sconn.sconn288_h44441003(chips)!SCONN288_H44441003_PIP-SCONN,HA!!!F230!VSS(84)!!!!
S!GND!J6L1!20!@baseboard_fab2_lib.baseboard_fab2(sch_1):page54_i43@mstr_sconn.sconn288_h44441003(chips)!SCONN288_H44441003_PIP-SCONN,HA!!!F230!VSS(85)!!!!
S!GND!J6L1!17!@baseboard_fab2_lib.baseboard_fab2(sch_1):page54_i43@mstr_sconn.sconn288_h44441003(chips)!SCONN288_H44441003_PIP-SCONN,HA!!!F230!VSS(86)!!!!
S!GND!J6L1!15!@baseboard_fab2_lib.baseboard_fab2(sch_1):page54_i43@mstr_sconn.sconn288_h44441003(chips)!SCONN288_H44441003_PIP-SCONN,HA!!!F230!VSS(87)!!!!
S!GND!J6L1!13!@baseboard_fab2_lib.baseboard_fab2(sch_1):page54_i43@mstr_sconn.sconn288_h44441003(chips)!SCONN288_H44441003_PIP-SCONN,HA!!!F230!VSS(88)!!!!
S!GND!J6L1!11!@baseboard_fab2_lib.baseboard_fab2(sch_1):page54_i43@mstr_sconn.sconn288_h44441003(chips)!SCONN288_H44441003_PIP-SCONN,HA!!!F230!VSS(89)!!!!
S!GND!J6L1!265!@baseboard_fab2_lib.baseboard_fab2(sch_1):page54_i43@mstr_sconn.sconn288_h44441003(chips)!SCONN288_H44441003_PIP-SCONN,HA!!!F230!VSS(8)!!!!
S!GND!J6L1!9!@baseboard_fab2_lib.baseboard_fab2(sch_1):page54_i43@mstr_sconn.sconn288_h44441003(chips)!SCONN288_H44441003_PIP-SCONN,HA!!!F230!VSS(90)!!!!
S!GND!J6L1!6!@baseboard_fab2_lib.baseboard_fab2(sch_1):page54_i43@mstr_sconn.sconn288_h44441003(chips)!SCONN288_H44441003_PIP-SCONN,HA!!!F230!VSS(91)!!!!
S!GND!J6L1!4!@baseboard_fab2_lib.baseboard_fab2(sch_1):page54_i43@mstr_sconn.sconn288_h44441003(chips)!SCONN288_H44441003_PIP-SCONN,HA!!!F230!VSS(92)!!!!
S!GND!J6L1!2!@baseboard_fab2_lib.baseboard_fab2(sch_1):page54_i43@mstr_sconn.sconn288_h44441003(chips)!SCONN288_H44441003_PIP-SCONN,HA!!!F230!VSS(93)!!!!
S!GND!J6L1!263!@baseboard_fab2_lib.baseboard_fab2(sch_1):page54_i43@mstr_sconn.sconn288_h44441003(chips)!SCONN288_H44441003_PIP-SCONN,HA!!!F230!VSS(9)!!!!
S!P12V_NVDIMM_DEF!J6L1!145!@baseboard_fab2_lib.baseboard_fab2(sch_1):page54_i170@mstr_sconn.sconn288_h44441003(chips)!SCONN288_H44441003_PIP-SCONN,HA!!!F229!\12v\(0)!!!!
S!P12V_NVDIMM_DEF!J6L1!1!@baseboard_fab2_lib.baseboard_fab2(sch_1):page54_i170@mstr_sconn.sconn288_h44441003(chips)!SCONN288_H44441003_PIP-SCONN,HA!!!F229!\12v\(1)!!!!
S!PVDDQ_DEF!J6L1!236!@baseboard_fab2_lib.baseboard_fab2(sch_1):page54_i170@mstr_sconn.sconn288_h44441003(chips)!SCONN288_H44441003_PIP-SCONN,HA!!!F229!VDD(0)!!!!
S!PVDDQ_DEF!J6L1!209!@baseboard_fab2_lib.baseboard_fab2(sch_1):page54_i170@mstr_sconn.sconn288_h44441003(chips)!SCONN288_H44441003_PIP-SCONN,HA!!!F229!VDD(10)!!!!
S!PVDDQ_DEF!J6L1!206!@baseboard_fab2_lib.baseboard_fab2(sch_1):page54_i170@mstr_sconn.sconn288_h44441003(chips)!SCONN288_H44441003_PIP-SCONN,HA!!!F229!VDD(11)!!!!
S!PVDDQ_DEF!J6L1!204!@baseboard_fab2_lib.baseboard_fab2(sch_1):page54_i170@mstr_sconn.sconn288_h44441003(chips)!SCONN288_H44441003_PIP-SCONN,HA!!!F229!VDD(12)!!!!
S!PVDDQ_DEF!J6L1!92!@baseboard_fab2_lib.baseboard_fab2(sch_1):page54_i170@mstr_sconn.sconn288_h44441003(chips)!SCONN288_H44441003_PIP-SCONN,HA!!!F229!VDD(13)!!!!
S!PVDDQ_DEF!J6L1!90!@baseboard_fab2_lib.baseboard_fab2(sch_1):page54_i170@mstr_sconn.sconn288_h44441003(chips)!SCONN288_H44441003_PIP-SCONN,HA!!!F229!VDD(14)!!!!
S!PVDDQ_DEF!J6L1!88!@baseboard_fab2_lib.baseboard_fab2(sch_1):page54_i170@mstr_sconn.sconn288_h44441003(chips)!SCONN288_H44441003_PIP-SCONN,HA!!!F229!VDD(15)!!!!
S!PVDDQ_DEF!J6L1!85!@baseboard_fab2_lib.baseboard_fab2(sch_1):page54_i170@mstr_sconn.sconn288_h44441003(chips)!SCONN288_H44441003_PIP-SCONN,HA!!!F229!VDD(16)!!!!
S!PVDDQ_DEF!J6L1!83!@baseboard_fab2_lib.baseboard_fab2(sch_1):page54_i170@mstr_sconn.sconn288_h44441003(chips)!SCONN288_H44441003_PIP-SCONN,HA!!!F229!VDD(17)!!!!
S!PVDDQ_DEF!J6L1!80!@baseboard_fab2_lib.baseboard_fab2(sch_1):page54_i170@mstr_sconn.sconn288_h44441003(chips)!SCONN288_H44441003_PIP-SCONN,HA!!!F229!VDD(18)!!!!
S!PVDDQ_DEF!J6L1!76!@baseboard_fab2_lib.baseboard_fab2(sch_1):page54_i170@mstr_sconn.sconn288_h44441003(chips)!SCONN288_H44441003_PIP-SCONN,HA!!!F229!VDD(19)!!!!
S!PVDDQ_DEF!J6L1!233!@baseboard_fab2_lib.baseboard_fab2(sch_1):page54_i170@mstr_sconn.sconn288_h44441003(chips)!SCONN288_H44441003_PIP-SCONN,HA!!!F229!VDD(1)!!!!
S!PVDDQ_DEF!J6L1!73!@baseboard_fab2_lib.baseboard_fab2(sch_1):page54_i170@mstr_sconn.sconn288_h44441003(chips)!SCONN288_H44441003_PIP-SCONN,HA!!!F229!VDD(20)!!!!
S!PVDDQ_DEF!J6L1!70!@baseboard_fab2_lib.baseboard_fab2(sch_1):page54_i170@mstr_sconn.sconn288_h44441003(chips)!SCONN288_H44441003_PIP-SCONN,HA!!!F229!VDD(21)!!!!
S!PVDDQ_DEF!J6L1!67!@baseboard_fab2_lib.baseboard_fab2(sch_1):page54_i170@mstr_sconn.sconn288_h44441003(chips)!SCONN288_H44441003_PIP-SCONN,HA!!!F229!VDD(22)!!!!
S!PVDDQ_DEF!J6L1!64!@baseboard_fab2_lib.baseboard_fab2(sch_1):page54_i170@mstr_sconn.sconn288_h44441003(chips)!SCONN288_H44441003_PIP-SCONN,HA!!!F229!VDD(23)!!!!
S!PVDDQ_DEF!J6L1!61!@baseboard_fab2_lib.baseboard_fab2(sch_1):page54_i170@mstr_sconn.sconn288_h44441003(chips)!SCONN288_H44441003_PIP-SCONN,HA!!!F229!VDD(24)!!!!
S!PVDDQ_DEF!J6L1!59!@baseboard_fab2_lib.baseboard_fab2(sch_1):page54_i170@mstr_sconn.sconn288_h44441003(chips)!SCONN288_H44441003_PIP-SCONN,HA!!!F229!VDD(25)!!!!
S!PVDDQ_DEF!J6L1!231!@baseboard_fab2_lib.baseboard_fab2(sch_1):page54_i170@mstr_sconn.sconn288_h44441003(chips)!SCONN288_H44441003_PIP-SCONN,HA!!!F229!VDD(2)!!!!
S!PVDDQ_DEF!J6L1!229!@baseboard_fab2_lib.baseboard_fab2(sch_1):page54_i170@mstr_sconn.sconn288_h44441003(chips)!SCONN288_H44441003_PIP-SCONN,HA!!!F229!VDD(3)!!!!
S!PVDDQ_DEF!J6L1!226!@baseboard_fab2_lib.baseboard_fab2(sch_1):page54_i170@mstr_sconn.sconn288_h44441003(chips)!SCONN288_H44441003_PIP-SCONN,HA!!!F229!VDD(4)!!!!
S!PVDDQ_DEF!J6L1!223!@baseboard_fab2_lib.baseboard_fab2(sch_1):page54_i170@mstr_sconn.sconn288_h44441003(chips)!SCONN288_H44441003_PIP-SCONN,HA!!!F229!VDD(5)!!!!
S!PVDDQ_DEF!J6L1!220!@baseboard_fab2_lib.baseboard_fab2(sch_1):page54_i170@mstr_sconn.sconn288_h44441003(chips)!SCONN288_H44441003_PIP-SCONN,HA!!!F229!VDD(6)!!!!
S!PVDDQ_DEF!J6L1!217!@baseboard_fab2_lib.baseboard_fab2(sch_1):page54_i170@mstr_sconn.sconn288_h44441003(chips)!SCONN288_H44441003_PIP-SCONN,HA!!!F229!VDD(7)!!!!
S!PVDDQ_DEF!J6L1!215!@baseboard_fab2_lib.baseboard_fab2(sch_1):page54_i170@mstr_sconn.sconn288_h44441003(chips)!SCONN288_H44441003_PIP-SCONN,HA!!!F229!VDD(8)!!!!
S!PVDDQ_DEF!J6L1!212!@baseboard_fab2_lib.baseboard_fab2(sch_1):page54_i170@mstr_sconn.sconn288_h44441003(chips)!SCONN288_H44441003_PIP-SCONN,HA!!!F229!VDD(9)!!!!
S!PVPP_DEF!J6L1!287!@baseboard_fab2_lib.baseboard_fab2(sch_1):page54_i170@mstr_sconn.sconn288_h44441003(chips)!SCONN288_H44441003_PIP-SCONN,HA!!!F229!VPP(0)!!!!
S!PVPP_DEF!J6L1!286!@baseboard_fab2_lib.baseboard_fab2(sch_1):page54_i170@mstr_sconn.sconn288_h44441003(chips)!SCONN288_H44441003_PIP-SCONN,HA!!!F229!VPP(1)!!!!
S!PVPP_DEF!J6L1!288!@baseboard_fab2_lib.baseboard_fab2(sch_1):page54_i170@mstr_sconn.sconn288_h44441003(chips)!SCONN288_H44441003_PIP-SCONN,HA!!!F229!VPP(2)!!!!
S!PVPP_DEF!J6L1!143!@baseboard_fab2_lib.baseboard_fab2(sch_1):page54_i170@mstr_sconn.sconn288_h44441003(chips)!SCONN288_H44441003_PIP-SCONN,HA!!!F229!VPP(3)!!!!
S!PVPP_DEF!J6L1!142!@baseboard_fab2_lib.baseboard_fab2(sch_1):page54_i170@mstr_sconn.sconn288_h44441003(chips)!SCONN288_H44441003_PIP-SCONN,HA!!!F229!VPP(4)!!!!
S!PVTT_DEF!J6L1!221!@baseboard_fab2_lib.baseboard_fab2(sch_1):page54_i170@mstr_sconn.sconn288_h44441003(chips)!SCONN288_H44441003_PIP-SCONN,HA!!!F229!VTT(0)!!!!
S!PVTT_DEF!J6L1!77!@baseboard_fab2_lib.baseboard_fab2(sch_1):page54_i170@mstr_sconn.sconn288_h44441003(chips)!SCONN288_H44441003_PIP-SCONN,HA!!!F229!VTT(1)!!!!
S!M_G_MA<0>!J9T1!79!@baseboard_fab2_lib.baseboard_fab2(sch_1):page78_i13@mstr_sconn.sconn288_h44441003(chips)!SCONN288_H44441003_PIP-SCONN,HA!!!F196!A0!!!!
S!M_G_MA<1>!J9T1!72!@baseboard_fab2_lib.baseboard_fab2(sch_1):page78_i13@mstr_sconn.sconn288_h44441003(chips)!SCONN288_H44441003_PIP-SCONN,HA!!!F196!A1!!!!
S!M_G_MA<10>!J9T1!225!@baseboard_fab2_lib.baseboard_fab2(sch_1):page78_i13@mstr_sconn.sconn288_h44441003(chips)!SCONN288_H44441003_PIP-SCONN,HA!!!F196!A10!!!!
S!M_G_MA<11>!J9T1!210!@baseboard_fab2_lib.baseboard_fab2(sch_1):page78_i13@mstr_sconn.sconn288_h44441003(chips)!SCONN288_H44441003_PIP-SCONN,HA!!!F196!A11!!!!
S!M_G_MA<12>!J9T1!65!@baseboard_fab2_lib.baseboard_fab2(sch_1):page78_i13@mstr_sconn.sconn288_h44441003(chips)!SCONN288_H44441003_PIP-SCONN,HA!!!F196!A12!!!!
S!M_G_MA<13>!J9T1!232!@baseboard_fab2_lib.baseboard_fab2(sch_1):page78_i13@mstr_sconn.sconn288_h44441003(chips)!SCONN288_H44441003_PIP-SCONN,HA!!!F196!A13!!!!
S!M_G_MA<14>!J9T1!228!@baseboard_fab2_lib.baseboard_fab2(sch_1):page78_i13@mstr_sconn.sconn288_h44441003(chips)!SCONN288_H44441003_PIP-SCONN,HA!!!F196!A14_WE_N!!!!
S!M_G_MA<15>!J9T1!86!@baseboard_fab2_lib.baseboard_fab2(sch_1):page78_i13@mstr_sconn.sconn288_h44441003(chips)!SCONN288_H44441003_PIP-SCONN,HA!!!F196!A15_CAS_N!!!!
S!M_G_MA<16>!J9T1!82!@baseboard_fab2_lib.baseboard_fab2(sch_1):page78_i13@mstr_sconn.sconn288_h44441003(chips)!SCONN288_H44441003_PIP-SCONN,HA!!!F196!A16_RAS_N!!!!
S!M_G_MA<17>!J9T1!234!@baseboard_fab2_lib.baseboard_fab2(sch_1):page78_i13@mstr_sconn.sconn288_h44441003(chips)!SCONN288_H44441003_PIP-SCONN,HA!!!F196!A17!!!!
S!M_G_MA<2>!J9T1!216!@baseboard_fab2_lib.baseboard_fab2(sch_1):page78_i13@mstr_sconn.sconn288_h44441003(chips)!SCONN288_H44441003_PIP-SCONN,HA!!!F196!A2!!!!
S!M_G_MA<3>!J9T1!71!@baseboard_fab2_lib.baseboard_fab2(sch_1):page78_i13@mstr_sconn.sconn288_h44441003(chips)!SCONN288_H44441003_PIP-SCONN,HA!!!F196!A3!!!!
S!M_G_MA<4>!J9T1!214!@baseboard_fab2_lib.baseboard_fab2(sch_1):page78_i13@mstr_sconn.sconn288_h44441003(chips)!SCONN288_H44441003_PIP-SCONN,HA!!!F196!A4!!!!
S!M_G_MA<5>!J9T1!213!@baseboard_fab2_lib.baseboard_fab2(sch_1):page78_i13@mstr_sconn.sconn288_h44441003(chips)!SCONN288_H44441003_PIP-SCONN,HA!!!F196!A5!!!!
S!M_G_MA<6>!J9T1!69!@baseboard_fab2_lib.baseboard_fab2(sch_1):page78_i13@mstr_sconn.sconn288_h44441003(chips)!SCONN288_H44441003_PIP-SCONN,HA!!!F196!A6!!!!
S!M_G_MA<7>!J9T1!211!@baseboard_fab2_lib.baseboard_fab2(sch_1):page78_i13@mstr_sconn.sconn288_h44441003(chips)!SCONN288_H44441003_PIP-SCONN,HA!!!F196!A7!!!!
S!M_G_MA<8>!J9T1!68!@baseboard_fab2_lib.baseboard_fab2(sch_1):page78_i13@mstr_sconn.sconn288_h44441003(chips)!SCONN288_H44441003_PIP-SCONN,HA!!!F196!A8!!!!
S!M_G_MA<9>!J9T1!66!@baseboard_fab2_lib.baseboard_fab2(sch_1):page78_i13@mstr_sconn.sconn288_h44441003(chips)!SCONN288_H44441003_PIP-SCONN,HA!!!F196!A9!!!!
S!M_G_ACT_N!J9T1!62!@baseboard_fab2_lib.baseboard_fab2(sch_1):page78_i13@mstr_sconn.sconn288_h44441003(chips)!SCONN288_H44441003_PIP-SCONN,HA!!!F196!ACT_N!!!!
S!M_G_ALERT_N!J9T1!208!@baseboard_fab2_lib.baseboard_fab2(sch_1):page78_i13@mstr_sconn.sconn288_h44441003(chips)!SCONN288_H44441003_PIP-SCONN,HA!!!F196!ALERT_N!!!!
S!M_G_BA<0>!J9T1!81!@baseboard_fab2_lib.baseboard_fab2(sch_1):page78_i13@mstr_sconn.sconn288_h44441003(chips)!SCONN288_H44441003_PIP-SCONN,HA!!!F196!BA(0)!!!!
S!M_G_BA<1>!J9T1!224!@baseboard_fab2_lib.baseboard_fab2(sch_1):page78_i13@mstr_sconn.sconn288_h44441003(chips)!SCONN288_H44441003_PIP-SCONN,HA!!!F196!BA(1)!!!!
S!M_G_BG<0>!J9T1!63!@baseboard_fab2_lib.baseboard_fab2(sch_1):page78_i13@mstr_sconn.sconn288_h44441003(chips)!SCONN288_H44441003_PIP-SCONN,HA!!!F196!BG(0)!!!!
S!M_G_BG<1>!J9T1!207!@baseboard_fab2_lib.baseboard_fab2(sch_1):page78_i13@mstr_sconn.sconn288_h44441003(chips)!SCONN288_H44441003_PIP-SCONN,HA!!!F196!BG(1)!!!!
S!M_G_C<2>!J9T1!235!@baseboard_fab2_lib.baseboard_fab2(sch_1):page78_i13@mstr_sconn.sconn288_h44441003(chips)!SCONN288_H44441003_PIP-SCONN,HA!!!F196!C(2)!!!!
S!M_G_ECC<0>!J9T1!49!@baseboard_fab2_lib.baseboard_fab2(sch_1):page78_i13@mstr_sconn.sconn288_h44441003(chips)!SCONN288_H44441003_PIP-SCONN,HA!!!F196!CB(0)!!!!
S!M_G_ECC<1>!J9T1!194!@baseboard_fab2_lib.baseboard_fab2(sch_1):page78_i13@mstr_sconn.sconn288_h44441003(chips)!SCONN288_H44441003_PIP-SCONN,HA!!!F196!CB(1)!!!!
S!M_G_ECC<2>!J9T1!56!@baseboard_fab2_lib.baseboard_fab2(sch_1):page78_i13@mstr_sconn.sconn288_h44441003(chips)!SCONN288_H44441003_PIP-SCONN,HA!!!F196!CB(2)!!!!
S!M_G_ECC<3>!J9T1!201!@baseboard_fab2_lib.baseboard_fab2(sch_1):page78_i13@mstr_sconn.sconn288_h44441003(chips)!SCONN288_H44441003_PIP-SCONN,HA!!!F196!CB(3)!!!!
S!M_G_ECC<4>!J9T1!47!@baseboard_fab2_lib.baseboard_fab2(sch_1):page78_i13@mstr_sconn.sconn288_h44441003(chips)!SCONN288_H44441003_PIP-SCONN,HA!!!F196!CB(4)!!!!
S!M_G_ECC<5>!J9T1!192!@baseboard_fab2_lib.baseboard_fab2(sch_1):page78_i13@mstr_sconn.sconn288_h44441003(chips)!SCONN288_H44441003_PIP-SCONN,HA!!!F196!CB(5)!!!!
S!M_G_ECC<6>!J9T1!54!@baseboard_fab2_lib.baseboard_fab2(sch_1):page78_i13@mstr_sconn.sconn288_h44441003(chips)!SCONN288_H44441003_PIP-SCONN,HA!!!F196!CB(6)!!!!
S!M_G_ECC<7>!J9T1!199!@baseboard_fab2_lib.baseboard_fab2(sch_1):page78_i13@mstr_sconn.sconn288_h44441003(chips)!SCONN288_H44441003_PIP-SCONN,HA!!!F196!CB(7)!!!!
S!M_G_CLK_DN<2>!J9T1!75!@baseboard_fab2_lib.baseboard_fab2(sch_1):page78_i13@mstr_sconn.sconn288_h44441003(chips)!SCONN288_H44441003_PIP-SCONN,HA!!!F196!CK0N!!!!
S!M_G_CLK_DP<2>!J9T1!74!@baseboard_fab2_lib.baseboard_fab2(sch_1):page78_i13@mstr_sconn.sconn288_h44441003(chips)!SCONN288_H44441003_PIP-SCONN,HA!!!F196!CK0P!!!!
S!M_G_CLK_DN<3>!J9T1!219!@baseboard_fab2_lib.baseboard_fab2(sch_1):page78_i13@mstr_sconn.sconn288_h44441003(chips)!SCONN288_H44441003_PIP-SCONN,HA!!!F196!CK1N!!!!
S!M_G_CLK_DP<3>!J9T1!218!@baseboard_fab2_lib.baseboard_fab2(sch_1):page78_i13@mstr_sconn.sconn288_h44441003(chips)!SCONN288_H44441003_PIP-SCONN,HA!!!F196!CK1P!!!!
S!M_G_CKE<2>!J9T1!60!@baseboard_fab2_lib.baseboard_fab2(sch_1):page78_i13@mstr_sconn.sconn288_h44441003(chips)!SCONN288_H44441003_PIP-SCONN,HA!!!F196!CKE(0)!!!!
S!M_G_CKE<3>!J9T1!203!@baseboard_fab2_lib.baseboard_fab2(sch_1):page78_i13@mstr_sconn.sconn288_h44441003(chips)!SCONN288_H44441003_PIP-SCONN,HA!!!F196!CKE(1)!!!!
S!M_G_DQ<0>!J9T1!5!@baseboard_fab2_lib.baseboard_fab2(sch_1):page78_i13@mstr_sconn.sconn288_h44441003(chips)!SCONN288_H44441003_PIP-SCONN,HA!!!F196!DQ(0)!!!!
S!M_G_DQ<10>!J9T1!23!@baseboard_fab2_lib.baseboard_fab2(sch_1):page78_i13@mstr_sconn.sconn288_h44441003(chips)!SCONN288_H44441003_PIP-SCONN,HA!!!F196!DQ(10)!!!!
S!M_G_DQ<11>!J9T1!168!@baseboard_fab2_lib.baseboard_fab2(sch_1):page78_i13@mstr_sconn.sconn288_h44441003(chips)!SCONN288_H44441003_PIP-SCONN,HA!!!F196!DQ(11)!!!!
S!M_G_DQ<12>!J9T1!14!@baseboard_fab2_lib.baseboard_fab2(sch_1):page78_i13@mstr_sconn.sconn288_h44441003(chips)!SCONN288_H44441003_PIP-SCONN,HA!!!F196!DQ(12)!!!!
S!M_G_DQ<13>!J9T1!159!@baseboard_fab2_lib.baseboard_fab2(sch_1):page78_i13@mstr_sconn.sconn288_h44441003(chips)!SCONN288_H44441003_PIP-SCONN,HA!!!F196!DQ(13)!!!!
S!M_G_DQ<14>!J9T1!21!@baseboard_fab2_lib.baseboard_fab2(sch_1):page78_i13@mstr_sconn.sconn288_h44441003(chips)!SCONN288_H44441003_PIP-SCONN,HA!!!F196!DQ(14)!!!!
S!M_G_DQ<15>!J9T1!166!@baseboard_fab2_lib.baseboard_fab2(sch_1):page78_i13@mstr_sconn.sconn288_h44441003(chips)!SCONN288_H44441003_PIP-SCONN,HA!!!F196!DQ(15)!!!!
S!M_G_DQ<16>!J9T1!27!@baseboard_fab2_lib.baseboard_fab2(sch_1):page78_i13@mstr_sconn.sconn288_h44441003(chips)!SCONN288_H44441003_PIP-SCONN,HA!!!F196!DQ(16)!!!!
S!M_G_DQ<17>!J9T1!172!@baseboard_fab2_lib.baseboard_fab2(sch_1):page78_i13@mstr_sconn.sconn288_h44441003(chips)!SCONN288_H44441003_PIP-SCONN,HA!!!F196!DQ(17)!!!!
S!M_G_DQ<18>!J9T1!34!@baseboard_fab2_lib.baseboard_fab2(sch_1):page78_i13@mstr_sconn.sconn288_h44441003(chips)!SCONN288_H44441003_PIP-SCONN,HA!!!F196!DQ(18)!!!!
S!M_G_DQ<19>!J9T1!179!@baseboard_fab2_lib.baseboard_fab2(sch_1):page78_i13@mstr_sconn.sconn288_h44441003(chips)!SCONN288_H44441003_PIP-SCONN,HA!!!F196!DQ(19)!!!!
S!M_G_DQ<1>!J9T1!150!@baseboard_fab2_lib.baseboard_fab2(sch_1):page78_i13@mstr_sconn.sconn288_h44441003(chips)!SCONN288_H44441003_PIP-SCONN,HA!!!F196!DQ(1)!!!!
S!M_G_DQ<20>!J9T1!25!@baseboard_fab2_lib.baseboard_fab2(sch_1):page78_i13@mstr_sconn.sconn288_h44441003(chips)!SCONN288_H44441003_PIP-SCONN,HA!!!F196!DQ(20)!!!!
S!M_G_DQ<21>!J9T1!170!@baseboard_fab2_lib.baseboard_fab2(sch_1):page78_i13@mstr_sconn.sconn288_h44441003(chips)!SCONN288_H44441003_PIP-SCONN,HA!!!F196!DQ(21)!!!!
S!M_G_DQ<22>!J9T1!32!@baseboard_fab2_lib.baseboard_fab2(sch_1):page78_i13@mstr_sconn.sconn288_h44441003(chips)!SCONN288_H44441003_PIP-SCONN,HA!!!F196!DQ(22)!!!!
S!M_G_DQ<23>!J9T1!177!@baseboard_fab2_lib.baseboard_fab2(sch_1):page78_i13@mstr_sconn.sconn288_h44441003(chips)!SCONN288_H44441003_PIP-SCONN,HA!!!F196!DQ(23)!!!!
S!M_G_DQ<24>!J9T1!38!@baseboard_fab2_lib.baseboard_fab2(sch_1):page78_i13@mstr_sconn.sconn288_h44441003(chips)!SCONN288_H44441003_PIP-SCONN,HA!!!F196!DQ(24)!!!!
S!M_G_DQ<25>!J9T1!183!@baseboard_fab2_lib.baseboard_fab2(sch_1):page78_i13@mstr_sconn.sconn288_h44441003(chips)!SCONN288_H44441003_PIP-SCONN,HA!!!F196!DQ(25)!!!!
S!M_G_DQ<26>!J9T1!45!@baseboard_fab2_lib.baseboard_fab2(sch_1):page78_i13@mstr_sconn.sconn288_h44441003(chips)!SCONN288_H44441003_PIP-SCONN,HA!!!F196!DQ(26)!!!!
S!M_G_DQ<27>!J9T1!190!@baseboard_fab2_lib.baseboard_fab2(sch_1):page78_i13@mstr_sconn.sconn288_h44441003(chips)!SCONN288_H44441003_PIP-SCONN,HA!!!F196!DQ(27)!!!!
S!M_G_DQ<28>!J9T1!36!@baseboard_fab2_lib.baseboard_fab2(sch_1):page78_i13@mstr_sconn.sconn288_h44441003(chips)!SCONN288_H44441003_PIP-SCONN,HA!!!F196!DQ(28)!!!!
S!M_G_DQ<29>!J9T1!181!@baseboard_fab2_lib.baseboard_fab2(sch_1):page78_i13@mstr_sconn.sconn288_h44441003(chips)!SCONN288_H44441003_PIP-SCONN,HA!!!F196!DQ(29)!!!!
S!M_G_DQ<2>!J9T1!12!@baseboard_fab2_lib.baseboard_fab2(sch_1):page78_i13@mstr_sconn.sconn288_h44441003(chips)!SCONN288_H44441003_PIP-SCONN,HA!!!F196!DQ(2)!!!!
S!M_G_DQ<30>!J9T1!43!@baseboard_fab2_lib.baseboard_fab2(sch_1):page78_i13@mstr_sconn.sconn288_h44441003(chips)!SCONN288_H44441003_PIP-SCONN,HA!!!F196!DQ(30)!!!!
S!M_G_DQ<31>!J9T1!188!@baseboard_fab2_lib.baseboard_fab2(sch_1):page78_i13@mstr_sconn.sconn288_h44441003(chips)!SCONN288_H44441003_PIP-SCONN,HA!!!F196!DQ(31)!!!!
S!M_G_DQ<32>!J9T1!97!@baseboard_fab2_lib.baseboard_fab2(sch_1):page78_i13@mstr_sconn.sconn288_h44441003(chips)!SCONN288_H44441003_PIP-SCONN,HA!!!F196!DQ(32)!!!!
S!M_G_DQ<33>!J9T1!242!@baseboard_fab2_lib.baseboard_fab2(sch_1):page78_i13@mstr_sconn.sconn288_h44441003(chips)!SCONN288_H44441003_PIP-SCONN,HA!!!F196!DQ(33)!!!!
S!M_G_DQ<34>!J9T1!104!@baseboard_fab2_lib.baseboard_fab2(sch_1):page78_i13@mstr_sconn.sconn288_h44441003(chips)!SCONN288_H44441003_PIP-SCONN,HA!!!F196!DQ(34)!!!!
S!M_G_DQ<35>!J9T1!249!@baseboard_fab2_lib.baseboard_fab2(sch_1):page78_i13@mstr_sconn.sconn288_h44441003(chips)!SCONN288_H44441003_PIP-SCONN,HA!!!F196!DQ(35)!!!!
S!M_G_DQ<36>!J9T1!95!@baseboard_fab2_lib.baseboard_fab2(sch_1):page78_i13@mstr_sconn.sconn288_h44441003(chips)!SCONN288_H44441003_PIP-SCONN,HA!!!F196!DQ(36)!!!!
S!M_G_DQ<37>!J9T1!240!@baseboard_fab2_lib.baseboard_fab2(sch_1):page78_i13@mstr_sconn.sconn288_h44441003(chips)!SCONN288_H44441003_PIP-SCONN,HA!!!F196!DQ(37)!!!!
S!M_G_DQ<38>!J9T1!102!@baseboard_fab2_lib.baseboard_fab2(sch_1):page78_i13@mstr_sconn.sconn288_h44441003(chips)!SCONN288_H44441003_PIP-SCONN,HA!!!F196!DQ(38)!!!!
S!M_G_DQ<39>!J9T1!247!@baseboard_fab2_lib.baseboard_fab2(sch_1):page78_i13@mstr_sconn.sconn288_h44441003(chips)!SCONN288_H44441003_PIP-SCONN,HA!!!F196!DQ(39)!!!!
S!M_G_DQ<3>!J9T1!157!@baseboard_fab2_lib.baseboard_fab2(sch_1):page78_i13@mstr_sconn.sconn288_h44441003(chips)!SCONN288_H44441003_PIP-SCONN,HA!!!F196!DQ(3)!!!!
S!M_G_DQ<40>!J9T1!108!@baseboard_fab2_lib.baseboard_fab2(sch_1):page78_i13@mstr_sconn.sconn288_h44441003(chips)!SCONN288_H44441003_PIP-SCONN,HA!!!F196!DQ(40)!!!!
S!M_G_DQ<41>!J9T1!253!@baseboard_fab2_lib.baseboard_fab2(sch_1):page78_i13@mstr_sconn.sconn288_h44441003(chips)!SCONN288_H44441003_PIP-SCONN,HA!!!F196!DQ(41)!!!!
S!M_G_DQ<42>!J9T1!115!@baseboard_fab2_lib.baseboard_fab2(sch_1):page78_i13@mstr_sconn.sconn288_h44441003(chips)!SCONN288_H44441003_PIP-SCONN,HA!!!F196!DQ(42)!!!!
S!M_G_DQ<43>!J9T1!260!@baseboard_fab2_lib.baseboard_fab2(sch_1):page78_i13@mstr_sconn.sconn288_h44441003(chips)!SCONN288_H44441003_PIP-SCONN,HA!!!F196!DQ(43)!!!!
S!M_G_DQ<44>!J9T1!106!@baseboard_fab2_lib.baseboard_fab2(sch_1):page78_i13@mstr_sconn.sconn288_h44441003(chips)!SCONN288_H44441003_PIP-SCONN,HA!!!F196!DQ(44)!!!!
S!M_G_DQ<45>!J9T1!251!@baseboard_fab2_lib.baseboard_fab2(sch_1):page78_i13@mstr_sconn.sconn288_h44441003(chips)!SCONN288_H44441003_PIP-SCONN,HA!!!F196!DQ(45)!!!!
S!M_G_DQ<46>!J9T1!113!@baseboard_fab2_lib.baseboard_fab2(sch_1):page78_i13@mstr_sconn.sconn288_h44441003(chips)!SCONN288_H44441003_PIP-SCONN,HA!!!F196!DQ(46)!!!!
S!M_G_DQ<47>!J9T1!258!@baseboard_fab2_lib.baseboard_fab2(sch_1):page78_i13@mstr_sconn.sconn288_h44441003(chips)!SCONN288_H44441003_PIP-SCONN,HA!!!F196!DQ(47)!!!!
S!M_G_DQ<48>!J9T1!119!@baseboard_fab2_lib.baseboard_fab2(sch_1):page78_i13@mstr_sconn.sconn288_h44441003(chips)!SCONN288_H44441003_PIP-SCONN,HA!!!F196!DQ(48)!!!!
S!M_G_DQ<49>!J9T1!264!@baseboard_fab2_lib.baseboard_fab2(sch_1):page78_i13@mstr_sconn.sconn288_h44441003(chips)!SCONN288_H44441003_PIP-SCONN,HA!!!F196!DQ(49)!!!!
S!M_G_DQ<4>!J9T1!3!@baseboard_fab2_lib.baseboard_fab2(sch_1):page78_i13@mstr_sconn.sconn288_h44441003(chips)!SCONN288_H44441003_PIP-SCONN,HA!!!F196!DQ(4)!!!!
S!M_G_DQ<50>!J9T1!126!@baseboard_fab2_lib.baseboard_fab2(sch_1):page78_i13@mstr_sconn.sconn288_h44441003(chips)!SCONN288_H44441003_PIP-SCONN,HA!!!F196!DQ(50)!!!!
S!M_G_DQ<51>!J9T1!271!@baseboard_fab2_lib.baseboard_fab2(sch_1):page78_i13@mstr_sconn.sconn288_h44441003(chips)!SCONN288_H44441003_PIP-SCONN,HA!!!F196!DQ(51)!!!!
S!M_G_DQ<52>!J9T1!117!@baseboard_fab2_lib.baseboard_fab2(sch_1):page78_i13@mstr_sconn.sconn288_h44441003(chips)!SCONN288_H44441003_PIP-SCONN,HA!!!F196!DQ(52)!!!!
S!M_G_DQ<53>!J9T1!262!@baseboard_fab2_lib.baseboard_fab2(sch_1):page78_i13@mstr_sconn.sconn288_h44441003(chips)!SCONN288_H44441003_PIP-SCONN,HA!!!F196!DQ(53)!!!!
S!M_G_DQ<54>!J9T1!124!@baseboard_fab2_lib.baseboard_fab2(sch_1):page78_i13@mstr_sconn.sconn288_h44441003(chips)!SCONN288_H44441003_PIP-SCONN,HA!!!F196!DQ(54)!!!!
S!M_G_DQ<55>!J9T1!269!@baseboard_fab2_lib.baseboard_fab2(sch_1):page78_i13@mstr_sconn.sconn288_h44441003(chips)!SCONN288_H44441003_PIP-SCONN,HA!!!F196!DQ(55)!!!!
S!M_G_DQ<56>!J9T1!130!@baseboard_fab2_lib.baseboard_fab2(sch_1):page78_i13@mstr_sconn.sconn288_h44441003(chips)!SCONN288_H44441003_PIP-SCONN,HA!!!F196!DQ(56)!!!!
S!M_G_DQ<57>!J9T1!275!@baseboard_fab2_lib.baseboard_fab2(sch_1):page78_i13@mstr_sconn.sconn288_h44441003(chips)!SCONN288_H44441003_PIP-SCONN,HA!!!F196!DQ(57)!!!!
S!M_G_DQ<58>!J9T1!137!@baseboard_fab2_lib.baseboard_fab2(sch_1):page78_i13@mstr_sconn.sconn288_h44441003(chips)!SCONN288_H44441003_PIP-SCONN,HA!!!F196!DQ(58)!!!!
S!M_G_DQ<59>!J9T1!282!@baseboard_fab2_lib.baseboard_fab2(sch_1):page78_i13@mstr_sconn.sconn288_h44441003(chips)!SCONN288_H44441003_PIP-SCONN,HA!!!F196!DQ(59)!!!!
S!M_G_DQ<5>!J9T1!148!@baseboard_fab2_lib.baseboard_fab2(sch_1):page78_i13@mstr_sconn.sconn288_h44441003(chips)!SCONN288_H44441003_PIP-SCONN,HA!!!F196!DQ(5)!!!!
S!M_G_DQ<60>!J9T1!128!@baseboard_fab2_lib.baseboard_fab2(sch_1):page78_i13@mstr_sconn.sconn288_h44441003(chips)!SCONN288_H44441003_PIP-SCONN,HA!!!F196!DQ(60)!!!!
S!M_G_DQ<61>!J9T1!273!@baseboard_fab2_lib.baseboard_fab2(sch_1):page78_i13@mstr_sconn.sconn288_h44441003(chips)!SCONN288_H44441003_PIP-SCONN,HA!!!F196!DQ(61)!!!!
S!M_G_DQ<62>!J9T1!135!@baseboard_fab2_lib.baseboard_fab2(sch_1):page78_i13@mstr_sconn.sconn288_h44441003(chips)!SCONN288_H44441003_PIP-SCONN,HA!!!F196!DQ(62)!!!!
S!M_G_DQ<63>!J9T1!280!@baseboard_fab2_lib.baseboard_fab2(sch_1):page78_i13@mstr_sconn.sconn288_h44441003(chips)!SCONN288_H44441003_PIP-SCONN,HA!!!F196!DQ(63)!!!!
S!M_G_DQ<6>!J9T1!10!@baseboard_fab2_lib.baseboard_fab2(sch_1):page78_i13@mstr_sconn.sconn288_h44441003(chips)!SCONN288_H44441003_PIP-SCONN,HA!!!F196!DQ(6)!!!!
S!M_G_DQ<7>!J9T1!155!@baseboard_fab2_lib.baseboard_fab2(sch_1):page78_i13@mstr_sconn.sconn288_h44441003(chips)!SCONN288_H44441003_PIP-SCONN,HA!!!F196!DQ(7)!!!!
S!M_G_DQ<8>!J9T1!16!@baseboard_fab2_lib.baseboard_fab2(sch_1):page78_i13@mstr_sconn.sconn288_h44441003(chips)!SCONN288_H44441003_PIP-SCONN,HA!!!F196!DQ(8)!!!!
S!M_G_DQ<9>!J9T1!161!@baseboard_fab2_lib.baseboard_fab2(sch_1):page78_i13@mstr_sconn.sconn288_h44441003(chips)!SCONN288_H44441003_PIP-SCONN,HA!!!F196!DQ(9)!!!!
S!FM_DIMM_EVENT_COD_N!J9T1!78!@baseboard_fab2_lib.baseboard_fab2(sch_1):page78_i13@mstr_sconn.sconn288_h44441003(chips)!SCONN288_H44441003_PIP-SCONN,HA!!!F196!EVENT_N!!!!
S!M_G_ODT<2>!J9T1!87!@baseboard_fab2_lib.baseboard_fab2(sch_1):page78_i13@mstr_sconn.sconn288_h44441003(chips)!SCONN288_H44441003_PIP-SCONN,HA!!!F196!ODT(0)!!!!
S!M_G_ODT<3>!J9T1!91!@baseboard_fab2_lib.baseboard_fab2(sch_1):page78_i13@mstr_sconn.sconn288_h44441003(chips)!SCONN288_H44441003_PIP-SCONN,HA!!!F196!ODT(1)!!!!
S!M_G_PAR!J9T1!222!@baseboard_fab2_lib.baseboard_fab2(sch_1):page78_i13@mstr_sconn.sconn288_h44441003(chips)!SCONN288_H44441003_PIP-SCONN,HA!!!F196!PAR!!!!
S!M_GHJ_RST_N!J9T1!58!@baseboard_fab2_lib.baseboard_fab2(sch_1):page78_i13@mstr_sconn.sconn288_h44441003(chips)!SCONN288_H44441003_PIP-SCONN,HA!!!F196!RESET_N!!!!
S!TP_CH_G_DIMM0_RFU_0!J9T1!205!@baseboard_fab2_lib.baseboard_fab2(sch_1):page78_i13@mstr_sconn.sconn288_h44441003(chips)!SCONN288_H44441003_PIP-SCONN,HA!!!F196!RFU(0)!!!!
S!TP_CH_G_DIMM0_RFU_1!J9T1!227!@baseboard_fab2_lib.baseboard_fab2(sch_1):page78_i13@mstr_sconn.sconn288_h44441003(chips)!SCONN288_H44441003_PIP-SCONN,HA!!!F196!RFU(1)!!!!
S!TP_CH_G_DIMM0_RFU_2!J9T1!144!@baseboard_fab2_lib.baseboard_fab2(sch_1):page78_i13@mstr_sconn.sconn288_h44441003(chips)!SCONN288_H44441003_PIP-SCONN,HA!!!F196!RFU(2)!!!!
S!M_G_CS_N<4>!J9T1!84!@baseboard_fab2_lib.baseboard_fab2(sch_1):page78_i13@mstr_sconn.sconn288_h44441003(chips)!SCONN288_H44441003_PIP-SCONN,HA!!!F196!S0_N!!!!
S!M_G_CS_N<5>!J9T1!89!@baseboard_fab2_lib.baseboard_fab2(sch_1):page78_i13@mstr_sconn.sconn288_h44441003(chips)!SCONN288_H44441003_PIP-SCONN,HA!!!F196!S1_N!!!!
S!M_G_CS_N<6>!J9T1!93!@baseboard_fab2_lib.baseboard_fab2(sch_1):page78_i13@mstr_sconn.sconn288_h44441003(chips)!SCONN288_H44441003_PIP-SCONN,HA!!!F196!S2_N_C(0)!!!!
S!M_G_CS_N<7>!J9T1!237!@baseboard_fab2_lib.baseboard_fab2(sch_1):page78_i13@mstr_sconn.sconn288_h44441003(chips)!SCONN288_H44441003_PIP-SCONN,HA!!!F196!S3_N_C(1)!!!!
S!PVPP_GHJ!J9T1!139!@baseboard_fab2_lib.baseboard_fab2(sch_1):page78_i13@mstr_sconn.sconn288_h44441003(chips)!SCONN288_H44441003_PIP-SCONN,HA!!!F196!SA(0)!!!!
S!GND!J9T1!140!@baseboard_fab2_lib.baseboard_fab2(sch_1):page78_i13@mstr_sconn.sconn288_h44441003(chips)!SCONN288_H44441003_PIP-SCONN,HA!!!F196!SA(1)!!!!
S!GND!J9T1!238!@baseboard_fab2_lib.baseboard_fab2(sch_1):page78_i13@mstr_sconn.sconn288_h44441003(chips)!SCONN288_H44441003_PIP-SCONN,HA!!!F196!SA(2)!!!!
S!FM_ADR_COMPLETE_GHJ_N!J9T1!230!@baseboard_fab2_lib.baseboard_fab2(sch_1):page78_i13@mstr_sconn.sconn288_h44441003(chips)!SCONN288_H44441003_PIP-SCONN,HA!!!F196!SAVE_N_NC!!!!
S!SMB_DDR_GHJ_VPP_SCL!J9T1!141!@baseboard_fab2_lib.baseboard_fab2(sch_1):page78_i13@mstr_sconn.sconn288_h44441003(chips)!SCONN288_H44441003_PIP-SCONN,HA!!!F196!SCL!!!!
S!SMB_DDR_GHJ_VPP_SDA!J9T1!285!@baseboard_fab2_lib.baseboard_fab2(sch_1):page78_i13@mstr_sconn.sconn288_h44441003(chips)!SCONN288_H44441003_PIP-SCONN,HA!!!F196!SDA!!!!
S!PVPP_GHJ!J9T1!284!@baseboard_fab2_lib.baseboard_fab2(sch_1):page78_i13@mstr_sconn.sconn288_h44441003(chips)!SCONN288_H44441003_PIP-SCONN,HA!!!F196!VDDSPD!!!!
S!M_G_VREF!J9T1!146!@baseboard_fab2_lib.baseboard_fab2(sch_1):page78_i13@mstr_sconn.sconn288_h44441003(chips)!SCONN288_H44441003_PIP-SCONN,HA!!!F196!VREFCA!!!!
S!M_G_DQS_DN<0>!J9T1!152!@baseboard_fab2_lib.baseboard_fab2(sch_1):page78_i120@mstr_sconn.sconn288_h44441003(chips)!SCONN288_H44441003_PIP-SCONN,HA!!!F195!DQS0N!!!!
S!M_G_DQS_DP<0>!J9T1!153!@baseboard_fab2_lib.baseboard_fab2(sch_1):page78_i120@mstr_sconn.sconn288_h44441003(chips)!SCONN288_H44441003_PIP-SCONN,HA!!!F195!DQS0P!!!!
S!M_G_DQS_DN<10>!J9T1!19!@baseboard_fab2_lib.baseboard_fab2(sch_1):page78_i120@mstr_sconn.sconn288_h44441003(chips)!SCONN288_H44441003_PIP-SCONN,HA!!!F195!DQS10N!!!!
S!M_G_DQS_DP<10>!J9T1!18!@baseboard_fab2_lib.baseboard_fab2(sch_1):page78_i120@mstr_sconn.sconn288_h44441003(chips)!SCONN288_H44441003_PIP-SCONN,HA!!!F195!DQS10P!!!!
S!M_G_DQS_DN<11>!J9T1!30!@baseboard_fab2_lib.baseboard_fab2(sch_1):page78_i120@mstr_sconn.sconn288_h44441003(chips)!SCONN288_H44441003_PIP-SCONN,HA!!!F195!DQS11N!!!!
S!M_G_DQS_DP<11>!J9T1!29!@baseboard_fab2_lib.baseboard_fab2(sch_1):page78_i120@mstr_sconn.sconn288_h44441003(chips)!SCONN288_H44441003_PIP-SCONN,HA!!!F195!DQS11P!!!!
S!M_G_DQS_DN<12>!J9T1!41!@baseboard_fab2_lib.baseboard_fab2(sch_1):page78_i120@mstr_sconn.sconn288_h44441003(chips)!SCONN288_H44441003_PIP-SCONN,HA!!!F195!DQS12N!!!!
S!M_G_DQS_DP<12>!J9T1!40!@baseboard_fab2_lib.baseboard_fab2(sch_1):page78_i120@mstr_sconn.sconn288_h44441003(chips)!SCONN288_H44441003_PIP-SCONN,HA!!!F195!DQS12P!!!!
S!M_G_DQS_DN<13>!J9T1!100!@baseboard_fab2_lib.baseboard_fab2(sch_1):page78_i120@mstr_sconn.sconn288_h44441003(chips)!SCONN288_H44441003_PIP-SCONN,HA!!!F195!DQS13N!!!!
S!M_G_DQS_DP<13>!J9T1!99!@baseboard_fab2_lib.baseboard_fab2(sch_1):page78_i120@mstr_sconn.sconn288_h44441003(chips)!SCONN288_H44441003_PIP-SCONN,HA!!!F195!DQS13P!!!!
S!M_G_DQS_DN<14>!J9T1!111!@baseboard_fab2_lib.baseboard_fab2(sch_1):page78_i120@mstr_sconn.sconn288_h44441003(chips)!SCONN288_H44441003_PIP-SCONN,HA!!!F195!DQS14N!!!!
S!M_G_DQS_DP<14>!J9T1!110!@baseboard_fab2_lib.baseboard_fab2(sch_1):page78_i120@mstr_sconn.sconn288_h44441003(chips)!SCONN288_H44441003_PIP-SCONN,HA!!!F195!DQS14P!!!!
S!M_G_DQS_DN<15>!J9T1!122!@baseboard_fab2_lib.baseboard_fab2(sch_1):page78_i120@mstr_sconn.sconn288_h44441003(chips)!SCONN288_H44441003_PIP-SCONN,HA!!!F195!DQS15N!!!!
S!M_G_DQS_DP<15>!J9T1!121!@baseboard_fab2_lib.baseboard_fab2(sch_1):page78_i120@mstr_sconn.sconn288_h44441003(chips)!SCONN288_H44441003_PIP-SCONN,HA!!!F195!DQS15P!!!!
S!M_G_DQS_DN<16>!J9T1!133!@baseboard_fab2_lib.baseboard_fab2(sch_1):page78_i120@mstr_sconn.sconn288_h44441003(chips)!SCONN288_H44441003_PIP-SCONN,HA!!!F195!DQS16N!!!!
S!M_G_DQS_DP<16>!J9T1!132!@baseboard_fab2_lib.baseboard_fab2(sch_1):page78_i120@mstr_sconn.sconn288_h44441003(chips)!SCONN288_H44441003_PIP-SCONN,HA!!!F195!DQS16P!!!!
S!M_G_DQS_DN<17>!J9T1!52!@baseboard_fab2_lib.baseboard_fab2(sch_1):page78_i120@mstr_sconn.sconn288_h44441003(chips)!SCONN288_H44441003_PIP-SCONN,HA!!!F195!DQS17N!!!!
S!M_G_DQS_DP<17>!J9T1!51!@baseboard_fab2_lib.baseboard_fab2(sch_1):page78_i120@mstr_sconn.sconn288_h44441003(chips)!SCONN288_H44441003_PIP-SCONN,HA!!!F195!DQS17P!!!!
S!M_G_DQS_DN<1>!J9T1!163!@baseboard_fab2_lib.baseboard_fab2(sch_1):page78_i120@mstr_sconn.sconn288_h44441003(chips)!SCONN288_H44441003_PIP-SCONN,HA!!!F195!DQS1N!!!!
S!M_G_DQS_DP<1>!J9T1!164!@baseboard_fab2_lib.baseboard_fab2(sch_1):page78_i120@mstr_sconn.sconn288_h44441003(chips)!SCONN288_H44441003_PIP-SCONN,HA!!!F195!DQS1P!!!!
S!M_G_DQS_DN<2>!J9T1!174!@baseboard_fab2_lib.baseboard_fab2(sch_1):page78_i120@mstr_sconn.sconn288_h44441003(chips)!SCONN288_H44441003_PIP-SCONN,HA!!!F195!DQS2N!!!!
S!M_G_DQS_DP<2>!J9T1!175!@baseboard_fab2_lib.baseboard_fab2(sch_1):page78_i120@mstr_sconn.sconn288_h44441003(chips)!SCONN288_H44441003_PIP-SCONN,HA!!!F195!DQS2P!!!!
S!M_G_DQS_DN<3>!J9T1!185!@baseboard_fab2_lib.baseboard_fab2(sch_1):page78_i120@mstr_sconn.sconn288_h44441003(chips)!SCONN288_H44441003_PIP-SCONN,HA!!!F195!DQS3N!!!!
S!M_G_DQS_DP<3>!J9T1!186!@baseboard_fab2_lib.baseboard_fab2(sch_1):page78_i120@mstr_sconn.sconn288_h44441003(chips)!SCONN288_H44441003_PIP-SCONN,HA!!!F195!DQS3P!!!!
S!M_G_DQS_DN<4>!J9T1!244!@baseboard_fab2_lib.baseboard_fab2(sch_1):page78_i120@mstr_sconn.sconn288_h44441003(chips)!SCONN288_H44441003_PIP-SCONN,HA!!!F195!DQS4N!!!!
S!M_G_DQS_DP<4>!J9T1!245!@baseboard_fab2_lib.baseboard_fab2(sch_1):page78_i120@mstr_sconn.sconn288_h44441003(chips)!SCONN288_H44441003_PIP-SCONN,HA!!!F195!DQS4P!!!!
S!M_G_DQS_DN<5>!J9T1!255!@baseboard_fab2_lib.baseboard_fab2(sch_1):page78_i120@mstr_sconn.sconn288_h44441003(chips)!SCONN288_H44441003_PIP-SCONN,HA!!!F195!DQS5N!!!!
S!M_G_DQS_DP<5>!J9T1!256!@baseboard_fab2_lib.baseboard_fab2(sch_1):page78_i120@mstr_sconn.sconn288_h44441003(chips)!SCONN288_H44441003_PIP-SCONN,HA!!!F195!DQS5P!!!!
S!M_G_DQS_DN<6>!J9T1!266!@baseboard_fab2_lib.baseboard_fab2(sch_1):page78_i120@mstr_sconn.sconn288_h44441003(chips)!SCONN288_H44441003_PIP-SCONN,HA!!!F195!DQS6N!!!!
S!M_G_DQS_DP<6>!J9T1!267!@baseboard_fab2_lib.baseboard_fab2(sch_1):page78_i120@mstr_sconn.sconn288_h44441003(chips)!SCONN288_H44441003_PIP-SCONN,HA!!!F195!DQS6P!!!!
S!M_G_DQS_DN<7>!J9T1!277!@baseboard_fab2_lib.baseboard_fab2(sch_1):page78_i120@mstr_sconn.sconn288_h44441003(chips)!SCONN288_H44441003_PIP-SCONN,HA!!!F195!DQS7N!!!!
S!M_G_DQS_DP<7>!J9T1!278!@baseboard_fab2_lib.baseboard_fab2(sch_1):page78_i120@mstr_sconn.sconn288_h44441003(chips)!SCONN288_H44441003_PIP-SCONN,HA!!!F195!DQS7P!!!!
S!M_G_DQS_DN<8>!J9T1!196!@baseboard_fab2_lib.baseboard_fab2(sch_1):page78_i120@mstr_sconn.sconn288_h44441003(chips)!SCONN288_H44441003_PIP-SCONN,HA!!!F195!DQS8N!!!!
S!M_G_DQS_DP<8>!J9T1!197!@baseboard_fab2_lib.baseboard_fab2(sch_1):page78_i120@mstr_sconn.sconn288_h44441003(chips)!SCONN288_H44441003_PIP-SCONN,HA!!!F195!DQS8P!!!!
S!M_G_DQS_DN<9>!J9T1!8!@baseboard_fab2_lib.baseboard_fab2(sch_1):page78_i120@mstr_sconn.sconn288_h44441003(chips)!SCONN288_H44441003_PIP-SCONN,HA!!!F195!DQS9N!!!!
S!M_G_DQS_DP<9>!J9T1!7!@baseboard_fab2_lib.baseboard_fab2(sch_1):page78_i120@mstr_sconn.sconn288_h44441003(chips)!SCONN288_H44441003_PIP-SCONN,HA!!!F195!DQS9P!!!!
S!GND!J9T1!283!@baseboard_fab2_lib.baseboard_fab2(sch_1):page78_i144@mstr_sconn.sconn288_h44441003(chips)!SCONN288_H44441003_PIP-SCONN,HA!!!F194!VSS(0)!!!!
S!GND!J9T1!261!@baseboard_fab2_lib.baseboard_fab2(sch_1):page78_i144@mstr_sconn.sconn288_h44441003(chips)!SCONN288_H44441003_PIP-SCONN,HA!!!F194!VSS(10)!!!!
S!GND!J9T1!259!@baseboard_fab2_lib.baseboard_fab2(sch_1):page78_i144@mstr_sconn.sconn288_h44441003(chips)!SCONN288_H44441003_PIP-SCONN,HA!!!F194!VSS(11)!!!!
S!GND!J9T1!257!@baseboard_fab2_lib.baseboard_fab2(sch_1):page78_i144@mstr_sconn.sconn288_h44441003(chips)!SCONN288_H44441003_PIP-SCONN,HA!!!F194!VSS(12)!!!!
S!GND!J9T1!254!@baseboard_fab2_lib.baseboard_fab2(sch_1):page78_i144@mstr_sconn.sconn288_h44441003(chips)!SCONN288_H44441003_PIP-SCONN,HA!!!F194!VSS(13)!!!!
S!GND!J9T1!252!@baseboard_fab2_lib.baseboard_fab2(sch_1):page78_i144@mstr_sconn.sconn288_h44441003(chips)!SCONN288_H44441003_PIP-SCONN,HA!!!F194!VSS(14)!!!!
S!GND!J9T1!250!@baseboard_fab2_lib.baseboard_fab2(sch_1):page78_i144@mstr_sconn.sconn288_h44441003(chips)!SCONN288_H44441003_PIP-SCONN,HA!!!F194!VSS(15)!!!!
S!GND!J9T1!248!@baseboard_fab2_lib.baseboard_fab2(sch_1):page78_i144@mstr_sconn.sconn288_h44441003(chips)!SCONN288_H44441003_PIP-SCONN,HA!!!F194!VSS(16)!!!!
S!GND!J9T1!246!@baseboard_fab2_lib.baseboard_fab2(sch_1):page78_i144@mstr_sconn.sconn288_h44441003(chips)!SCONN288_H44441003_PIP-SCONN,HA!!!F194!VSS(17)!!!!
S!GND!J9T1!243!@baseboard_fab2_lib.baseboard_fab2(sch_1):page78_i144@mstr_sconn.sconn288_h44441003(chips)!SCONN288_H44441003_PIP-SCONN,HA!!!F194!VSS(18)!!!!
S!GND!J9T1!241!@baseboard_fab2_lib.baseboard_fab2(sch_1):page78_i144@mstr_sconn.sconn288_h44441003(chips)!SCONN288_H44441003_PIP-SCONN,HA!!!F194!VSS(19)!!!!
S!GND!J9T1!281!@baseboard_fab2_lib.baseboard_fab2(sch_1):page78_i144@mstr_sconn.sconn288_h44441003(chips)!SCONN288_H44441003_PIP-SCONN,HA!!!F194!VSS(1)!!!!
S!GND!J9T1!239!@baseboard_fab2_lib.baseboard_fab2(sch_1):page78_i144@mstr_sconn.sconn288_h44441003(chips)!SCONN288_H44441003_PIP-SCONN,HA!!!F194!VSS(20)!!!!
S!GND!J9T1!202!@baseboard_fab2_lib.baseboard_fab2(sch_1):page78_i144@mstr_sconn.sconn288_h44441003(chips)!SCONN288_H44441003_PIP-SCONN,HA!!!F194!VSS(21)!!!!
S!GND!J9T1!200!@baseboard_fab2_lib.baseboard_fab2(sch_1):page78_i144@mstr_sconn.sconn288_h44441003(chips)!SCONN288_H44441003_PIP-SCONN,HA!!!F194!VSS(22)!!!!
S!GND!J9T1!198!@baseboard_fab2_lib.baseboard_fab2(sch_1):page78_i144@mstr_sconn.sconn288_h44441003(chips)!SCONN288_H44441003_PIP-SCONN,HA!!!F194!VSS(23)!!!!
S!GND!J9T1!195!@baseboard_fab2_lib.baseboard_fab2(sch_1):page78_i144@mstr_sconn.sconn288_h44441003(chips)!SCONN288_H44441003_PIP-SCONN,HA!!!F194!VSS(24)!!!!
S!GND!J9T1!193!@baseboard_fab2_lib.baseboard_fab2(sch_1):page78_i144@mstr_sconn.sconn288_h44441003(chips)!SCONN288_H44441003_PIP-SCONN,HA!!!F194!VSS(25)!!!!
S!GND!J9T1!191!@baseboard_fab2_lib.baseboard_fab2(sch_1):page78_i144@mstr_sconn.sconn288_h44441003(chips)!SCONN288_H44441003_PIP-SCONN,HA!!!F194!VSS(26)!!!!
S!GND!J9T1!189!@baseboard_fab2_lib.baseboard_fab2(sch_1):page78_i144@mstr_sconn.sconn288_h44441003(chips)!SCONN288_H44441003_PIP-SCONN,HA!!!F194!VSS(27)!!!!
S!GND!J9T1!187!@baseboard_fab2_lib.baseboard_fab2(sch_1):page78_i144@mstr_sconn.sconn288_h44441003(chips)!SCONN288_H44441003_PIP-SCONN,HA!!!F194!VSS(28)!!!!
S!GND!J9T1!184!@baseboard_fab2_lib.baseboard_fab2(sch_1):page78_i144@mstr_sconn.sconn288_h44441003(chips)!SCONN288_H44441003_PIP-SCONN,HA!!!F194!VSS(29)!!!!
S!GND!J9T1!279!@baseboard_fab2_lib.baseboard_fab2(sch_1):page78_i144@mstr_sconn.sconn288_h44441003(chips)!SCONN288_H44441003_PIP-SCONN,HA!!!F194!VSS(2)!!!!
S!GND!J9T1!182!@baseboard_fab2_lib.baseboard_fab2(sch_1):page78_i144@mstr_sconn.sconn288_h44441003(chips)!SCONN288_H44441003_PIP-SCONN,HA!!!F194!VSS(30)!!!!
S!GND!J9T1!180!@baseboard_fab2_lib.baseboard_fab2(sch_1):page78_i144@mstr_sconn.sconn288_h44441003(chips)!SCONN288_H44441003_PIP-SCONN,HA!!!F194!VSS(31)!!!!
S!GND!J9T1!178!@baseboard_fab2_lib.baseboard_fab2(sch_1):page78_i144@mstr_sconn.sconn288_h44441003(chips)!SCONN288_H44441003_PIP-SCONN,HA!!!F194!VSS(32)!!!!
S!GND!J9T1!176!@baseboard_fab2_lib.baseboard_fab2(sch_1):page78_i144@mstr_sconn.sconn288_h44441003(chips)!SCONN288_H44441003_PIP-SCONN,HA!!!F194!VSS(33)!!!!
S!GND!J9T1!173!@baseboard_fab2_lib.baseboard_fab2(sch_1):page78_i144@mstr_sconn.sconn288_h44441003(chips)!SCONN288_H44441003_PIP-SCONN,HA!!!F194!VSS(34)!!!!
S!GND!J9T1!171!@baseboard_fab2_lib.baseboard_fab2(sch_1):page78_i144@mstr_sconn.sconn288_h44441003(chips)!SCONN288_H44441003_PIP-SCONN,HA!!!F194!VSS(35)!!!!
S!GND!J9T1!169!@baseboard_fab2_lib.baseboard_fab2(sch_1):page78_i144@mstr_sconn.sconn288_h44441003(chips)!SCONN288_H44441003_PIP-SCONN,HA!!!F194!VSS(36)!!!!
S!GND!J9T1!167!@baseboard_fab2_lib.baseboard_fab2(sch_1):page78_i144@mstr_sconn.sconn288_h44441003(chips)!SCONN288_H44441003_PIP-SCONN,HA!!!F194!VSS(37)!!!!
S!GND!J9T1!165!@baseboard_fab2_lib.baseboard_fab2(sch_1):page78_i144@mstr_sconn.sconn288_h44441003(chips)!SCONN288_H44441003_PIP-SCONN,HA!!!F194!VSS(38)!!!!
S!GND!J9T1!162!@baseboard_fab2_lib.baseboard_fab2(sch_1):page78_i144@mstr_sconn.sconn288_h44441003(chips)!SCONN288_H44441003_PIP-SCONN,HA!!!F194!VSS(39)!!!!
S!GND!J9T1!276!@baseboard_fab2_lib.baseboard_fab2(sch_1):page78_i144@mstr_sconn.sconn288_h44441003(chips)!SCONN288_H44441003_PIP-SCONN,HA!!!F194!VSS(3)!!!!
S!GND!J9T1!160!@baseboard_fab2_lib.baseboard_fab2(sch_1):page78_i144@mstr_sconn.sconn288_h44441003(chips)!SCONN288_H44441003_PIP-SCONN,HA!!!F194!VSS(40)!!!!
S!GND!J9T1!158!@baseboard_fab2_lib.baseboard_fab2(sch_1):page78_i144@mstr_sconn.sconn288_h44441003(chips)!SCONN288_H44441003_PIP-SCONN,HA!!!F194!VSS(41)!!!!
S!GND!J9T1!156!@baseboard_fab2_lib.baseboard_fab2(sch_1):page78_i144@mstr_sconn.sconn288_h44441003(chips)!SCONN288_H44441003_PIP-SCONN,HA!!!F194!VSS(42)!!!!
S!GND!J9T1!154!@baseboard_fab2_lib.baseboard_fab2(sch_1):page78_i144@mstr_sconn.sconn288_h44441003(chips)!SCONN288_H44441003_PIP-SCONN,HA!!!F194!VSS(43)!!!!
S!GND!J9T1!151!@baseboard_fab2_lib.baseboard_fab2(sch_1):page78_i144@mstr_sconn.sconn288_h44441003(chips)!SCONN288_H44441003_PIP-SCONN,HA!!!F194!VSS(44)!!!!
S!GND!J9T1!149!@baseboard_fab2_lib.baseboard_fab2(sch_1):page78_i144@mstr_sconn.sconn288_h44441003(chips)!SCONN288_H44441003_PIP-SCONN,HA!!!F194!VSS(45)!!!!
S!GND!J9T1!147!@baseboard_fab2_lib.baseboard_fab2(sch_1):page78_i144@mstr_sconn.sconn288_h44441003(chips)!SCONN288_H44441003_PIP-SCONN,HA!!!F194!VSS(46)!!!!
S!GND!J9T1!138!@baseboard_fab2_lib.baseboard_fab2(sch_1):page78_i144@mstr_sconn.sconn288_h44441003(chips)!SCONN288_H44441003_PIP-SCONN,HA!!!F194!VSS(47)!!!!
S!GND!J9T1!136!@baseboard_fab2_lib.baseboard_fab2(sch_1):page78_i144@mstr_sconn.sconn288_h44441003(chips)!SCONN288_H44441003_PIP-SCONN,HA!!!F194!VSS(48)!!!!
S!GND!J9T1!134!@baseboard_fab2_lib.baseboard_fab2(sch_1):page78_i144@mstr_sconn.sconn288_h44441003(chips)!SCONN288_H44441003_PIP-SCONN,HA!!!F194!VSS(49)!!!!
S!GND!J9T1!274!@baseboard_fab2_lib.baseboard_fab2(sch_1):page78_i144@mstr_sconn.sconn288_h44441003(chips)!SCONN288_H44441003_PIP-SCONN,HA!!!F194!VSS(4)!!!!
S!GND!J9T1!131!@baseboard_fab2_lib.baseboard_fab2(sch_1):page78_i144@mstr_sconn.sconn288_h44441003(chips)!SCONN288_H44441003_PIP-SCONN,HA!!!F194!VSS(50)!!!!
S!GND!J9T1!129!@baseboard_fab2_lib.baseboard_fab2(sch_1):page78_i144@mstr_sconn.sconn288_h44441003(chips)!SCONN288_H44441003_PIP-SCONN,HA!!!F194!VSS(51)!!!!
S!GND!J9T1!127!@baseboard_fab2_lib.baseboard_fab2(sch_1):page78_i144@mstr_sconn.sconn288_h44441003(chips)!SCONN288_H44441003_PIP-SCONN,HA!!!F194!VSS(52)!!!!
S!GND!J9T1!125!@baseboard_fab2_lib.baseboard_fab2(sch_1):page78_i144@mstr_sconn.sconn288_h44441003(chips)!SCONN288_H44441003_PIP-SCONN,HA!!!F194!VSS(53)!!!!
S!GND!J9T1!123!@baseboard_fab2_lib.baseboard_fab2(sch_1):page78_i144@mstr_sconn.sconn288_h44441003(chips)!SCONN288_H44441003_PIP-SCONN,HA!!!F194!VSS(54)!!!!
S!GND!J9T1!120!@baseboard_fab2_lib.baseboard_fab2(sch_1):page78_i144@mstr_sconn.sconn288_h44441003(chips)!SCONN288_H44441003_PIP-SCONN,HA!!!F194!VSS(55)!!!!
S!GND!J9T1!118!@baseboard_fab2_lib.baseboard_fab2(sch_1):page78_i144@mstr_sconn.sconn288_h44441003(chips)!SCONN288_H44441003_PIP-SCONN,HA!!!F194!VSS(56)!!!!
S!GND!J9T1!116!@baseboard_fab2_lib.baseboard_fab2(sch_1):page78_i144@mstr_sconn.sconn288_h44441003(chips)!SCONN288_H44441003_PIP-SCONN,HA!!!F194!VSS(57)!!!!
S!GND!J9T1!114!@baseboard_fab2_lib.baseboard_fab2(sch_1):page78_i144@mstr_sconn.sconn288_h44441003(chips)!SCONN288_H44441003_PIP-SCONN,HA!!!F194!VSS(58)!!!!
S!GND!J9T1!112!@baseboard_fab2_lib.baseboard_fab2(sch_1):page78_i144@mstr_sconn.sconn288_h44441003(chips)!SCONN288_H44441003_PIP-SCONN,HA!!!F194!VSS(59)!!!!
S!GND!J9T1!272!@baseboard_fab2_lib.baseboard_fab2(sch_1):page78_i144@mstr_sconn.sconn288_h44441003(chips)!SCONN288_H44441003_PIP-SCONN,HA!!!F194!VSS(5)!!!!
S!GND!J9T1!109!@baseboard_fab2_lib.baseboard_fab2(sch_1):page78_i144@mstr_sconn.sconn288_h44441003(chips)!SCONN288_H44441003_PIP-SCONN,HA!!!F194!VSS(60)!!!!
S!GND!J9T1!107!@baseboard_fab2_lib.baseboard_fab2(sch_1):page78_i144@mstr_sconn.sconn288_h44441003(chips)!SCONN288_H44441003_PIP-SCONN,HA!!!F194!VSS(61)!!!!
S!GND!J9T1!105!@baseboard_fab2_lib.baseboard_fab2(sch_1):page78_i144@mstr_sconn.sconn288_h44441003(chips)!SCONN288_H44441003_PIP-SCONN,HA!!!F194!VSS(62)!!!!
S!GND!J9T1!103!@baseboard_fab2_lib.baseboard_fab2(sch_1):page78_i144@mstr_sconn.sconn288_h44441003(chips)!SCONN288_H44441003_PIP-SCONN,HA!!!F194!VSS(63)!!!!
S!GND!J9T1!101!@baseboard_fab2_lib.baseboard_fab2(sch_1):page78_i144@mstr_sconn.sconn288_h44441003(chips)!SCONN288_H44441003_PIP-SCONN,HA!!!F194!VSS(64)!!!!
S!GND!J9T1!98!@baseboard_fab2_lib.baseboard_fab2(sch_1):page78_i144@mstr_sconn.sconn288_h44441003(chips)!SCONN288_H44441003_PIP-SCONN,HA!!!F194!VSS(65)!!!!
S!GND!J9T1!96!@baseboard_fab2_lib.baseboard_fab2(sch_1):page78_i144@mstr_sconn.sconn288_h44441003(chips)!SCONN288_H44441003_PIP-SCONN,HA!!!F194!VSS(66)!!!!
S!GND!J9T1!94!@baseboard_fab2_lib.baseboard_fab2(sch_1):page78_i144@mstr_sconn.sconn288_h44441003(chips)!SCONN288_H44441003_PIP-SCONN,HA!!!F194!VSS(67)!!!!
S!GND!J9T1!57!@baseboard_fab2_lib.baseboard_fab2(sch_1):page78_i144@mstr_sconn.sconn288_h44441003(chips)!SCONN288_H44441003_PIP-SCONN,HA!!!F194!VSS(68)!!!!
S!GND!J9T1!55!@baseboard_fab2_lib.baseboard_fab2(sch_1):page78_i144@mstr_sconn.sconn288_h44441003(chips)!SCONN288_H44441003_PIP-SCONN,HA!!!F194!VSS(69)!!!!
S!GND!J9T1!270!@baseboard_fab2_lib.baseboard_fab2(sch_1):page78_i144@mstr_sconn.sconn288_h44441003(chips)!SCONN288_H44441003_PIP-SCONN,HA!!!F194!VSS(6)!!!!
S!GND!J9T1!53!@baseboard_fab2_lib.baseboard_fab2(sch_1):page78_i144@mstr_sconn.sconn288_h44441003(chips)!SCONN288_H44441003_PIP-SCONN,HA!!!F194!VSS(70)!!!!
S!GND!J9T1!50!@baseboard_fab2_lib.baseboard_fab2(sch_1):page78_i144@mstr_sconn.sconn288_h44441003(chips)!SCONN288_H44441003_PIP-SCONN,HA!!!F194!VSS(71)!!!!
S!GND!J9T1!48!@baseboard_fab2_lib.baseboard_fab2(sch_1):page78_i144@mstr_sconn.sconn288_h44441003(chips)!SCONN288_H44441003_PIP-SCONN,HA!!!F194!VSS(72)!!!!
S!GND!J9T1!46!@baseboard_fab2_lib.baseboard_fab2(sch_1):page78_i144@mstr_sconn.sconn288_h44441003(chips)!SCONN288_H44441003_PIP-SCONN,HA!!!F194!VSS(73)!!!!
S!GND!J9T1!44!@baseboard_fab2_lib.baseboard_fab2(sch_1):page78_i144@mstr_sconn.sconn288_h44441003(chips)!SCONN288_H44441003_PIP-SCONN,HA!!!F194!VSS(74)!!!!
S!GND!J9T1!42!@baseboard_fab2_lib.baseboard_fab2(sch_1):page78_i144@mstr_sconn.sconn288_h44441003(chips)!SCONN288_H44441003_PIP-SCONN,HA!!!F194!VSS(75)!!!!
S!GND!J9T1!39!@baseboard_fab2_lib.baseboard_fab2(sch_1):page78_i144@mstr_sconn.sconn288_h44441003(chips)!SCONN288_H44441003_PIP-SCONN,HA!!!F194!VSS(76)!!!!
S!GND!J9T1!37!@baseboard_fab2_lib.baseboard_fab2(sch_1):page78_i144@mstr_sconn.sconn288_h44441003(chips)!SCONN288_H44441003_PIP-SCONN,HA!!!F194!VSS(77)!!!!
S!GND!J9T1!35!@baseboard_fab2_lib.baseboard_fab2(sch_1):page78_i144@mstr_sconn.sconn288_h44441003(chips)!SCONN288_H44441003_PIP-SCONN,HA!!!F194!VSS(78)!!!!
S!GND!J9T1!33!@baseboard_fab2_lib.baseboard_fab2(sch_1):page78_i144@mstr_sconn.sconn288_h44441003(chips)!SCONN288_H44441003_PIP-SCONN,HA!!!F194!VSS(79)!!!!
S!GND!J9T1!268!@baseboard_fab2_lib.baseboard_fab2(sch_1):page78_i144@mstr_sconn.sconn288_h44441003(chips)!SCONN288_H44441003_PIP-SCONN,HA!!!F194!VSS(7)!!!!
S!GND!J9T1!31!@baseboard_fab2_lib.baseboard_fab2(sch_1):page78_i144@mstr_sconn.sconn288_h44441003(chips)!SCONN288_H44441003_PIP-SCONN,HA!!!F194!VSS(80)!!!!
S!GND!J9T1!28!@baseboard_fab2_lib.baseboard_fab2(sch_1):page78_i144@mstr_sconn.sconn288_h44441003(chips)!SCONN288_H44441003_PIP-SCONN,HA!!!F194!VSS(81)!!!!
S!GND!J9T1!26!@baseboard_fab2_lib.baseboard_fab2(sch_1):page78_i144@mstr_sconn.sconn288_h44441003(chips)!SCONN288_H44441003_PIP-SCONN,HA!!!F194!VSS(82)!!!!
S!GND!J9T1!24!@baseboard_fab2_lib.baseboard_fab2(sch_1):page78_i144@mstr_sconn.sconn288_h44441003(chips)!SCONN288_H44441003_PIP-SCONN,HA!!!F194!VSS(83)!!!!
S!GND!J9T1!22!@baseboard_fab2_lib.baseboard_fab2(sch_1):page78_i144@mstr_sconn.sconn288_h44441003(chips)!SCONN288_H44441003_PIP-SCONN,HA!!!F194!VSS(84)!!!!
S!GND!J9T1!20!@baseboard_fab2_lib.baseboard_fab2(sch_1):page78_i144@mstr_sconn.sconn288_h44441003(chips)!SCONN288_H44441003_PIP-SCONN,HA!!!F194!VSS(85)!!!!
S!GND!J9T1!17!@baseboard_fab2_lib.baseboard_fab2(sch_1):page78_i144@mstr_sconn.sconn288_h44441003(chips)!SCONN288_H44441003_PIP-SCONN,HA!!!F194!VSS(86)!!!!
S!GND!J9T1!15!@baseboard_fab2_lib.baseboard_fab2(sch_1):page78_i144@mstr_sconn.sconn288_h44441003(chips)!SCONN288_H44441003_PIP-SCONN,HA!!!F194!VSS(87)!!!!
S!GND!J9T1!13!@baseboard_fab2_lib.baseboard_fab2(sch_1):page78_i144@mstr_sconn.sconn288_h44441003(chips)!SCONN288_H44441003_PIP-SCONN,HA!!!F194!VSS(88)!!!!
S!GND!J9T1!11!@baseboard_fab2_lib.baseboard_fab2(sch_1):page78_i144@mstr_sconn.sconn288_h44441003(chips)!SCONN288_H44441003_PIP-SCONN,HA!!!F194!VSS(89)!!!!
S!GND!J9T1!265!@baseboard_fab2_lib.baseboard_fab2(sch_1):page78_i144@mstr_sconn.sconn288_h44441003(chips)!SCONN288_H44441003_PIP-SCONN,HA!!!F194!VSS(8)!!!!
S!GND!J9T1!9!@baseboard_fab2_lib.baseboard_fab2(sch_1):page78_i144@mstr_sconn.sconn288_h44441003(chips)!SCONN288_H44441003_PIP-SCONN,HA!!!F194!VSS(90)!!!!
S!GND!J9T1!6!@baseboard_fab2_lib.baseboard_fab2(sch_1):page78_i144@mstr_sconn.sconn288_h44441003(chips)!SCONN288_H44441003_PIP-SCONN,HA!!!F194!VSS(91)!!!!
S!GND!J9T1!4!@baseboard_fab2_lib.baseboard_fab2(sch_1):page78_i144@mstr_sconn.sconn288_h44441003(chips)!SCONN288_H44441003_PIP-SCONN,HA!!!F194!VSS(92)!!!!
S!GND!J9T1!2!@baseboard_fab2_lib.baseboard_fab2(sch_1):page78_i144@mstr_sconn.sconn288_h44441003(chips)!SCONN288_H44441003_PIP-SCONN,HA!!!F194!VSS(93)!!!!
S!GND!J9T1!263!@baseboard_fab2_lib.baseboard_fab2(sch_1):page78_i144@mstr_sconn.sconn288_h44441003(chips)!SCONN288_H44441003_PIP-SCONN,HA!!!F194!VSS(9)!!!!
S!P12V_NVDIMM_GHJ!J9T1!145!@baseboard_fab2_lib.baseboard_fab2(sch_1):page78_i75@mstr_sconn.sconn288_h44441003(chips)!SCONN288_H44441003_PIP-SCONN,HA!!!F193!\12v\(0)!!!!
S!P12V_NVDIMM_GHJ!J9T1!1!@baseboard_fab2_lib.baseboard_fab2(sch_1):page78_i75@mstr_sconn.sconn288_h44441003(chips)!SCONN288_H44441003_PIP-SCONN,HA!!!F193!\12v\(1)!!!!
S!PVDDQ_GHJ!J9T1!236!@baseboard_fab2_lib.baseboard_fab2(sch_1):page78_i75@mstr_sconn.sconn288_h44441003(chips)!SCONN288_H44441003_PIP-SCONN,HA!!!F193!VDD(0)!!!!
S!PVDDQ_GHJ!J9T1!209!@baseboard_fab2_lib.baseboard_fab2(sch_1):page78_i75@mstr_sconn.sconn288_h44441003(chips)!SCONN288_H44441003_PIP-SCONN,HA!!!F193!VDD(10)!!!!
S!PVDDQ_GHJ!J9T1!206!@baseboard_fab2_lib.baseboard_fab2(sch_1):page78_i75@mstr_sconn.sconn288_h44441003(chips)!SCONN288_H44441003_PIP-SCONN,HA!!!F193!VDD(11)!!!!
S!PVDDQ_GHJ!J9T1!204!@baseboard_fab2_lib.baseboard_fab2(sch_1):page78_i75@mstr_sconn.sconn288_h44441003(chips)!SCONN288_H44441003_PIP-SCONN,HA!!!F193!VDD(12)!!!!
S!PVDDQ_GHJ!J9T1!92!@baseboard_fab2_lib.baseboard_fab2(sch_1):page78_i75@mstr_sconn.sconn288_h44441003(chips)!SCONN288_H44441003_PIP-SCONN,HA!!!F193!VDD(13)!!!!
S!PVDDQ_GHJ!J9T1!90!@baseboard_fab2_lib.baseboard_fab2(sch_1):page78_i75@mstr_sconn.sconn288_h44441003(chips)!SCONN288_H44441003_PIP-SCONN,HA!!!F193!VDD(14)!!!!
S!PVDDQ_GHJ!J9T1!88!@baseboard_fab2_lib.baseboard_fab2(sch_1):page78_i75@mstr_sconn.sconn288_h44441003(chips)!SCONN288_H44441003_PIP-SCONN,HA!!!F193!VDD(15)!!!!
S!PVDDQ_GHJ!J9T1!85!@baseboard_fab2_lib.baseboard_fab2(sch_1):page78_i75@mstr_sconn.sconn288_h44441003(chips)!SCONN288_H44441003_PIP-SCONN,HA!!!F193!VDD(16)!!!!
S!PVDDQ_GHJ!J9T1!83!@baseboard_fab2_lib.baseboard_fab2(sch_1):page78_i75@mstr_sconn.sconn288_h44441003(chips)!SCONN288_H44441003_PIP-SCONN,HA!!!F193!VDD(17)!!!!
S!PVDDQ_GHJ!J9T1!80!@baseboard_fab2_lib.baseboard_fab2(sch_1):page78_i75@mstr_sconn.sconn288_h44441003(chips)!SCONN288_H44441003_PIP-SCONN,HA!!!F193!VDD(18)!!!!
S!PVDDQ_GHJ!J9T1!76!@baseboard_fab2_lib.baseboard_fab2(sch_1):page78_i75@mstr_sconn.sconn288_h44441003(chips)!SCONN288_H44441003_PIP-SCONN,HA!!!F193!VDD(19)!!!!
S!PVDDQ_GHJ!J9T1!233!@baseboard_fab2_lib.baseboard_fab2(sch_1):page78_i75@mstr_sconn.sconn288_h44441003(chips)!SCONN288_H44441003_PIP-SCONN,HA!!!F193!VDD(1)!!!!
S!PVDDQ_GHJ!J9T1!73!@baseboard_fab2_lib.baseboard_fab2(sch_1):page78_i75@mstr_sconn.sconn288_h44441003(chips)!SCONN288_H44441003_PIP-SCONN,HA!!!F193!VDD(20)!!!!
S!PVDDQ_GHJ!J9T1!70!@baseboard_fab2_lib.baseboard_fab2(sch_1):page78_i75@mstr_sconn.sconn288_h44441003(chips)!SCONN288_H44441003_PIP-SCONN,HA!!!F193!VDD(21)!!!!
S!PVDDQ_GHJ!J9T1!67!@baseboard_fab2_lib.baseboard_fab2(sch_1):page78_i75@mstr_sconn.sconn288_h44441003(chips)!SCONN288_H44441003_PIP-SCONN,HA!!!F193!VDD(22)!!!!
S!PVDDQ_GHJ!J9T1!64!@baseboard_fab2_lib.baseboard_fab2(sch_1):page78_i75@mstr_sconn.sconn288_h44441003(chips)!SCONN288_H44441003_PIP-SCONN,HA!!!F193!VDD(23)!!!!
S!PVDDQ_GHJ!J9T1!61!@baseboard_fab2_lib.baseboard_fab2(sch_1):page78_i75@mstr_sconn.sconn288_h44441003(chips)!SCONN288_H44441003_PIP-SCONN,HA!!!F193!VDD(24)!!!!
S!PVDDQ_GHJ!J9T1!59!@baseboard_fab2_lib.baseboard_fab2(sch_1):page78_i75@mstr_sconn.sconn288_h44441003(chips)!SCONN288_H44441003_PIP-SCONN,HA!!!F193!VDD(25)!!!!
S!PVDDQ_GHJ!J9T1!231!@baseboard_fab2_lib.baseboard_fab2(sch_1):page78_i75@mstr_sconn.sconn288_h44441003(chips)!SCONN288_H44441003_PIP-SCONN,HA!!!F193!VDD(2)!!!!
S!PVDDQ_GHJ!J9T1!229!@baseboard_fab2_lib.baseboard_fab2(sch_1):page78_i75@mstr_sconn.sconn288_h44441003(chips)!SCONN288_H44441003_PIP-SCONN,HA!!!F193!VDD(3)!!!!
S!PVDDQ_GHJ!J9T1!226!@baseboard_fab2_lib.baseboard_fab2(sch_1):page78_i75@mstr_sconn.sconn288_h44441003(chips)!SCONN288_H44441003_PIP-SCONN,HA!!!F193!VDD(4)!!!!
S!PVDDQ_GHJ!J9T1!223!@baseboard_fab2_lib.baseboard_fab2(sch_1):page78_i75@mstr_sconn.sconn288_h44441003(chips)!SCONN288_H44441003_PIP-SCONN,HA!!!F193!VDD(5)!!!!
S!PVDDQ_GHJ!J9T1!220!@baseboard_fab2_lib.baseboard_fab2(sch_1):page78_i75@mstr_sconn.sconn288_h44441003(chips)!SCONN288_H44441003_PIP-SCONN,HA!!!F193!VDD(6)!!!!
S!PVDDQ_GHJ!J9T1!217!@baseboard_fab2_lib.baseboard_fab2(sch_1):page78_i75@mstr_sconn.sconn288_h44441003(chips)!SCONN288_H44441003_PIP-SCONN,HA!!!F193!VDD(7)!!!!
S!PVDDQ_GHJ!J9T1!215!@baseboard_fab2_lib.baseboard_fab2(sch_1):page78_i75@mstr_sconn.sconn288_h44441003(chips)!SCONN288_H44441003_PIP-SCONN,HA!!!F193!VDD(8)!!!!
S!PVDDQ_GHJ!J9T1!212!@baseboard_fab2_lib.baseboard_fab2(sch_1):page78_i75@mstr_sconn.sconn288_h44441003(chips)!SCONN288_H44441003_PIP-SCONN,HA!!!F193!VDD(9)!!!!
S!PVPP_GHJ!J9T1!287!@baseboard_fab2_lib.baseboard_fab2(sch_1):page78_i75@mstr_sconn.sconn288_h44441003(chips)!SCONN288_H44441003_PIP-SCONN,HA!!!F193!VPP(0)!!!!
S!PVPP_GHJ!J9T1!286!@baseboard_fab2_lib.baseboard_fab2(sch_1):page78_i75@mstr_sconn.sconn288_h44441003(chips)!SCONN288_H44441003_PIP-SCONN,HA!!!F193!VPP(1)!!!!
S!PVPP_GHJ!J9T1!288!@baseboard_fab2_lib.baseboard_fab2(sch_1):page78_i75@mstr_sconn.sconn288_h44441003(chips)!SCONN288_H44441003_PIP-SCONN,HA!!!F193!VPP(2)!!!!
S!PVPP_GHJ!J9T1!143!@baseboard_fab2_lib.baseboard_fab2(sch_1):page78_i75@mstr_sconn.sconn288_h44441003(chips)!SCONN288_H44441003_PIP-SCONN,HA!!!F193!VPP(3)!!!!
S!PVPP_GHJ!J9T1!142!@baseboard_fab2_lib.baseboard_fab2(sch_1):page78_i75@mstr_sconn.sconn288_h44441003(chips)!SCONN288_H44441003_PIP-SCONN,HA!!!F193!VPP(4)!!!!
S!PVTT_GHJ!J9T1!221!@baseboard_fab2_lib.baseboard_fab2(sch_1):page78_i75@mstr_sconn.sconn288_h44441003(chips)!SCONN288_H44441003_PIP-SCONN,HA!!!F193!VTT(0)!!!!
S!PVTT_GHJ!J9T1!77!@baseboard_fab2_lib.baseboard_fab2(sch_1):page78_i75@mstr_sconn.sconn288_h44441003(chips)!SCONN288_H44441003_PIP-SCONN,HA!!!F193!VTT(1)!!!!
S!M_H_MA<0>!J9U1!79!@baseboard_fab2_lib.baseboard_fab2(sch_1):page80_i24@mstr_sconn.sconn288_h44441003(chips)!SCONN288_H44441003_PIP-SCONN,HA!!!F192!A0!!!!
S!M_H_MA<1>!J9U1!72!@baseboard_fab2_lib.baseboard_fab2(sch_1):page80_i24@mstr_sconn.sconn288_h44441003(chips)!SCONN288_H44441003_PIP-SCONN,HA!!!F192!A1!!!!
S!M_H_MA<10>!J9U1!225!@baseboard_fab2_lib.baseboard_fab2(sch_1):page80_i24@mstr_sconn.sconn288_h44441003(chips)!SCONN288_H44441003_PIP-SCONN,HA!!!F192!A10!!!!
S!M_H_MA<11>!J9U1!210!@baseboard_fab2_lib.baseboard_fab2(sch_1):page80_i24@mstr_sconn.sconn288_h44441003(chips)!SCONN288_H44441003_PIP-SCONN,HA!!!F192!A11!!!!
S!M_H_MA<12>!J9U1!65!@baseboard_fab2_lib.baseboard_fab2(sch_1):page80_i24@mstr_sconn.sconn288_h44441003(chips)!SCONN288_H44441003_PIP-SCONN,HA!!!F192!A12!!!!
S!M_H_MA<13>!J9U1!232!@baseboard_fab2_lib.baseboard_fab2(sch_1):page80_i24@mstr_sconn.sconn288_h44441003(chips)!SCONN288_H44441003_PIP-SCONN,HA!!!F192!A13!!!!
S!M_H_MA<14>!J9U1!228!@baseboard_fab2_lib.baseboard_fab2(sch_1):page80_i24@mstr_sconn.sconn288_h44441003(chips)!SCONN288_H44441003_PIP-SCONN,HA!!!F192!A14_WE_N!!!!
S!M_H_MA<15>!J9U1!86!@baseboard_fab2_lib.baseboard_fab2(sch_1):page80_i24@mstr_sconn.sconn288_h44441003(chips)!SCONN288_H44441003_PIP-SCONN,HA!!!F192!A15_CAS_N!!!!
S!M_H_MA<16>!J9U1!82!@baseboard_fab2_lib.baseboard_fab2(sch_1):page80_i24@mstr_sconn.sconn288_h44441003(chips)!SCONN288_H44441003_PIP-SCONN,HA!!!F192!A16_RAS_N!!!!
S!M_H_MA<17>!J9U1!234!@baseboard_fab2_lib.baseboard_fab2(sch_1):page80_i24@mstr_sconn.sconn288_h44441003(chips)!SCONN288_H44441003_PIP-SCONN,HA!!!F192!A17!!!!
S!M_H_MA<2>!J9U1!216!@baseboard_fab2_lib.baseboard_fab2(sch_1):page80_i24@mstr_sconn.sconn288_h44441003(chips)!SCONN288_H44441003_PIP-SCONN,HA!!!F192!A2!!!!
S!M_H_MA<3>!J9U1!71!@baseboard_fab2_lib.baseboard_fab2(sch_1):page80_i24@mstr_sconn.sconn288_h44441003(chips)!SCONN288_H44441003_PIP-SCONN,HA!!!F192!A3!!!!
S!M_H_MA<4>!J9U1!214!@baseboard_fab2_lib.baseboard_fab2(sch_1):page80_i24@mstr_sconn.sconn288_h44441003(chips)!SCONN288_H44441003_PIP-SCONN,HA!!!F192!A4!!!!
S!M_H_MA<5>!J9U1!213!@baseboard_fab2_lib.baseboard_fab2(sch_1):page80_i24@mstr_sconn.sconn288_h44441003(chips)!SCONN288_H44441003_PIP-SCONN,HA!!!F192!A5!!!!
S!M_H_MA<6>!J9U1!69!@baseboard_fab2_lib.baseboard_fab2(sch_1):page80_i24@mstr_sconn.sconn288_h44441003(chips)!SCONN288_H44441003_PIP-SCONN,HA!!!F192!A6!!!!
S!M_H_MA<7>!J9U1!211!@baseboard_fab2_lib.baseboard_fab2(sch_1):page80_i24@mstr_sconn.sconn288_h44441003(chips)!SCONN288_H44441003_PIP-SCONN,HA!!!F192!A7!!!!
S!M_H_MA<8>!J9U1!68!@baseboard_fab2_lib.baseboard_fab2(sch_1):page80_i24@mstr_sconn.sconn288_h44441003(chips)!SCONN288_H44441003_PIP-SCONN,HA!!!F192!A8!!!!
S!M_H_MA<9>!J9U1!66!@baseboard_fab2_lib.baseboard_fab2(sch_1):page80_i24@mstr_sconn.sconn288_h44441003(chips)!SCONN288_H44441003_PIP-SCONN,HA!!!F192!A9!!!!
S!M_H_ACT_N!J9U1!62!@baseboard_fab2_lib.baseboard_fab2(sch_1):page80_i24@mstr_sconn.sconn288_h44441003(chips)!SCONN288_H44441003_PIP-SCONN,HA!!!F192!ACT_N!!!!
S!M_H_ALERT_N!J9U1!208!@baseboard_fab2_lib.baseboard_fab2(sch_1):page80_i24@mstr_sconn.sconn288_h44441003(chips)!SCONN288_H44441003_PIP-SCONN,HA!!!F192!ALERT_N!!!!
S!M_H_BA<0>!J9U1!81!@baseboard_fab2_lib.baseboard_fab2(sch_1):page80_i24@mstr_sconn.sconn288_h44441003(chips)!SCONN288_H44441003_PIP-SCONN,HA!!!F192!BA(0)!!!!
S!M_H_BA<1>!J9U1!224!@baseboard_fab2_lib.baseboard_fab2(sch_1):page80_i24@mstr_sconn.sconn288_h44441003(chips)!SCONN288_H44441003_PIP-SCONN,HA!!!F192!BA(1)!!!!
S!M_H_BG<0>!J9U1!63!@baseboard_fab2_lib.baseboard_fab2(sch_1):page80_i24@mstr_sconn.sconn288_h44441003(chips)!SCONN288_H44441003_PIP-SCONN,HA!!!F192!BG(0)!!!!
S!M_H_BG<1>!J9U1!207!@baseboard_fab2_lib.baseboard_fab2(sch_1):page80_i24@mstr_sconn.sconn288_h44441003(chips)!SCONN288_H44441003_PIP-SCONN,HA!!!F192!BG(1)!!!!
S!M_H_C<2>!J9U1!235!@baseboard_fab2_lib.baseboard_fab2(sch_1):page80_i24@mstr_sconn.sconn288_h44441003(chips)!SCONN288_H44441003_PIP-SCONN,HA!!!F192!C(2)!!!!
S!M_H_ECC<0>!J9U1!49!@baseboard_fab2_lib.baseboard_fab2(sch_1):page80_i24@mstr_sconn.sconn288_h44441003(chips)!SCONN288_H44441003_PIP-SCONN,HA!!!F192!CB(0)!!!!
S!M_H_ECC<1>!J9U1!194!@baseboard_fab2_lib.baseboard_fab2(sch_1):page80_i24@mstr_sconn.sconn288_h44441003(chips)!SCONN288_H44441003_PIP-SCONN,HA!!!F192!CB(1)!!!!
S!M_H_ECC<2>!J9U1!56!@baseboard_fab2_lib.baseboard_fab2(sch_1):page80_i24@mstr_sconn.sconn288_h44441003(chips)!SCONN288_H44441003_PIP-SCONN,HA!!!F192!CB(2)!!!!
S!M_H_ECC<3>!J9U1!201!@baseboard_fab2_lib.baseboard_fab2(sch_1):page80_i24@mstr_sconn.sconn288_h44441003(chips)!SCONN288_H44441003_PIP-SCONN,HA!!!F192!CB(3)!!!!
S!M_H_ECC<4>!J9U1!47!@baseboard_fab2_lib.baseboard_fab2(sch_1):page80_i24@mstr_sconn.sconn288_h44441003(chips)!SCONN288_H44441003_PIP-SCONN,HA!!!F192!CB(4)!!!!
S!M_H_ECC<5>!J9U1!192!@baseboard_fab2_lib.baseboard_fab2(sch_1):page80_i24@mstr_sconn.sconn288_h44441003(chips)!SCONN288_H44441003_PIP-SCONN,HA!!!F192!CB(5)!!!!
S!M_H_ECC<6>!J9U1!54!@baseboard_fab2_lib.baseboard_fab2(sch_1):page80_i24@mstr_sconn.sconn288_h44441003(chips)!SCONN288_H44441003_PIP-SCONN,HA!!!F192!CB(6)!!!!
S!M_H_ECC<7>!J9U1!199!@baseboard_fab2_lib.baseboard_fab2(sch_1):page80_i24@mstr_sconn.sconn288_h44441003(chips)!SCONN288_H44441003_PIP-SCONN,HA!!!F192!CB(7)!!!!
S!M_H_CLK_DN<2>!J9U1!75!@baseboard_fab2_lib.baseboard_fab2(sch_1):page80_i24@mstr_sconn.sconn288_h44441003(chips)!SCONN288_H44441003_PIP-SCONN,HA!!!F192!CK0N!!!!
S!M_H_CLK_DP<2>!J9U1!74!@baseboard_fab2_lib.baseboard_fab2(sch_1):page80_i24@mstr_sconn.sconn288_h44441003(chips)!SCONN288_H44441003_PIP-SCONN,HA!!!F192!CK0P!!!!
S!M_H_CLK_DN<3>!J9U1!219!@baseboard_fab2_lib.baseboard_fab2(sch_1):page80_i24@mstr_sconn.sconn288_h44441003(chips)!SCONN288_H44441003_PIP-SCONN,HA!!!F192!CK1N!!!!
S!M_H_CLK_DP<3>!J9U1!218!@baseboard_fab2_lib.baseboard_fab2(sch_1):page80_i24@mstr_sconn.sconn288_h44441003(chips)!SCONN288_H44441003_PIP-SCONN,HA!!!F192!CK1P!!!!
S!M_H_CKE<2>!J9U1!60!@baseboard_fab2_lib.baseboard_fab2(sch_1):page80_i24@mstr_sconn.sconn288_h44441003(chips)!SCONN288_H44441003_PIP-SCONN,HA!!!F192!CKE(0)!!!!
S!M_H_CKE<3>!J9U1!203!@baseboard_fab2_lib.baseboard_fab2(sch_1):page80_i24@mstr_sconn.sconn288_h44441003(chips)!SCONN288_H44441003_PIP-SCONN,HA!!!F192!CKE(1)!!!!
S!M_H_DQ<0>!J9U1!5!@baseboard_fab2_lib.baseboard_fab2(sch_1):page80_i24@mstr_sconn.sconn288_h44441003(chips)!SCONN288_H44441003_PIP-SCONN,HA!!!F192!DQ(0)!!!!
S!M_H_DQ<10>!J9U1!23!@baseboard_fab2_lib.baseboard_fab2(sch_1):page80_i24@mstr_sconn.sconn288_h44441003(chips)!SCONN288_H44441003_PIP-SCONN,HA!!!F192!DQ(10)!!!!
S!M_H_DQ<11>!J9U1!168!@baseboard_fab2_lib.baseboard_fab2(sch_1):page80_i24@mstr_sconn.sconn288_h44441003(chips)!SCONN288_H44441003_PIP-SCONN,HA!!!F192!DQ(11)!!!!
S!M_H_DQ<12>!J9U1!14!@baseboard_fab2_lib.baseboard_fab2(sch_1):page80_i24@mstr_sconn.sconn288_h44441003(chips)!SCONN288_H44441003_PIP-SCONN,HA!!!F192!DQ(12)!!!!
S!M_H_DQ<13>!J9U1!159!@baseboard_fab2_lib.baseboard_fab2(sch_1):page80_i24@mstr_sconn.sconn288_h44441003(chips)!SCONN288_H44441003_PIP-SCONN,HA!!!F192!DQ(13)!!!!
S!M_H_DQ<14>!J9U1!21!@baseboard_fab2_lib.baseboard_fab2(sch_1):page80_i24@mstr_sconn.sconn288_h44441003(chips)!SCONN288_H44441003_PIP-SCONN,HA!!!F192!DQ(14)!!!!
S!M_H_DQ<15>!J9U1!166!@baseboard_fab2_lib.baseboard_fab2(sch_1):page80_i24@mstr_sconn.sconn288_h44441003(chips)!SCONN288_H44441003_PIP-SCONN,HA!!!F192!DQ(15)!!!!
S!M_H_DQ<16>!J9U1!27!@baseboard_fab2_lib.baseboard_fab2(sch_1):page80_i24@mstr_sconn.sconn288_h44441003(chips)!SCONN288_H44441003_PIP-SCONN,HA!!!F192!DQ(16)!!!!
S!M_H_DQ<17>!J9U1!172!@baseboard_fab2_lib.baseboard_fab2(sch_1):page80_i24@mstr_sconn.sconn288_h44441003(chips)!SCONN288_H44441003_PIP-SCONN,HA!!!F192!DQ(17)!!!!
S!M_H_DQ<18>!J9U1!34!@baseboard_fab2_lib.baseboard_fab2(sch_1):page80_i24@mstr_sconn.sconn288_h44441003(chips)!SCONN288_H44441003_PIP-SCONN,HA!!!F192!DQ(18)!!!!
S!M_H_DQ<19>!J9U1!179!@baseboard_fab2_lib.baseboard_fab2(sch_1):page80_i24@mstr_sconn.sconn288_h44441003(chips)!SCONN288_H44441003_PIP-SCONN,HA!!!F192!DQ(19)!!!!
S!M_H_DQ<1>!J9U1!150!@baseboard_fab2_lib.baseboard_fab2(sch_1):page80_i24@mstr_sconn.sconn288_h44441003(chips)!SCONN288_H44441003_PIP-SCONN,HA!!!F192!DQ(1)!!!!
S!M_H_DQ<20>!J9U1!25!@baseboard_fab2_lib.baseboard_fab2(sch_1):page80_i24@mstr_sconn.sconn288_h44441003(chips)!SCONN288_H44441003_PIP-SCONN,HA!!!F192!DQ(20)!!!!
S!M_H_DQ<21>!J9U1!170!@baseboard_fab2_lib.baseboard_fab2(sch_1):page80_i24@mstr_sconn.sconn288_h44441003(chips)!SCONN288_H44441003_PIP-SCONN,HA!!!F192!DQ(21)!!!!
S!M_H_DQ<22>!J9U1!32!@baseboard_fab2_lib.baseboard_fab2(sch_1):page80_i24@mstr_sconn.sconn288_h44441003(chips)!SCONN288_H44441003_PIP-SCONN,HA!!!F192!DQ(22)!!!!
S!M_H_DQ<23>!J9U1!177!@baseboard_fab2_lib.baseboard_fab2(sch_1):page80_i24@mstr_sconn.sconn288_h44441003(chips)!SCONN288_H44441003_PIP-SCONN,HA!!!F192!DQ(23)!!!!
S!M_H_DQ<24>!J9U1!38!@baseboard_fab2_lib.baseboard_fab2(sch_1):page80_i24@mstr_sconn.sconn288_h44441003(chips)!SCONN288_H44441003_PIP-SCONN,HA!!!F192!DQ(24)!!!!
S!M_H_DQ<25>!J9U1!183!@baseboard_fab2_lib.baseboard_fab2(sch_1):page80_i24@mstr_sconn.sconn288_h44441003(chips)!SCONN288_H44441003_PIP-SCONN,HA!!!F192!DQ(25)!!!!
S!M_H_DQ<26>!J9U1!45!@baseboard_fab2_lib.baseboard_fab2(sch_1):page80_i24@mstr_sconn.sconn288_h44441003(chips)!SCONN288_H44441003_PIP-SCONN,HA!!!F192!DQ(26)!!!!
S!M_H_DQ<27>!J9U1!190!@baseboard_fab2_lib.baseboard_fab2(sch_1):page80_i24@mstr_sconn.sconn288_h44441003(chips)!SCONN288_H44441003_PIP-SCONN,HA!!!F192!DQ(27)!!!!
S!M_H_DQ<28>!J9U1!36!@baseboard_fab2_lib.baseboard_fab2(sch_1):page80_i24@mstr_sconn.sconn288_h44441003(chips)!SCONN288_H44441003_PIP-SCONN,HA!!!F192!DQ(28)!!!!
S!M_H_DQ<29>!J9U1!181!@baseboard_fab2_lib.baseboard_fab2(sch_1):page80_i24@mstr_sconn.sconn288_h44441003(chips)!SCONN288_H44441003_PIP-SCONN,HA!!!F192!DQ(29)!!!!
S!M_H_DQ<2>!J9U1!12!@baseboard_fab2_lib.baseboard_fab2(sch_1):page80_i24@mstr_sconn.sconn288_h44441003(chips)!SCONN288_H44441003_PIP-SCONN,HA!!!F192!DQ(2)!!!!
S!M_H_DQ<30>!J9U1!43!@baseboard_fab2_lib.baseboard_fab2(sch_1):page80_i24@mstr_sconn.sconn288_h44441003(chips)!SCONN288_H44441003_PIP-SCONN,HA!!!F192!DQ(30)!!!!
S!M_H_DQ<31>!J9U1!188!@baseboard_fab2_lib.baseboard_fab2(sch_1):page80_i24@mstr_sconn.sconn288_h44441003(chips)!SCONN288_H44441003_PIP-SCONN,HA!!!F192!DQ(31)!!!!
S!M_H_DQ<32>!J9U1!97!@baseboard_fab2_lib.baseboard_fab2(sch_1):page80_i24@mstr_sconn.sconn288_h44441003(chips)!SCONN288_H44441003_PIP-SCONN,HA!!!F192!DQ(32)!!!!
S!M_H_DQ<33>!J9U1!242!@baseboard_fab2_lib.baseboard_fab2(sch_1):page80_i24@mstr_sconn.sconn288_h44441003(chips)!SCONN288_H44441003_PIP-SCONN,HA!!!F192!DQ(33)!!!!
S!M_H_DQ<34>!J9U1!104!@baseboard_fab2_lib.baseboard_fab2(sch_1):page80_i24@mstr_sconn.sconn288_h44441003(chips)!SCONN288_H44441003_PIP-SCONN,HA!!!F192!DQ(34)!!!!
S!M_H_DQ<35>!J9U1!249!@baseboard_fab2_lib.baseboard_fab2(sch_1):page80_i24@mstr_sconn.sconn288_h44441003(chips)!SCONN288_H44441003_PIP-SCONN,HA!!!F192!DQ(35)!!!!
S!M_H_DQ<36>!J9U1!95!@baseboard_fab2_lib.baseboard_fab2(sch_1):page80_i24@mstr_sconn.sconn288_h44441003(chips)!SCONN288_H44441003_PIP-SCONN,HA!!!F192!DQ(36)!!!!
S!M_H_DQ<37>!J9U1!240!@baseboard_fab2_lib.baseboard_fab2(sch_1):page80_i24@mstr_sconn.sconn288_h44441003(chips)!SCONN288_H44441003_PIP-SCONN,HA!!!F192!DQ(37)!!!!
S!M_H_DQ<38>!J9U1!102!@baseboard_fab2_lib.baseboard_fab2(sch_1):page80_i24@mstr_sconn.sconn288_h44441003(chips)!SCONN288_H44441003_PIP-SCONN,HA!!!F192!DQ(38)!!!!
S!M_H_DQ<39>!J9U1!247!@baseboard_fab2_lib.baseboard_fab2(sch_1):page80_i24@mstr_sconn.sconn288_h44441003(chips)!SCONN288_H44441003_PIP-SCONN,HA!!!F192!DQ(39)!!!!
S!M_H_DQ<3>!J9U1!157!@baseboard_fab2_lib.baseboard_fab2(sch_1):page80_i24@mstr_sconn.sconn288_h44441003(chips)!SCONN288_H44441003_PIP-SCONN,HA!!!F192!DQ(3)!!!!
S!M_H_DQ<40>!J9U1!108!@baseboard_fab2_lib.baseboard_fab2(sch_1):page80_i24@mstr_sconn.sconn288_h44441003(chips)!SCONN288_H44441003_PIP-SCONN,HA!!!F192!DQ(40)!!!!
S!M_H_DQ<41>!J9U1!253!@baseboard_fab2_lib.baseboard_fab2(sch_1):page80_i24@mstr_sconn.sconn288_h44441003(chips)!SCONN288_H44441003_PIP-SCONN,HA!!!F192!DQ(41)!!!!
S!M_H_DQ<42>!J9U1!115!@baseboard_fab2_lib.baseboard_fab2(sch_1):page80_i24@mstr_sconn.sconn288_h44441003(chips)!SCONN288_H44441003_PIP-SCONN,HA!!!F192!DQ(42)!!!!
S!M_H_DQ<43>!J9U1!260!@baseboard_fab2_lib.baseboard_fab2(sch_1):page80_i24@mstr_sconn.sconn288_h44441003(chips)!SCONN288_H44441003_PIP-SCONN,HA!!!F192!DQ(43)!!!!
S!M_H_DQ<44>!J9U1!106!@baseboard_fab2_lib.baseboard_fab2(sch_1):page80_i24@mstr_sconn.sconn288_h44441003(chips)!SCONN288_H44441003_PIP-SCONN,HA!!!F192!DQ(44)!!!!
S!M_H_DQ<45>!J9U1!251!@baseboard_fab2_lib.baseboard_fab2(sch_1):page80_i24@mstr_sconn.sconn288_h44441003(chips)!SCONN288_H44441003_PIP-SCONN,HA!!!F192!DQ(45)!!!!
S!M_H_DQ<46>!J9U1!113!@baseboard_fab2_lib.baseboard_fab2(sch_1):page80_i24@mstr_sconn.sconn288_h44441003(chips)!SCONN288_H44441003_PIP-SCONN,HA!!!F192!DQ(46)!!!!
S!M_H_DQ<47>!J9U1!258!@baseboard_fab2_lib.baseboard_fab2(sch_1):page80_i24@mstr_sconn.sconn288_h44441003(chips)!SCONN288_H44441003_PIP-SCONN,HA!!!F192!DQ(47)!!!!
S!M_H_DQ<48>!J9U1!119!@baseboard_fab2_lib.baseboard_fab2(sch_1):page80_i24@mstr_sconn.sconn288_h44441003(chips)!SCONN288_H44441003_PIP-SCONN,HA!!!F192!DQ(48)!!!!
S!M_H_DQ<49>!J9U1!264!@baseboard_fab2_lib.baseboard_fab2(sch_1):page80_i24@mstr_sconn.sconn288_h44441003(chips)!SCONN288_H44441003_PIP-SCONN,HA!!!F192!DQ(49)!!!!
S!M_H_DQ<4>!J9U1!3!@baseboard_fab2_lib.baseboard_fab2(sch_1):page80_i24@mstr_sconn.sconn288_h44441003(chips)!SCONN288_H44441003_PIP-SCONN,HA!!!F192!DQ(4)!!!!
S!M_H_DQ<50>!J9U1!126!@baseboard_fab2_lib.baseboard_fab2(sch_1):page80_i24@mstr_sconn.sconn288_h44441003(chips)!SCONN288_H44441003_PIP-SCONN,HA!!!F192!DQ(50)!!!!
S!M_H_DQ<51>!J9U1!271!@baseboard_fab2_lib.baseboard_fab2(sch_1):page80_i24@mstr_sconn.sconn288_h44441003(chips)!SCONN288_H44441003_PIP-SCONN,HA!!!F192!DQ(51)!!!!
S!M_H_DQ<52>!J9U1!117!@baseboard_fab2_lib.baseboard_fab2(sch_1):page80_i24@mstr_sconn.sconn288_h44441003(chips)!SCONN288_H44441003_PIP-SCONN,HA!!!F192!DQ(52)!!!!
S!M_H_DQ<53>!J9U1!262!@baseboard_fab2_lib.baseboard_fab2(sch_1):page80_i24@mstr_sconn.sconn288_h44441003(chips)!SCONN288_H44441003_PIP-SCONN,HA!!!F192!DQ(53)!!!!
S!M_H_DQ<54>!J9U1!124!@baseboard_fab2_lib.baseboard_fab2(sch_1):page80_i24@mstr_sconn.sconn288_h44441003(chips)!SCONN288_H44441003_PIP-SCONN,HA!!!F192!DQ(54)!!!!
S!M_H_DQ<55>!J9U1!269!@baseboard_fab2_lib.baseboard_fab2(sch_1):page80_i24@mstr_sconn.sconn288_h44441003(chips)!SCONN288_H44441003_PIP-SCONN,HA!!!F192!DQ(55)!!!!
S!M_H_DQ<56>!J9U1!130!@baseboard_fab2_lib.baseboard_fab2(sch_1):page80_i24@mstr_sconn.sconn288_h44441003(chips)!SCONN288_H44441003_PIP-SCONN,HA!!!F192!DQ(56)!!!!
S!M_H_DQ<57>!J9U1!275!@baseboard_fab2_lib.baseboard_fab2(sch_1):page80_i24@mstr_sconn.sconn288_h44441003(chips)!SCONN288_H44441003_PIP-SCONN,HA!!!F192!DQ(57)!!!!
S!M_H_DQ<58>!J9U1!137!@baseboard_fab2_lib.baseboard_fab2(sch_1):page80_i24@mstr_sconn.sconn288_h44441003(chips)!SCONN288_H44441003_PIP-SCONN,HA!!!F192!DQ(58)!!!!
S!M_H_DQ<59>!J9U1!282!@baseboard_fab2_lib.baseboard_fab2(sch_1):page80_i24@mstr_sconn.sconn288_h44441003(chips)!SCONN288_H44441003_PIP-SCONN,HA!!!F192!DQ(59)!!!!
S!M_H_DQ<5>!J9U1!148!@baseboard_fab2_lib.baseboard_fab2(sch_1):page80_i24@mstr_sconn.sconn288_h44441003(chips)!SCONN288_H44441003_PIP-SCONN,HA!!!F192!DQ(5)!!!!
S!M_H_DQ<60>!J9U1!128!@baseboard_fab2_lib.baseboard_fab2(sch_1):page80_i24@mstr_sconn.sconn288_h44441003(chips)!SCONN288_H44441003_PIP-SCONN,HA!!!F192!DQ(60)!!!!
S!M_H_DQ<61>!J9U1!273!@baseboard_fab2_lib.baseboard_fab2(sch_1):page80_i24@mstr_sconn.sconn288_h44441003(chips)!SCONN288_H44441003_PIP-SCONN,HA!!!F192!DQ(61)!!!!
S!M_H_DQ<62>!J9U1!135!@baseboard_fab2_lib.baseboard_fab2(sch_1):page80_i24@mstr_sconn.sconn288_h44441003(chips)!SCONN288_H44441003_PIP-SCONN,HA!!!F192!DQ(62)!!!!
S!M_H_DQ<63>!J9U1!280!@baseboard_fab2_lib.baseboard_fab2(sch_1):page80_i24@mstr_sconn.sconn288_h44441003(chips)!SCONN288_H44441003_PIP-SCONN,HA!!!F192!DQ(63)!!!!
S!M_H_DQ<6>!J9U1!10!@baseboard_fab2_lib.baseboard_fab2(sch_1):page80_i24@mstr_sconn.sconn288_h44441003(chips)!SCONN288_H44441003_PIP-SCONN,HA!!!F192!DQ(6)!!!!
S!M_H_DQ<7>!J9U1!155!@baseboard_fab2_lib.baseboard_fab2(sch_1):page80_i24@mstr_sconn.sconn288_h44441003(chips)!SCONN288_H44441003_PIP-SCONN,HA!!!F192!DQ(7)!!!!
S!M_H_DQ<8>!J9U1!16!@baseboard_fab2_lib.baseboard_fab2(sch_1):page80_i24@mstr_sconn.sconn288_h44441003(chips)!SCONN288_H44441003_PIP-SCONN,HA!!!F192!DQ(8)!!!!
S!M_H_DQ<9>!J9U1!161!@baseboard_fab2_lib.baseboard_fab2(sch_1):page80_i24@mstr_sconn.sconn288_h44441003(chips)!SCONN288_H44441003_PIP-SCONN,HA!!!F192!DQ(9)!!!!
S!FM_DIMM_EVENT_COD_N!J9U1!78!@baseboard_fab2_lib.baseboard_fab2(sch_1):page80_i24@mstr_sconn.sconn288_h44441003(chips)!SCONN288_H44441003_PIP-SCONN,HA!!!F192!EVENT_N!!!!
S!M_H_ODT<2>!J9U1!87!@baseboard_fab2_lib.baseboard_fab2(sch_1):page80_i24@mstr_sconn.sconn288_h44441003(chips)!SCONN288_H44441003_PIP-SCONN,HA!!!F192!ODT(0)!!!!
S!M_H_ODT<3>!J9U1!91!@baseboard_fab2_lib.baseboard_fab2(sch_1):page80_i24@mstr_sconn.sconn288_h44441003(chips)!SCONN288_H44441003_PIP-SCONN,HA!!!F192!ODT(1)!!!!
S!M_H_PAR!J9U1!222!@baseboard_fab2_lib.baseboard_fab2(sch_1):page80_i24@mstr_sconn.sconn288_h44441003(chips)!SCONN288_H44441003_PIP-SCONN,HA!!!F192!PAR!!!!
S!M_GHJ_RST_N!J9U1!58!@baseboard_fab2_lib.baseboard_fab2(sch_1):page80_i24@mstr_sconn.sconn288_h44441003(chips)!SCONN288_H44441003_PIP-SCONN,HA!!!F192!RESET_N!!!!
S!TP_CH_H_DIMM0_RFU_0!J9U1!205!@baseboard_fab2_lib.baseboard_fab2(sch_1):page80_i24@mstr_sconn.sconn288_h44441003(chips)!SCONN288_H44441003_PIP-SCONN,HA!!!F192!RFU(0)!!!!
S!TP_CH_H_DIMM0_RFU_1!J9U1!227!@baseboard_fab2_lib.baseboard_fab2(sch_1):page80_i24@mstr_sconn.sconn288_h44441003(chips)!SCONN288_H44441003_PIP-SCONN,HA!!!F192!RFU(1)!!!!
S!TP_CH_H_DIMM0_RFU_2!J9U1!144!@baseboard_fab2_lib.baseboard_fab2(sch_1):page80_i24@mstr_sconn.sconn288_h44441003(chips)!SCONN288_H44441003_PIP-SCONN,HA!!!F192!RFU(2)!!!!
S!M_H_CS_N<4>!J9U1!84!@baseboard_fab2_lib.baseboard_fab2(sch_1):page80_i24@mstr_sconn.sconn288_h44441003(chips)!SCONN288_H44441003_PIP-SCONN,HA!!!F192!S0_N!!!!
S!M_H_CS_N<5>!J9U1!89!@baseboard_fab2_lib.baseboard_fab2(sch_1):page80_i24@mstr_sconn.sconn288_h44441003(chips)!SCONN288_H44441003_PIP-SCONN,HA!!!F192!S1_N!!!!
S!M_H_CS_N<6>!J9U1!93!@baseboard_fab2_lib.baseboard_fab2(sch_1):page80_i24@mstr_sconn.sconn288_h44441003(chips)!SCONN288_H44441003_PIP-SCONN,HA!!!F192!S2_N_C(0)!!!!
S!M_H_CS_N<7>!J9U1!237!@baseboard_fab2_lib.baseboard_fab2(sch_1):page80_i24@mstr_sconn.sconn288_h44441003(chips)!SCONN288_H44441003_PIP-SCONN,HA!!!F192!S3_N_C(1)!!!!
S!PVPP_GHJ!J9U1!139!@baseboard_fab2_lib.baseboard_fab2(sch_1):page80_i24@mstr_sconn.sconn288_h44441003(chips)!SCONN288_H44441003_PIP-SCONN,HA!!!F192!SA(0)!!!!
S!PVPP_GHJ!J9U1!140!@baseboard_fab2_lib.baseboard_fab2(sch_1):page80_i24@mstr_sconn.sconn288_h44441003(chips)!SCONN288_H44441003_PIP-SCONN,HA!!!F192!SA(1)!!!!
S!GND!J9U1!238!@baseboard_fab2_lib.baseboard_fab2(sch_1):page80_i24@mstr_sconn.sconn288_h44441003(chips)!SCONN288_H44441003_PIP-SCONN,HA!!!F192!SA(2)!!!!
S!FM_ADR_COMPLETE_GHJ_N!J9U1!230!@baseboard_fab2_lib.baseboard_fab2(sch_1):page80_i24@mstr_sconn.sconn288_h44441003(chips)!SCONN288_H44441003_PIP-SCONN,HA!!!F192!SAVE_N_NC!!!!
S!SMB_DDR_GHJ_VPP_SCL!J9U1!141!@baseboard_fab2_lib.baseboard_fab2(sch_1):page80_i24@mstr_sconn.sconn288_h44441003(chips)!SCONN288_H44441003_PIP-SCONN,HA!!!F192!SCL!!!!
S!SMB_DDR_GHJ_VPP_SDA!J9U1!285!@baseboard_fab2_lib.baseboard_fab2(sch_1):page80_i24@mstr_sconn.sconn288_h44441003(chips)!SCONN288_H44441003_PIP-SCONN,HA!!!F192!SDA!!!!
S!PVPP_GHJ!J9U1!284!@baseboard_fab2_lib.baseboard_fab2(sch_1):page80_i24@mstr_sconn.sconn288_h44441003(chips)!SCONN288_H44441003_PIP-SCONN,HA!!!F192!VDDSPD!!!!
S!M_H_VREF!J9U1!146!@baseboard_fab2_lib.baseboard_fab2(sch_1):page80_i24@mstr_sconn.sconn288_h44441003(chips)!SCONN288_H44441003_PIP-SCONN,HA!!!F192!VREFCA!!!!
S!M_H_DQS_DN<0>!J9U1!152!@baseboard_fab2_lib.baseboard_fab2(sch_1):page80_i101@mstr_sconn.sconn288_h44441003(chips)!SCONN288_H44441003_PIP-SCONN,HA!!!F191!DQS0N!!!!
S!M_H_DQS_DP<0>!J9U1!153!@baseboard_fab2_lib.baseboard_fab2(sch_1):page80_i101@mstr_sconn.sconn288_h44441003(chips)!SCONN288_H44441003_PIP-SCONN,HA!!!F191!DQS0P!!!!
S!M_H_DQS_DN<10>!J9U1!19!@baseboard_fab2_lib.baseboard_fab2(sch_1):page80_i101@mstr_sconn.sconn288_h44441003(chips)!SCONN288_H44441003_PIP-SCONN,HA!!!F191!DQS10N!!!!
S!M_H_DQS_DP<10>!J9U1!18!@baseboard_fab2_lib.baseboard_fab2(sch_1):page80_i101@mstr_sconn.sconn288_h44441003(chips)!SCONN288_H44441003_PIP-SCONN,HA!!!F191!DQS10P!!!!
S!M_H_DQS_DN<11>!J9U1!30!@baseboard_fab2_lib.baseboard_fab2(sch_1):page80_i101@mstr_sconn.sconn288_h44441003(chips)!SCONN288_H44441003_PIP-SCONN,HA!!!F191!DQS11N!!!!
S!M_H_DQS_DP<11>!J9U1!29!@baseboard_fab2_lib.baseboard_fab2(sch_1):page80_i101@mstr_sconn.sconn288_h44441003(chips)!SCONN288_H44441003_PIP-SCONN,HA!!!F191!DQS11P!!!!
S!M_H_DQS_DN<12>!J9U1!41!@baseboard_fab2_lib.baseboard_fab2(sch_1):page80_i101@mstr_sconn.sconn288_h44441003(chips)!SCONN288_H44441003_PIP-SCONN,HA!!!F191!DQS12N!!!!
S!M_H_DQS_DP<12>!J9U1!40!@baseboard_fab2_lib.baseboard_fab2(sch_1):page80_i101@mstr_sconn.sconn288_h44441003(chips)!SCONN288_H44441003_PIP-SCONN,HA!!!F191!DQS12P!!!!
S!M_H_DQS_DN<13>!J9U1!100!@baseboard_fab2_lib.baseboard_fab2(sch_1):page80_i101@mstr_sconn.sconn288_h44441003(chips)!SCONN288_H44441003_PIP-SCONN,HA!!!F191!DQS13N!!!!
S!M_H_DQS_DP<13>!J9U1!99!@baseboard_fab2_lib.baseboard_fab2(sch_1):page80_i101@mstr_sconn.sconn288_h44441003(chips)!SCONN288_H44441003_PIP-SCONN,HA!!!F191!DQS13P!!!!
S!M_H_DQS_DN<14>!J9U1!111!@baseboard_fab2_lib.baseboard_fab2(sch_1):page80_i101@mstr_sconn.sconn288_h44441003(chips)!SCONN288_H44441003_PIP-SCONN,HA!!!F191!DQS14N!!!!
S!M_H_DQS_DP<14>!J9U1!110!@baseboard_fab2_lib.baseboard_fab2(sch_1):page80_i101@mstr_sconn.sconn288_h44441003(chips)!SCONN288_H44441003_PIP-SCONN,HA!!!F191!DQS14P!!!!
S!M_H_DQS_DN<15>!J9U1!122!@baseboard_fab2_lib.baseboard_fab2(sch_1):page80_i101@mstr_sconn.sconn288_h44441003(chips)!SCONN288_H44441003_PIP-SCONN,HA!!!F191!DQS15N!!!!
S!M_H_DQS_DP<15>!J9U1!121!@baseboard_fab2_lib.baseboard_fab2(sch_1):page80_i101@mstr_sconn.sconn288_h44441003(chips)!SCONN288_H44441003_PIP-SCONN,HA!!!F191!DQS15P!!!!
S!M_H_DQS_DN<16>!J9U1!133!@baseboard_fab2_lib.baseboard_fab2(sch_1):page80_i101@mstr_sconn.sconn288_h44441003(chips)!SCONN288_H44441003_PIP-SCONN,HA!!!F191!DQS16N!!!!
S!M_H_DQS_DP<16>!J9U1!132!@baseboard_fab2_lib.baseboard_fab2(sch_1):page80_i101@mstr_sconn.sconn288_h44441003(chips)!SCONN288_H44441003_PIP-SCONN,HA!!!F191!DQS16P!!!!
S!M_H_DQS_DN<17>!J9U1!52!@baseboard_fab2_lib.baseboard_fab2(sch_1):page80_i101@mstr_sconn.sconn288_h44441003(chips)!SCONN288_H44441003_PIP-SCONN,HA!!!F191!DQS17N!!!!
S!M_H_DQS_DP<17>!J9U1!51!@baseboard_fab2_lib.baseboard_fab2(sch_1):page80_i101@mstr_sconn.sconn288_h44441003(chips)!SCONN288_H44441003_PIP-SCONN,HA!!!F191!DQS17P!!!!
S!M_H_DQS_DN<1>!J9U1!163!@baseboard_fab2_lib.baseboard_fab2(sch_1):page80_i101@mstr_sconn.sconn288_h44441003(chips)!SCONN288_H44441003_PIP-SCONN,HA!!!F191!DQS1N!!!!
S!M_H_DQS_DP<1>!J9U1!164!@baseboard_fab2_lib.baseboard_fab2(sch_1):page80_i101@mstr_sconn.sconn288_h44441003(chips)!SCONN288_H44441003_PIP-SCONN,HA!!!F191!DQS1P!!!!
S!M_H_DQS_DN<2>!J9U1!174!@baseboard_fab2_lib.baseboard_fab2(sch_1):page80_i101@mstr_sconn.sconn288_h44441003(chips)!SCONN288_H44441003_PIP-SCONN,HA!!!F191!DQS2N!!!!
S!M_H_DQS_DP<2>!J9U1!175!@baseboard_fab2_lib.baseboard_fab2(sch_1):page80_i101@mstr_sconn.sconn288_h44441003(chips)!SCONN288_H44441003_PIP-SCONN,HA!!!F191!DQS2P!!!!
S!M_H_DQS_DN<3>!J9U1!185!@baseboard_fab2_lib.baseboard_fab2(sch_1):page80_i101@mstr_sconn.sconn288_h44441003(chips)!SCONN288_H44441003_PIP-SCONN,HA!!!F191!DQS3N!!!!
S!M_H_DQS_DP<3>!J9U1!186!@baseboard_fab2_lib.baseboard_fab2(sch_1):page80_i101@mstr_sconn.sconn288_h44441003(chips)!SCONN288_H44441003_PIP-SCONN,HA!!!F191!DQS3P!!!!
S!M_H_DQS_DN<4>!J9U1!244!@baseboard_fab2_lib.baseboard_fab2(sch_1):page80_i101@mstr_sconn.sconn288_h44441003(chips)!SCONN288_H44441003_PIP-SCONN,HA!!!F191!DQS4N!!!!
S!M_H_DQS_DP<4>!J9U1!245!@baseboard_fab2_lib.baseboard_fab2(sch_1):page80_i101@mstr_sconn.sconn288_h44441003(chips)!SCONN288_H44441003_PIP-SCONN,HA!!!F191!DQS4P!!!!
S!M_H_DQS_DN<5>!J9U1!255!@baseboard_fab2_lib.baseboard_fab2(sch_1):page80_i101@mstr_sconn.sconn288_h44441003(chips)!SCONN288_H44441003_PIP-SCONN,HA!!!F191!DQS5N!!!!
S!M_H_DQS_DP<5>!J9U1!256!@baseboard_fab2_lib.baseboard_fab2(sch_1):page80_i101@mstr_sconn.sconn288_h44441003(chips)!SCONN288_H44441003_PIP-SCONN,HA!!!F191!DQS5P!!!!
S!M_H_DQS_DN<6>!J9U1!266!@baseboard_fab2_lib.baseboard_fab2(sch_1):page80_i101@mstr_sconn.sconn288_h44441003(chips)!SCONN288_H44441003_PIP-SCONN,HA!!!F191!DQS6N!!!!
S!M_H_DQS_DP<6>!J9U1!267!@baseboard_fab2_lib.baseboard_fab2(sch_1):page80_i101@mstr_sconn.sconn288_h44441003(chips)!SCONN288_H44441003_PIP-SCONN,HA!!!F191!DQS6P!!!!
S!M_H_DQS_DN<7>!J9U1!277!@baseboard_fab2_lib.baseboard_fab2(sch_1):page80_i101@mstr_sconn.sconn288_h44441003(chips)!SCONN288_H44441003_PIP-SCONN,HA!!!F191!DQS7N!!!!
S!M_H_DQS_DP<7>!J9U1!278!@baseboard_fab2_lib.baseboard_fab2(sch_1):page80_i101@mstr_sconn.sconn288_h44441003(chips)!SCONN288_H44441003_PIP-SCONN,HA!!!F191!DQS7P!!!!
S!M_H_DQS_DN<8>!J9U1!196!@baseboard_fab2_lib.baseboard_fab2(sch_1):page80_i101@mstr_sconn.sconn288_h44441003(chips)!SCONN288_H44441003_PIP-SCONN,HA!!!F191!DQS8N!!!!
S!M_H_DQS_DP<8>!J9U1!197!@baseboard_fab2_lib.baseboard_fab2(sch_1):page80_i101@mstr_sconn.sconn288_h44441003(chips)!SCONN288_H44441003_PIP-SCONN,HA!!!F191!DQS8P!!!!
S!M_H_DQS_DN<9>!J9U1!8!@baseboard_fab2_lib.baseboard_fab2(sch_1):page80_i101@mstr_sconn.sconn288_h44441003(chips)!SCONN288_H44441003_PIP-SCONN,HA!!!F191!DQS9N!!!!
S!M_H_DQS_DP<9>!J9U1!7!@baseboard_fab2_lib.baseboard_fab2(sch_1):page80_i101@mstr_sconn.sconn288_h44441003(chips)!SCONN288_H44441003_PIP-SCONN,HA!!!F191!DQS9P!!!!
S!GND!J9U1!283!@baseboard_fab2_lib.baseboard_fab2(sch_1):page80_i138@mstr_sconn.sconn288_h44441003(chips)!SCONN288_H44441003_PIP-SCONN,HA!!!F190!VSS(0)!!!!
S!GND!J9U1!261!@baseboard_fab2_lib.baseboard_fab2(sch_1):page80_i138@mstr_sconn.sconn288_h44441003(chips)!SCONN288_H44441003_PIP-SCONN,HA!!!F190!VSS(10)!!!!
S!GND!J9U1!259!@baseboard_fab2_lib.baseboard_fab2(sch_1):page80_i138@mstr_sconn.sconn288_h44441003(chips)!SCONN288_H44441003_PIP-SCONN,HA!!!F190!VSS(11)!!!!
S!GND!J9U1!257!@baseboard_fab2_lib.baseboard_fab2(sch_1):page80_i138@mstr_sconn.sconn288_h44441003(chips)!SCONN288_H44441003_PIP-SCONN,HA!!!F190!VSS(12)!!!!
S!GND!J9U1!254!@baseboard_fab2_lib.baseboard_fab2(sch_1):page80_i138@mstr_sconn.sconn288_h44441003(chips)!SCONN288_H44441003_PIP-SCONN,HA!!!F190!VSS(13)!!!!
S!GND!J9U1!252!@baseboard_fab2_lib.baseboard_fab2(sch_1):page80_i138@mstr_sconn.sconn288_h44441003(chips)!SCONN288_H44441003_PIP-SCONN,HA!!!F190!VSS(14)!!!!
S!GND!J9U1!250!@baseboard_fab2_lib.baseboard_fab2(sch_1):page80_i138@mstr_sconn.sconn288_h44441003(chips)!SCONN288_H44441003_PIP-SCONN,HA!!!F190!VSS(15)!!!!
S!GND!J9U1!248!@baseboard_fab2_lib.baseboard_fab2(sch_1):page80_i138@mstr_sconn.sconn288_h44441003(chips)!SCONN288_H44441003_PIP-SCONN,HA!!!F190!VSS(16)!!!!
S!GND!J9U1!246!@baseboard_fab2_lib.baseboard_fab2(sch_1):page80_i138@mstr_sconn.sconn288_h44441003(chips)!SCONN288_H44441003_PIP-SCONN,HA!!!F190!VSS(17)!!!!
S!GND!J9U1!243!@baseboard_fab2_lib.baseboard_fab2(sch_1):page80_i138@mstr_sconn.sconn288_h44441003(chips)!SCONN288_H44441003_PIP-SCONN,HA!!!F190!VSS(18)!!!!
S!GND!J9U1!241!@baseboard_fab2_lib.baseboard_fab2(sch_1):page80_i138@mstr_sconn.sconn288_h44441003(chips)!SCONN288_H44441003_PIP-SCONN,HA!!!F190!VSS(19)!!!!
S!GND!J9U1!281!@baseboard_fab2_lib.baseboard_fab2(sch_1):page80_i138@mstr_sconn.sconn288_h44441003(chips)!SCONN288_H44441003_PIP-SCONN,HA!!!F190!VSS(1)!!!!
S!GND!J9U1!239!@baseboard_fab2_lib.baseboard_fab2(sch_1):page80_i138@mstr_sconn.sconn288_h44441003(chips)!SCONN288_H44441003_PIP-SCONN,HA!!!F190!VSS(20)!!!!
S!GND!J9U1!202!@baseboard_fab2_lib.baseboard_fab2(sch_1):page80_i138@mstr_sconn.sconn288_h44441003(chips)!SCONN288_H44441003_PIP-SCONN,HA!!!F190!VSS(21)!!!!
S!GND!J9U1!200!@baseboard_fab2_lib.baseboard_fab2(sch_1):page80_i138@mstr_sconn.sconn288_h44441003(chips)!SCONN288_H44441003_PIP-SCONN,HA!!!F190!VSS(22)!!!!
S!GND!J9U1!198!@baseboard_fab2_lib.baseboard_fab2(sch_1):page80_i138@mstr_sconn.sconn288_h44441003(chips)!SCONN288_H44441003_PIP-SCONN,HA!!!F190!VSS(23)!!!!
S!GND!J9U1!195!@baseboard_fab2_lib.baseboard_fab2(sch_1):page80_i138@mstr_sconn.sconn288_h44441003(chips)!SCONN288_H44441003_PIP-SCONN,HA!!!F190!VSS(24)!!!!
S!GND!J9U1!193!@baseboard_fab2_lib.baseboard_fab2(sch_1):page80_i138@mstr_sconn.sconn288_h44441003(chips)!SCONN288_H44441003_PIP-SCONN,HA!!!F190!VSS(25)!!!!
S!GND!J9U1!191!@baseboard_fab2_lib.baseboard_fab2(sch_1):page80_i138@mstr_sconn.sconn288_h44441003(chips)!SCONN288_H44441003_PIP-SCONN,HA!!!F190!VSS(26)!!!!
S!GND!J9U1!189!@baseboard_fab2_lib.baseboard_fab2(sch_1):page80_i138@mstr_sconn.sconn288_h44441003(chips)!SCONN288_H44441003_PIP-SCONN,HA!!!F190!VSS(27)!!!!
S!GND!J9U1!187!@baseboard_fab2_lib.baseboard_fab2(sch_1):page80_i138@mstr_sconn.sconn288_h44441003(chips)!SCONN288_H44441003_PIP-SCONN,HA!!!F190!VSS(28)!!!!
S!GND!J9U1!184!@baseboard_fab2_lib.baseboard_fab2(sch_1):page80_i138@mstr_sconn.sconn288_h44441003(chips)!SCONN288_H44441003_PIP-SCONN,HA!!!F190!VSS(29)!!!!
S!GND!J9U1!279!@baseboard_fab2_lib.baseboard_fab2(sch_1):page80_i138@mstr_sconn.sconn288_h44441003(chips)!SCONN288_H44441003_PIP-SCONN,HA!!!F190!VSS(2)!!!!
S!GND!J9U1!182!@baseboard_fab2_lib.baseboard_fab2(sch_1):page80_i138@mstr_sconn.sconn288_h44441003(chips)!SCONN288_H44441003_PIP-SCONN,HA!!!F190!VSS(30)!!!!
S!GND!J9U1!180!@baseboard_fab2_lib.baseboard_fab2(sch_1):page80_i138@mstr_sconn.sconn288_h44441003(chips)!SCONN288_H44441003_PIP-SCONN,HA!!!F190!VSS(31)!!!!
S!GND!J9U1!178!@baseboard_fab2_lib.baseboard_fab2(sch_1):page80_i138@mstr_sconn.sconn288_h44441003(chips)!SCONN288_H44441003_PIP-SCONN,HA!!!F190!VSS(32)!!!!
S!GND!J9U1!176!@baseboard_fab2_lib.baseboard_fab2(sch_1):page80_i138@mstr_sconn.sconn288_h44441003(chips)!SCONN288_H44441003_PIP-SCONN,HA!!!F190!VSS(33)!!!!
S!GND!J9U1!173!@baseboard_fab2_lib.baseboard_fab2(sch_1):page80_i138@mstr_sconn.sconn288_h44441003(chips)!SCONN288_H44441003_PIP-SCONN,HA!!!F190!VSS(34)!!!!
S!GND!J9U1!171!@baseboard_fab2_lib.baseboard_fab2(sch_1):page80_i138@mstr_sconn.sconn288_h44441003(chips)!SCONN288_H44441003_PIP-SCONN,HA!!!F190!VSS(35)!!!!
S!GND!J9U1!169!@baseboard_fab2_lib.baseboard_fab2(sch_1):page80_i138@mstr_sconn.sconn288_h44441003(chips)!SCONN288_H44441003_PIP-SCONN,HA!!!F190!VSS(36)!!!!
S!GND!J9U1!167!@baseboard_fab2_lib.baseboard_fab2(sch_1):page80_i138@mstr_sconn.sconn288_h44441003(chips)!SCONN288_H44441003_PIP-SCONN,HA!!!F190!VSS(37)!!!!
S!GND!J9U1!165!@baseboard_fab2_lib.baseboard_fab2(sch_1):page80_i138@mstr_sconn.sconn288_h44441003(chips)!SCONN288_H44441003_PIP-SCONN,HA!!!F190!VSS(38)!!!!
S!GND!J9U1!162!@baseboard_fab2_lib.baseboard_fab2(sch_1):page80_i138@mstr_sconn.sconn288_h44441003(chips)!SCONN288_H44441003_PIP-SCONN,HA!!!F190!VSS(39)!!!!
S!GND!J9U1!276!@baseboard_fab2_lib.baseboard_fab2(sch_1):page80_i138@mstr_sconn.sconn288_h44441003(chips)!SCONN288_H44441003_PIP-SCONN,HA!!!F190!VSS(3)!!!!
S!GND!J9U1!160!@baseboard_fab2_lib.baseboard_fab2(sch_1):page80_i138@mstr_sconn.sconn288_h44441003(chips)!SCONN288_H44441003_PIP-SCONN,HA!!!F190!VSS(40)!!!!
S!GND!J9U1!158!@baseboard_fab2_lib.baseboard_fab2(sch_1):page80_i138@mstr_sconn.sconn288_h44441003(chips)!SCONN288_H44441003_PIP-SCONN,HA!!!F190!VSS(41)!!!!
S!GND!J9U1!156!@baseboard_fab2_lib.baseboard_fab2(sch_1):page80_i138@mstr_sconn.sconn288_h44441003(chips)!SCONN288_H44441003_PIP-SCONN,HA!!!F190!VSS(42)!!!!
S!GND!J9U1!154!@baseboard_fab2_lib.baseboard_fab2(sch_1):page80_i138@mstr_sconn.sconn288_h44441003(chips)!SCONN288_H44441003_PIP-SCONN,HA!!!F190!VSS(43)!!!!
S!GND!J9U1!151!@baseboard_fab2_lib.baseboard_fab2(sch_1):page80_i138@mstr_sconn.sconn288_h44441003(chips)!SCONN288_H44441003_PIP-SCONN,HA!!!F190!VSS(44)!!!!
S!GND!J9U1!149!@baseboard_fab2_lib.baseboard_fab2(sch_1):page80_i138@mstr_sconn.sconn288_h44441003(chips)!SCONN288_H44441003_PIP-SCONN,HA!!!F190!VSS(45)!!!!
S!GND!J9U1!147!@baseboard_fab2_lib.baseboard_fab2(sch_1):page80_i138@mstr_sconn.sconn288_h44441003(chips)!SCONN288_H44441003_PIP-SCONN,HA!!!F190!VSS(46)!!!!
S!GND!J9U1!138!@baseboard_fab2_lib.baseboard_fab2(sch_1):page80_i138@mstr_sconn.sconn288_h44441003(chips)!SCONN288_H44441003_PIP-SCONN,HA!!!F190!VSS(47)!!!!
S!GND!J9U1!136!@baseboard_fab2_lib.baseboard_fab2(sch_1):page80_i138@mstr_sconn.sconn288_h44441003(chips)!SCONN288_H44441003_PIP-SCONN,HA!!!F190!VSS(48)!!!!
S!GND!J9U1!134!@baseboard_fab2_lib.baseboard_fab2(sch_1):page80_i138@mstr_sconn.sconn288_h44441003(chips)!SCONN288_H44441003_PIP-SCONN,HA!!!F190!VSS(49)!!!!
S!GND!J9U1!274!@baseboard_fab2_lib.baseboard_fab2(sch_1):page80_i138@mstr_sconn.sconn288_h44441003(chips)!SCONN288_H44441003_PIP-SCONN,HA!!!F190!VSS(4)!!!!
S!GND!J9U1!131!@baseboard_fab2_lib.baseboard_fab2(sch_1):page80_i138@mstr_sconn.sconn288_h44441003(chips)!SCONN288_H44441003_PIP-SCONN,HA!!!F190!VSS(50)!!!!
S!GND!J9U1!129!@baseboard_fab2_lib.baseboard_fab2(sch_1):page80_i138@mstr_sconn.sconn288_h44441003(chips)!SCONN288_H44441003_PIP-SCONN,HA!!!F190!VSS(51)!!!!
S!GND!J9U1!127!@baseboard_fab2_lib.baseboard_fab2(sch_1):page80_i138@mstr_sconn.sconn288_h44441003(chips)!SCONN288_H44441003_PIP-SCONN,HA!!!F190!VSS(52)!!!!
S!GND!J9U1!125!@baseboard_fab2_lib.baseboard_fab2(sch_1):page80_i138@mstr_sconn.sconn288_h44441003(chips)!SCONN288_H44441003_PIP-SCONN,HA!!!F190!VSS(53)!!!!
S!GND!J9U1!123!@baseboard_fab2_lib.baseboard_fab2(sch_1):page80_i138@mstr_sconn.sconn288_h44441003(chips)!SCONN288_H44441003_PIP-SCONN,HA!!!F190!VSS(54)!!!!
S!GND!J9U1!120!@baseboard_fab2_lib.baseboard_fab2(sch_1):page80_i138@mstr_sconn.sconn288_h44441003(chips)!SCONN288_H44441003_PIP-SCONN,HA!!!F190!VSS(55)!!!!
S!GND!J9U1!118!@baseboard_fab2_lib.baseboard_fab2(sch_1):page80_i138@mstr_sconn.sconn288_h44441003(chips)!SCONN288_H44441003_PIP-SCONN,HA!!!F190!VSS(56)!!!!
S!GND!J9U1!116!@baseboard_fab2_lib.baseboard_fab2(sch_1):page80_i138@mstr_sconn.sconn288_h44441003(chips)!SCONN288_H44441003_PIP-SCONN,HA!!!F190!VSS(57)!!!!
S!GND!J9U1!114!@baseboard_fab2_lib.baseboard_fab2(sch_1):page80_i138@mstr_sconn.sconn288_h44441003(chips)!SCONN288_H44441003_PIP-SCONN,HA!!!F190!VSS(58)!!!!
S!GND!J9U1!112!@baseboard_fab2_lib.baseboard_fab2(sch_1):page80_i138@mstr_sconn.sconn288_h44441003(chips)!SCONN288_H44441003_PIP-SCONN,HA!!!F190!VSS(59)!!!!
S!GND!J9U1!272!@baseboard_fab2_lib.baseboard_fab2(sch_1):page80_i138@mstr_sconn.sconn288_h44441003(chips)!SCONN288_H44441003_PIP-SCONN,HA!!!F190!VSS(5)!!!!
S!GND!J9U1!109!@baseboard_fab2_lib.baseboard_fab2(sch_1):page80_i138@mstr_sconn.sconn288_h44441003(chips)!SCONN288_H44441003_PIP-SCONN,HA!!!F190!VSS(60)!!!!
S!GND!J9U1!107!@baseboard_fab2_lib.baseboard_fab2(sch_1):page80_i138@mstr_sconn.sconn288_h44441003(chips)!SCONN288_H44441003_PIP-SCONN,HA!!!F190!VSS(61)!!!!
S!GND!J9U1!105!@baseboard_fab2_lib.baseboard_fab2(sch_1):page80_i138@mstr_sconn.sconn288_h44441003(chips)!SCONN288_H44441003_PIP-SCONN,HA!!!F190!VSS(62)!!!!
S!GND!J9U1!103!@baseboard_fab2_lib.baseboard_fab2(sch_1):page80_i138@mstr_sconn.sconn288_h44441003(chips)!SCONN288_H44441003_PIP-SCONN,HA!!!F190!VSS(63)!!!!
S!GND!J9U1!101!@baseboard_fab2_lib.baseboard_fab2(sch_1):page80_i138@mstr_sconn.sconn288_h44441003(chips)!SCONN288_H44441003_PIP-SCONN,HA!!!F190!VSS(64)!!!!
S!GND!J9U1!98!@baseboard_fab2_lib.baseboard_fab2(sch_1):page80_i138@mstr_sconn.sconn288_h44441003(chips)!SCONN288_H44441003_PIP-SCONN,HA!!!F190!VSS(65)!!!!
S!GND!J9U1!96!@baseboard_fab2_lib.baseboard_fab2(sch_1):page80_i138@mstr_sconn.sconn288_h44441003(chips)!SCONN288_H44441003_PIP-SCONN,HA!!!F190!VSS(66)!!!!
S!GND!J9U1!94!@baseboard_fab2_lib.baseboard_fab2(sch_1):page80_i138@mstr_sconn.sconn288_h44441003(chips)!SCONN288_H44441003_PIP-SCONN,HA!!!F190!VSS(67)!!!!
S!GND!J9U1!57!@baseboard_fab2_lib.baseboard_fab2(sch_1):page80_i138@mstr_sconn.sconn288_h44441003(chips)!SCONN288_H44441003_PIP-SCONN,HA!!!F190!VSS(68)!!!!
S!GND!J9U1!55!@baseboard_fab2_lib.baseboard_fab2(sch_1):page80_i138@mstr_sconn.sconn288_h44441003(chips)!SCONN288_H44441003_PIP-SCONN,HA!!!F190!VSS(69)!!!!
S!GND!J9U1!270!@baseboard_fab2_lib.baseboard_fab2(sch_1):page80_i138@mstr_sconn.sconn288_h44441003(chips)!SCONN288_H44441003_PIP-SCONN,HA!!!F190!VSS(6)!!!!
S!GND!J9U1!53!@baseboard_fab2_lib.baseboard_fab2(sch_1):page80_i138@mstr_sconn.sconn288_h44441003(chips)!SCONN288_H44441003_PIP-SCONN,HA!!!F190!VSS(70)!!!!
S!GND!J9U1!50!@baseboard_fab2_lib.baseboard_fab2(sch_1):page80_i138@mstr_sconn.sconn288_h44441003(chips)!SCONN288_H44441003_PIP-SCONN,HA!!!F190!VSS(71)!!!!
S!GND!J9U1!48!@baseboard_fab2_lib.baseboard_fab2(sch_1):page80_i138@mstr_sconn.sconn288_h44441003(chips)!SCONN288_H44441003_PIP-SCONN,HA!!!F190!VSS(72)!!!!
S!GND!J9U1!46!@baseboard_fab2_lib.baseboard_fab2(sch_1):page80_i138@mstr_sconn.sconn288_h44441003(chips)!SCONN288_H44441003_PIP-SCONN,HA!!!F190!VSS(73)!!!!
S!GND!J9U1!44!@baseboard_fab2_lib.baseboard_fab2(sch_1):page80_i138@mstr_sconn.sconn288_h44441003(chips)!SCONN288_H44441003_PIP-SCONN,HA!!!F190!VSS(74)!!!!
S!GND!J9U1!42!@baseboard_fab2_lib.baseboard_fab2(sch_1):page80_i138@mstr_sconn.sconn288_h44441003(chips)!SCONN288_H44441003_PIP-SCONN,HA!!!F190!VSS(75)!!!!
S!GND!J9U1!39!@baseboard_fab2_lib.baseboard_fab2(sch_1):page80_i138@mstr_sconn.sconn288_h44441003(chips)!SCONN288_H44441003_PIP-SCONN,HA!!!F190!VSS(76)!!!!
S!GND!J9U1!37!@baseboard_fab2_lib.baseboard_fab2(sch_1):page80_i138@mstr_sconn.sconn288_h44441003(chips)!SCONN288_H44441003_PIP-SCONN,HA!!!F190!VSS(77)!!!!
S!GND!J9U1!35!@baseboard_fab2_lib.baseboard_fab2(sch_1):page80_i138@mstr_sconn.sconn288_h44441003(chips)!SCONN288_H44441003_PIP-SCONN,HA!!!F190!VSS(78)!!!!
S!GND!J9U1!33!@baseboard_fab2_lib.baseboard_fab2(sch_1):page80_i138@mstr_sconn.sconn288_h44441003(chips)!SCONN288_H44441003_PIP-SCONN,HA!!!F190!VSS(79)!!!!
S!GND!J9U1!268!@baseboard_fab2_lib.baseboard_fab2(sch_1):page80_i138@mstr_sconn.sconn288_h44441003(chips)!SCONN288_H44441003_PIP-SCONN,HA!!!F190!VSS(7)!!!!
S!GND!J9U1!31!@baseboard_fab2_lib.baseboard_fab2(sch_1):page80_i138@mstr_sconn.sconn288_h44441003(chips)!SCONN288_H44441003_PIP-SCONN,HA!!!F190!VSS(80)!!!!
S!GND!J9U1!28!@baseboard_fab2_lib.baseboard_fab2(sch_1):page80_i138@mstr_sconn.sconn288_h44441003(chips)!SCONN288_H44441003_PIP-SCONN,HA!!!F190!VSS(81)!!!!
S!GND!J9U1!26!@baseboard_fab2_lib.baseboard_fab2(sch_1):page80_i138@mstr_sconn.sconn288_h44441003(chips)!SCONN288_H44441003_PIP-SCONN,HA!!!F190!VSS(82)!!!!
S!GND!J9U1!24!@baseboard_fab2_lib.baseboard_fab2(sch_1):page80_i138@mstr_sconn.sconn288_h44441003(chips)!SCONN288_H44441003_PIP-SCONN,HA!!!F190!VSS(83)!!!!
S!GND!J9U1!22!@baseboard_fab2_lib.baseboard_fab2(sch_1):page80_i138@mstr_sconn.sconn288_h44441003(chips)!SCONN288_H44441003_PIP-SCONN,HA!!!F190!VSS(84)!!!!
S!GND!J9U1!20!@baseboard_fab2_lib.baseboard_fab2(sch_1):page80_i138@mstr_sconn.sconn288_h44441003(chips)!SCONN288_H44441003_PIP-SCONN,HA!!!F190!VSS(85)!!!!
S!GND!J9U1!17!@baseboard_fab2_lib.baseboard_fab2(sch_1):page80_i138@mstr_sconn.sconn288_h44441003(chips)!SCONN288_H44441003_PIP-SCONN,HA!!!F190!VSS(86)!!!!
S!GND!J9U1!15!@baseboard_fab2_lib.baseboard_fab2(sch_1):page80_i138@mstr_sconn.sconn288_h44441003(chips)!SCONN288_H44441003_PIP-SCONN,HA!!!F190!VSS(87)!!!!
S!GND!J9U1!13!@baseboard_fab2_lib.baseboard_fab2(sch_1):page80_i138@mstr_sconn.sconn288_h44441003(chips)!SCONN288_H44441003_PIP-SCONN,HA!!!F190!VSS(88)!!!!
S!GND!J9U1!11!@baseboard_fab2_lib.baseboard_fab2(sch_1):page80_i138@mstr_sconn.sconn288_h44441003(chips)!SCONN288_H44441003_PIP-SCONN,HA!!!F190!VSS(89)!!!!
S!GND!J9U1!265!@baseboard_fab2_lib.baseboard_fab2(sch_1):page80_i138@mstr_sconn.sconn288_h44441003(chips)!SCONN288_H44441003_PIP-SCONN,HA!!!F190!VSS(8)!!!!
S!GND!J9U1!9!@baseboard_fab2_lib.baseboard_fab2(sch_1):page80_i138@mstr_sconn.sconn288_h44441003(chips)!SCONN288_H44441003_PIP-SCONN,HA!!!F190!VSS(90)!!!!
S!GND!J9U1!6!@baseboard_fab2_lib.baseboard_fab2(sch_1):page80_i138@mstr_sconn.sconn288_h44441003(chips)!SCONN288_H44441003_PIP-SCONN,HA!!!F190!VSS(91)!!!!
S!GND!J9U1!4!@baseboard_fab2_lib.baseboard_fab2(sch_1):page80_i138@mstr_sconn.sconn288_h44441003(chips)!SCONN288_H44441003_PIP-SCONN,HA!!!F190!VSS(92)!!!!
S!GND!J9U1!2!@baseboard_fab2_lib.baseboard_fab2(sch_1):page80_i138@mstr_sconn.sconn288_h44441003(chips)!SCONN288_H44441003_PIP-SCONN,HA!!!F190!VSS(93)!!!!
S!GND!J9U1!263!@baseboard_fab2_lib.baseboard_fab2(sch_1):page80_i138@mstr_sconn.sconn288_h44441003(chips)!SCONN288_H44441003_PIP-SCONN,HA!!!F190!VSS(9)!!!!
S!P12V_NVDIMM_GHJ!J9U1!145!@baseboard_fab2_lib.baseboard_fab2(sch_1):page80_i56@mstr_sconn.sconn288_h44441003(chips)!SCONN288_H44441003_PIP-SCONN,HA!!!F189!\12v\(0)!!!!
S!P12V_NVDIMM_GHJ!J9U1!1!@baseboard_fab2_lib.baseboard_fab2(sch_1):page80_i56@mstr_sconn.sconn288_h44441003(chips)!SCONN288_H44441003_PIP-SCONN,HA!!!F189!\12v\(1)!!!!
S!PVDDQ_GHJ!J9U1!236!@baseboard_fab2_lib.baseboard_fab2(sch_1):page80_i56@mstr_sconn.sconn288_h44441003(chips)!SCONN288_H44441003_PIP-SCONN,HA!!!F189!VDD(0)!!!!
S!PVDDQ_GHJ!J9U1!209!@baseboard_fab2_lib.baseboard_fab2(sch_1):page80_i56@mstr_sconn.sconn288_h44441003(chips)!SCONN288_H44441003_PIP-SCONN,HA!!!F189!VDD(10)!!!!
S!PVDDQ_GHJ!J9U1!206!@baseboard_fab2_lib.baseboard_fab2(sch_1):page80_i56@mstr_sconn.sconn288_h44441003(chips)!SCONN288_H44441003_PIP-SCONN,HA!!!F189!VDD(11)!!!!
S!PVDDQ_GHJ!J9U1!204!@baseboard_fab2_lib.baseboard_fab2(sch_1):page80_i56@mstr_sconn.sconn288_h44441003(chips)!SCONN288_H44441003_PIP-SCONN,HA!!!F189!VDD(12)!!!!
S!PVDDQ_GHJ!J9U1!92!@baseboard_fab2_lib.baseboard_fab2(sch_1):page80_i56@mstr_sconn.sconn288_h44441003(chips)!SCONN288_H44441003_PIP-SCONN,HA!!!F189!VDD(13)!!!!
S!PVDDQ_GHJ!J9U1!90!@baseboard_fab2_lib.baseboard_fab2(sch_1):page80_i56@mstr_sconn.sconn288_h44441003(chips)!SCONN288_H44441003_PIP-SCONN,HA!!!F189!VDD(14)!!!!
S!PVDDQ_GHJ!J9U1!88!@baseboard_fab2_lib.baseboard_fab2(sch_1):page80_i56@mstr_sconn.sconn288_h44441003(chips)!SCONN288_H44441003_PIP-SCONN,HA!!!F189!VDD(15)!!!!
S!PVDDQ_GHJ!J9U1!85!@baseboard_fab2_lib.baseboard_fab2(sch_1):page80_i56@mstr_sconn.sconn288_h44441003(chips)!SCONN288_H44441003_PIP-SCONN,HA!!!F189!VDD(16)!!!!
S!PVDDQ_GHJ!J9U1!83!@baseboard_fab2_lib.baseboard_fab2(sch_1):page80_i56@mstr_sconn.sconn288_h44441003(chips)!SCONN288_H44441003_PIP-SCONN,HA!!!F189!VDD(17)!!!!
S!PVDDQ_GHJ!J9U1!80!@baseboard_fab2_lib.baseboard_fab2(sch_1):page80_i56@mstr_sconn.sconn288_h44441003(chips)!SCONN288_H44441003_PIP-SCONN,HA!!!F189!VDD(18)!!!!
S!PVDDQ_GHJ!J9U1!76!@baseboard_fab2_lib.baseboard_fab2(sch_1):page80_i56@mstr_sconn.sconn288_h44441003(chips)!SCONN288_H44441003_PIP-SCONN,HA!!!F189!VDD(19)!!!!
S!PVDDQ_GHJ!J9U1!233!@baseboard_fab2_lib.baseboard_fab2(sch_1):page80_i56@mstr_sconn.sconn288_h44441003(chips)!SCONN288_H44441003_PIP-SCONN,HA!!!F189!VDD(1)!!!!
S!PVDDQ_GHJ!J9U1!73!@baseboard_fab2_lib.baseboard_fab2(sch_1):page80_i56@mstr_sconn.sconn288_h44441003(chips)!SCONN288_H44441003_PIP-SCONN,HA!!!F189!VDD(20)!!!!
S!PVDDQ_GHJ!J9U1!70!@baseboard_fab2_lib.baseboard_fab2(sch_1):page80_i56@mstr_sconn.sconn288_h44441003(chips)!SCONN288_H44441003_PIP-SCONN,HA!!!F189!VDD(21)!!!!
S!PVDDQ_GHJ!J9U1!67!@baseboard_fab2_lib.baseboard_fab2(sch_1):page80_i56@mstr_sconn.sconn288_h44441003(chips)!SCONN288_H44441003_PIP-SCONN,HA!!!F189!VDD(22)!!!!
S!PVDDQ_GHJ!J9U1!64!@baseboard_fab2_lib.baseboard_fab2(sch_1):page80_i56@mstr_sconn.sconn288_h44441003(chips)!SCONN288_H44441003_PIP-SCONN,HA!!!F189!VDD(23)!!!!
S!PVDDQ_GHJ!J9U1!61!@baseboard_fab2_lib.baseboard_fab2(sch_1):page80_i56@mstr_sconn.sconn288_h44441003(chips)!SCONN288_H44441003_PIP-SCONN,HA!!!F189!VDD(24)!!!!
S!PVDDQ_GHJ!J9U1!59!@baseboard_fab2_lib.baseboard_fab2(sch_1):page80_i56@mstr_sconn.sconn288_h44441003(chips)!SCONN288_H44441003_PIP-SCONN,HA!!!F189!VDD(25)!!!!
S!PVDDQ_GHJ!J9U1!231!@baseboard_fab2_lib.baseboard_fab2(sch_1):page80_i56@mstr_sconn.sconn288_h44441003(chips)!SCONN288_H44441003_PIP-SCONN,HA!!!F189!VDD(2)!!!!
S!PVDDQ_GHJ!J9U1!229!@baseboard_fab2_lib.baseboard_fab2(sch_1):page80_i56@mstr_sconn.sconn288_h44441003(chips)!SCONN288_H44441003_PIP-SCONN,HA!!!F189!VDD(3)!!!!
S!PVDDQ_GHJ!J9U1!226!@baseboard_fab2_lib.baseboard_fab2(sch_1):page80_i56@mstr_sconn.sconn288_h44441003(chips)!SCONN288_H44441003_PIP-SCONN,HA!!!F189!VDD(4)!!!!
S!PVDDQ_GHJ!J9U1!223!@baseboard_fab2_lib.baseboard_fab2(sch_1):page80_i56@mstr_sconn.sconn288_h44441003(chips)!SCONN288_H44441003_PIP-SCONN,HA!!!F189!VDD(5)!!!!
S!PVDDQ_GHJ!J9U1!220!@baseboard_fab2_lib.baseboard_fab2(sch_1):page80_i56@mstr_sconn.sconn288_h44441003(chips)!SCONN288_H44441003_PIP-SCONN,HA!!!F189!VDD(6)!!!!
S!PVDDQ_GHJ!J9U1!217!@baseboard_fab2_lib.baseboard_fab2(sch_1):page80_i56@mstr_sconn.sconn288_h44441003(chips)!SCONN288_H44441003_PIP-SCONN,HA!!!F189!VDD(7)!!!!
S!PVDDQ_GHJ!J9U1!215!@baseboard_fab2_lib.baseboard_fab2(sch_1):page80_i56@mstr_sconn.sconn288_h44441003(chips)!SCONN288_H44441003_PIP-SCONN,HA!!!F189!VDD(8)!!!!
S!PVDDQ_GHJ!J9U1!212!@baseboard_fab2_lib.baseboard_fab2(sch_1):page80_i56@mstr_sconn.sconn288_h44441003(chips)!SCONN288_H44441003_PIP-SCONN,HA!!!F189!VDD(9)!!!!
S!PVPP_GHJ!J9U1!287!@baseboard_fab2_lib.baseboard_fab2(sch_1):page80_i56@mstr_sconn.sconn288_h44441003(chips)!SCONN288_H44441003_PIP-SCONN,HA!!!F189!VPP(0)!!!!
S!PVPP_GHJ!J9U1!286!@baseboard_fab2_lib.baseboard_fab2(sch_1):page80_i56@mstr_sconn.sconn288_h44441003(chips)!SCONN288_H44441003_PIP-SCONN,HA!!!F189!VPP(1)!!!!
S!PVPP_GHJ!J9U1!288!@baseboard_fab2_lib.baseboard_fab2(sch_1):page80_i56@mstr_sconn.sconn288_h44441003(chips)!SCONN288_H44441003_PIP-SCONN,HA!!!F189!VPP(2)!!!!
S!PVPP_GHJ!J9U1!143!@baseboard_fab2_lib.baseboard_fab2(sch_1):page80_i56@mstr_sconn.sconn288_h44441003(chips)!SCONN288_H44441003_PIP-SCONN,HA!!!F189!VPP(3)!!!!
S!PVPP_GHJ!J9U1!142!@baseboard_fab2_lib.baseboard_fab2(sch_1):page80_i56@mstr_sconn.sconn288_h44441003(chips)!SCONN288_H44441003_PIP-SCONN,HA!!!F189!VPP(4)!!!!
S!PVTT_GHJ!J9U1!221!@baseboard_fab2_lib.baseboard_fab2(sch_1):page80_i56@mstr_sconn.sconn288_h44441003(chips)!SCONN288_H44441003_PIP-SCONN,HA!!!F189!VTT(0)!!!!
S!PVTT_GHJ!J9U1!77!@baseboard_fab2_lib.baseboard_fab2(sch_1):page80_i56@mstr_sconn.sconn288_h44441003(chips)!SCONN288_H44441003_PIP-SCONN,HA!!!F189!VTT(1)!!!!
S!M_J_MA<0>!J9U2!79!@baseboard_fab2_lib.baseboard_fab2(sch_1):page82_i187@mstr_sconn.sconn288_h44441003(chips)!SCONN288_H44441003_PIP-SCONN,HA!!!F188!A0!!!!
S!M_J_MA<1>!J9U2!72!@baseboard_fab2_lib.baseboard_fab2(sch_1):page82_i187@mstr_sconn.sconn288_h44441003(chips)!SCONN288_H44441003_PIP-SCONN,HA!!!F188!A1!!!!
S!M_J_MA<10>!J9U2!225!@baseboard_fab2_lib.baseboard_fab2(sch_1):page82_i187@mstr_sconn.sconn288_h44441003(chips)!SCONN288_H44441003_PIP-SCONN,HA!!!F188!A10!!!!
S!M_J_MA<11>!J9U2!210!@baseboard_fab2_lib.baseboard_fab2(sch_1):page82_i187@mstr_sconn.sconn288_h44441003(chips)!SCONN288_H44441003_PIP-SCONN,HA!!!F188!A11!!!!
S!M_J_MA<12>!J9U2!65!@baseboard_fab2_lib.baseboard_fab2(sch_1):page82_i187@mstr_sconn.sconn288_h44441003(chips)!SCONN288_H44441003_PIP-SCONN,HA!!!F188!A12!!!!
S!M_J_MA<13>!J9U2!232!@baseboard_fab2_lib.baseboard_fab2(sch_1):page82_i187@mstr_sconn.sconn288_h44441003(chips)!SCONN288_H44441003_PIP-SCONN,HA!!!F188!A13!!!!
S!M_J_MA<14>!J9U2!228!@baseboard_fab2_lib.baseboard_fab2(sch_1):page82_i187@mstr_sconn.sconn288_h44441003(chips)!SCONN288_H44441003_PIP-SCONN,HA!!!F188!A14_WE_N!!!!
S!M_J_MA<15>!J9U2!86!@baseboard_fab2_lib.baseboard_fab2(sch_1):page82_i187@mstr_sconn.sconn288_h44441003(chips)!SCONN288_H44441003_PIP-SCONN,HA!!!F188!A15_CAS_N!!!!
S!M_J_MA<16>!J9U2!82!@baseboard_fab2_lib.baseboard_fab2(sch_1):page82_i187@mstr_sconn.sconn288_h44441003(chips)!SCONN288_H44441003_PIP-SCONN,HA!!!F188!A16_RAS_N!!!!
S!M_J_MA<17>!J9U2!234!@baseboard_fab2_lib.baseboard_fab2(sch_1):page82_i187@mstr_sconn.sconn288_h44441003(chips)!SCONN288_H44441003_PIP-SCONN,HA!!!F188!A17!!!!
S!M_J_MA<2>!J9U2!216!@baseboard_fab2_lib.baseboard_fab2(sch_1):page82_i187@mstr_sconn.sconn288_h44441003(chips)!SCONN288_H44441003_PIP-SCONN,HA!!!F188!A2!!!!
S!M_J_MA<3>!J9U2!71!@baseboard_fab2_lib.baseboard_fab2(sch_1):page82_i187@mstr_sconn.sconn288_h44441003(chips)!SCONN288_H44441003_PIP-SCONN,HA!!!F188!A3!!!!
S!M_J_MA<4>!J9U2!214!@baseboard_fab2_lib.baseboard_fab2(sch_1):page82_i187@mstr_sconn.sconn288_h44441003(chips)!SCONN288_H44441003_PIP-SCONN,HA!!!F188!A4!!!!
S!M_J_MA<5>!J9U2!213!@baseboard_fab2_lib.baseboard_fab2(sch_1):page82_i187@mstr_sconn.sconn288_h44441003(chips)!SCONN288_H44441003_PIP-SCONN,HA!!!F188!A5!!!!
S!M_J_MA<6>!J9U2!69!@baseboard_fab2_lib.baseboard_fab2(sch_1):page82_i187@mstr_sconn.sconn288_h44441003(chips)!SCONN288_H44441003_PIP-SCONN,HA!!!F188!A6!!!!
S!M_J_MA<7>!J9U2!211!@baseboard_fab2_lib.baseboard_fab2(sch_1):page82_i187@mstr_sconn.sconn288_h44441003(chips)!SCONN288_H44441003_PIP-SCONN,HA!!!F188!A7!!!!
S!M_J_MA<8>!J9U2!68!@baseboard_fab2_lib.baseboard_fab2(sch_1):page82_i187@mstr_sconn.sconn288_h44441003(chips)!SCONN288_H44441003_PIP-SCONN,HA!!!F188!A8!!!!
S!M_J_MA<9>!J9U2!66!@baseboard_fab2_lib.baseboard_fab2(sch_1):page82_i187@mstr_sconn.sconn288_h44441003(chips)!SCONN288_H44441003_PIP-SCONN,HA!!!F188!A9!!!!
S!M_J_ACT_N!J9U2!62!@baseboard_fab2_lib.baseboard_fab2(sch_1):page82_i187@mstr_sconn.sconn288_h44441003(chips)!SCONN288_H44441003_PIP-SCONN,HA!!!F188!ACT_N!!!!
S!M_J_ALERT_N!J9U2!208!@baseboard_fab2_lib.baseboard_fab2(sch_1):page82_i187@mstr_sconn.sconn288_h44441003(chips)!SCONN288_H44441003_PIP-SCONN,HA!!!F188!ALERT_N!!!!
S!M_J_BA<0>!J9U2!81!@baseboard_fab2_lib.baseboard_fab2(sch_1):page82_i187@mstr_sconn.sconn288_h44441003(chips)!SCONN288_H44441003_PIP-SCONN,HA!!!F188!BA(0)!!!!
S!M_J_BA<1>!J9U2!224!@baseboard_fab2_lib.baseboard_fab2(sch_1):page82_i187@mstr_sconn.sconn288_h44441003(chips)!SCONN288_H44441003_PIP-SCONN,HA!!!F188!BA(1)!!!!
S!M_J_BG<0>!J9U2!63!@baseboard_fab2_lib.baseboard_fab2(sch_1):page82_i187@mstr_sconn.sconn288_h44441003(chips)!SCONN288_H44441003_PIP-SCONN,HA!!!F188!BG(0)!!!!
S!M_J_BG<1>!J9U2!207!@baseboard_fab2_lib.baseboard_fab2(sch_1):page82_i187@mstr_sconn.sconn288_h44441003(chips)!SCONN288_H44441003_PIP-SCONN,HA!!!F188!BG(1)!!!!
S!M_J_C<2>!J9U2!235!@baseboard_fab2_lib.baseboard_fab2(sch_1):page82_i187@mstr_sconn.sconn288_h44441003(chips)!SCONN288_H44441003_PIP-SCONN,HA!!!F188!C(2)!!!!
S!M_J_ECC<0>!J9U2!49!@baseboard_fab2_lib.baseboard_fab2(sch_1):page82_i187@mstr_sconn.sconn288_h44441003(chips)!SCONN288_H44441003_PIP-SCONN,HA!!!F188!CB(0)!!!!
S!M_J_ECC<1>!J9U2!194!@baseboard_fab2_lib.baseboard_fab2(sch_1):page82_i187@mstr_sconn.sconn288_h44441003(chips)!SCONN288_H44441003_PIP-SCONN,HA!!!F188!CB(1)!!!!
S!M_J_ECC<2>!J9U2!56!@baseboard_fab2_lib.baseboard_fab2(sch_1):page82_i187@mstr_sconn.sconn288_h44441003(chips)!SCONN288_H44441003_PIP-SCONN,HA!!!F188!CB(2)!!!!
S!M_J_ECC<3>!J9U2!201!@baseboard_fab2_lib.baseboard_fab2(sch_1):page82_i187@mstr_sconn.sconn288_h44441003(chips)!SCONN288_H44441003_PIP-SCONN,HA!!!F188!CB(3)!!!!
S!M_J_ECC<4>!J9U2!47!@baseboard_fab2_lib.baseboard_fab2(sch_1):page82_i187@mstr_sconn.sconn288_h44441003(chips)!SCONN288_H44441003_PIP-SCONN,HA!!!F188!CB(4)!!!!
S!M_J_ECC<5>!J9U2!192!@baseboard_fab2_lib.baseboard_fab2(sch_1):page82_i187@mstr_sconn.sconn288_h44441003(chips)!SCONN288_H44441003_PIP-SCONN,HA!!!F188!CB(5)!!!!
S!M_J_ECC<6>!J9U2!54!@baseboard_fab2_lib.baseboard_fab2(sch_1):page82_i187@mstr_sconn.sconn288_h44441003(chips)!SCONN288_H44441003_PIP-SCONN,HA!!!F188!CB(6)!!!!
S!M_J_ECC<7>!J9U2!199!@baseboard_fab2_lib.baseboard_fab2(sch_1):page82_i187@mstr_sconn.sconn288_h44441003(chips)!SCONN288_H44441003_PIP-SCONN,HA!!!F188!CB(7)!!!!
S!M_J_CLK_DN<2>!J9U2!75!@baseboard_fab2_lib.baseboard_fab2(sch_1):page82_i187@mstr_sconn.sconn288_h44441003(chips)!SCONN288_H44441003_PIP-SCONN,HA!!!F188!CK0N!!!!
S!M_J_CLK_DP<2>!J9U2!74!@baseboard_fab2_lib.baseboard_fab2(sch_1):page82_i187@mstr_sconn.sconn288_h44441003(chips)!SCONN288_H44441003_PIP-SCONN,HA!!!F188!CK0P!!!!
S!M_J_CLK_DN<3>!J9U2!219!@baseboard_fab2_lib.baseboard_fab2(sch_1):page82_i187@mstr_sconn.sconn288_h44441003(chips)!SCONN288_H44441003_PIP-SCONN,HA!!!F188!CK1N!!!!
S!M_J_CLK_DP<3>!J9U2!218!@baseboard_fab2_lib.baseboard_fab2(sch_1):page82_i187@mstr_sconn.sconn288_h44441003(chips)!SCONN288_H44441003_PIP-SCONN,HA!!!F188!CK1P!!!!
S!M_J_CKE<2>!J9U2!60!@baseboard_fab2_lib.baseboard_fab2(sch_1):page82_i187@mstr_sconn.sconn288_h44441003(chips)!SCONN288_H44441003_PIP-SCONN,HA!!!F188!CKE(0)!!!!
S!M_J_CKE<3>!J9U2!203!@baseboard_fab2_lib.baseboard_fab2(sch_1):page82_i187@mstr_sconn.sconn288_h44441003(chips)!SCONN288_H44441003_PIP-SCONN,HA!!!F188!CKE(1)!!!!
S!M_J_DQ<0>!J9U2!5!@baseboard_fab2_lib.baseboard_fab2(sch_1):page82_i187@mstr_sconn.sconn288_h44441003(chips)!SCONN288_H44441003_PIP-SCONN,HA!!!F188!DQ(0)!!!!
S!M_J_DQ<10>!J9U2!23!@baseboard_fab2_lib.baseboard_fab2(sch_1):page82_i187@mstr_sconn.sconn288_h44441003(chips)!SCONN288_H44441003_PIP-SCONN,HA!!!F188!DQ(10)!!!!
S!M_J_DQ<11>!J9U2!168!@baseboard_fab2_lib.baseboard_fab2(sch_1):page82_i187@mstr_sconn.sconn288_h44441003(chips)!SCONN288_H44441003_PIP-SCONN,HA!!!F188!DQ(11)!!!!
S!M_J_DQ<12>!J9U2!14!@baseboard_fab2_lib.baseboard_fab2(sch_1):page82_i187@mstr_sconn.sconn288_h44441003(chips)!SCONN288_H44441003_PIP-SCONN,HA!!!F188!DQ(12)!!!!
S!M_J_DQ<13>!J9U2!159!@baseboard_fab2_lib.baseboard_fab2(sch_1):page82_i187@mstr_sconn.sconn288_h44441003(chips)!SCONN288_H44441003_PIP-SCONN,HA!!!F188!DQ(13)!!!!
S!M_J_DQ<14>!J9U2!21!@baseboard_fab2_lib.baseboard_fab2(sch_1):page82_i187@mstr_sconn.sconn288_h44441003(chips)!SCONN288_H44441003_PIP-SCONN,HA!!!F188!DQ(14)!!!!
S!M_J_DQ<15>!J9U2!166!@baseboard_fab2_lib.baseboard_fab2(sch_1):page82_i187@mstr_sconn.sconn288_h44441003(chips)!SCONN288_H44441003_PIP-SCONN,HA!!!F188!DQ(15)!!!!
S!M_J_DQ<16>!J9U2!27!@baseboard_fab2_lib.baseboard_fab2(sch_1):page82_i187@mstr_sconn.sconn288_h44441003(chips)!SCONN288_H44441003_PIP-SCONN,HA!!!F188!DQ(16)!!!!
S!M_J_DQ<17>!J9U2!172!@baseboard_fab2_lib.baseboard_fab2(sch_1):page82_i187@mstr_sconn.sconn288_h44441003(chips)!SCONN288_H44441003_PIP-SCONN,HA!!!F188!DQ(17)!!!!
S!M_J_DQ<18>!J9U2!34!@baseboard_fab2_lib.baseboard_fab2(sch_1):page82_i187@mstr_sconn.sconn288_h44441003(chips)!SCONN288_H44441003_PIP-SCONN,HA!!!F188!DQ(18)!!!!
S!M_J_DQ<19>!J9U2!179!@baseboard_fab2_lib.baseboard_fab2(sch_1):page82_i187@mstr_sconn.sconn288_h44441003(chips)!SCONN288_H44441003_PIP-SCONN,HA!!!F188!DQ(19)!!!!
S!M_J_DQ<1>!J9U2!150!@baseboard_fab2_lib.baseboard_fab2(sch_1):page82_i187@mstr_sconn.sconn288_h44441003(chips)!SCONN288_H44441003_PIP-SCONN,HA!!!F188!DQ(1)!!!!
S!M_J_DQ<20>!J9U2!25!@baseboard_fab2_lib.baseboard_fab2(sch_1):page82_i187@mstr_sconn.sconn288_h44441003(chips)!SCONN288_H44441003_PIP-SCONN,HA!!!F188!DQ(20)!!!!
S!M_J_DQ<21>!J9U2!170!@baseboard_fab2_lib.baseboard_fab2(sch_1):page82_i187@mstr_sconn.sconn288_h44441003(chips)!SCONN288_H44441003_PIP-SCONN,HA!!!F188!DQ(21)!!!!
S!M_J_DQ<22>!J9U2!32!@baseboard_fab2_lib.baseboard_fab2(sch_1):page82_i187@mstr_sconn.sconn288_h44441003(chips)!SCONN288_H44441003_PIP-SCONN,HA!!!F188!DQ(22)!!!!
S!M_J_DQ<23>!J9U2!177!@baseboard_fab2_lib.baseboard_fab2(sch_1):page82_i187@mstr_sconn.sconn288_h44441003(chips)!SCONN288_H44441003_PIP-SCONN,HA!!!F188!DQ(23)!!!!
S!M_J_DQ<24>!J9U2!38!@baseboard_fab2_lib.baseboard_fab2(sch_1):page82_i187@mstr_sconn.sconn288_h44441003(chips)!SCONN288_H44441003_PIP-SCONN,HA!!!F188!DQ(24)!!!!
S!M_J_DQ<25>!J9U2!183!@baseboard_fab2_lib.baseboard_fab2(sch_1):page82_i187@mstr_sconn.sconn288_h44441003(chips)!SCONN288_H44441003_PIP-SCONN,HA!!!F188!DQ(25)!!!!
S!M_J_DQ<26>!J9U2!45!@baseboard_fab2_lib.baseboard_fab2(sch_1):page82_i187@mstr_sconn.sconn288_h44441003(chips)!SCONN288_H44441003_PIP-SCONN,HA!!!F188!DQ(26)!!!!
S!M_J_DQ<27>!J9U2!190!@baseboard_fab2_lib.baseboard_fab2(sch_1):page82_i187@mstr_sconn.sconn288_h44441003(chips)!SCONN288_H44441003_PIP-SCONN,HA!!!F188!DQ(27)!!!!
S!M_J_DQ<28>!J9U2!36!@baseboard_fab2_lib.baseboard_fab2(sch_1):page82_i187@mstr_sconn.sconn288_h44441003(chips)!SCONN288_H44441003_PIP-SCONN,HA!!!F188!DQ(28)!!!!
S!M_J_DQ<29>!J9U2!181!@baseboard_fab2_lib.baseboard_fab2(sch_1):page82_i187@mstr_sconn.sconn288_h44441003(chips)!SCONN288_H44441003_PIP-SCONN,HA!!!F188!DQ(29)!!!!
S!M_J_DQ<2>!J9U2!12!@baseboard_fab2_lib.baseboard_fab2(sch_1):page82_i187@mstr_sconn.sconn288_h44441003(chips)!SCONN288_H44441003_PIP-SCONN,HA!!!F188!DQ(2)!!!!
S!M_J_DQ<30>!J9U2!43!@baseboard_fab2_lib.baseboard_fab2(sch_1):page82_i187@mstr_sconn.sconn288_h44441003(chips)!SCONN288_H44441003_PIP-SCONN,HA!!!F188!DQ(30)!!!!
S!M_J_DQ<31>!J9U2!188!@baseboard_fab2_lib.baseboard_fab2(sch_1):page82_i187@mstr_sconn.sconn288_h44441003(chips)!SCONN288_H44441003_PIP-SCONN,HA!!!F188!DQ(31)!!!!
S!M_J_DQ<32>!J9U2!97!@baseboard_fab2_lib.baseboard_fab2(sch_1):page82_i187@mstr_sconn.sconn288_h44441003(chips)!SCONN288_H44441003_PIP-SCONN,HA!!!F188!DQ(32)!!!!
S!M_J_DQ<33>!J9U2!242!@baseboard_fab2_lib.baseboard_fab2(sch_1):page82_i187@mstr_sconn.sconn288_h44441003(chips)!SCONN288_H44441003_PIP-SCONN,HA!!!F188!DQ(33)!!!!
S!M_J_DQ<34>!J9U2!104!@baseboard_fab2_lib.baseboard_fab2(sch_1):page82_i187@mstr_sconn.sconn288_h44441003(chips)!SCONN288_H44441003_PIP-SCONN,HA!!!F188!DQ(34)!!!!
S!M_J_DQ<35>!J9U2!249!@baseboard_fab2_lib.baseboard_fab2(sch_1):page82_i187@mstr_sconn.sconn288_h44441003(chips)!SCONN288_H44441003_PIP-SCONN,HA!!!F188!DQ(35)!!!!
S!M_J_DQ<36>!J9U2!95!@baseboard_fab2_lib.baseboard_fab2(sch_1):page82_i187@mstr_sconn.sconn288_h44441003(chips)!SCONN288_H44441003_PIP-SCONN,HA!!!F188!DQ(36)!!!!
S!M_J_DQ<37>!J9U2!240!@baseboard_fab2_lib.baseboard_fab2(sch_1):page82_i187@mstr_sconn.sconn288_h44441003(chips)!SCONN288_H44441003_PIP-SCONN,HA!!!F188!DQ(37)!!!!
S!M_J_DQ<38>!J9U2!102!@baseboard_fab2_lib.baseboard_fab2(sch_1):page82_i187@mstr_sconn.sconn288_h44441003(chips)!SCONN288_H44441003_PIP-SCONN,HA!!!F188!DQ(38)!!!!
S!M_J_DQ<39>!J9U2!247!@baseboard_fab2_lib.baseboard_fab2(sch_1):page82_i187@mstr_sconn.sconn288_h44441003(chips)!SCONN288_H44441003_PIP-SCONN,HA!!!F188!DQ(39)!!!!
S!M_J_DQ<3>!J9U2!157!@baseboard_fab2_lib.baseboard_fab2(sch_1):page82_i187@mstr_sconn.sconn288_h44441003(chips)!SCONN288_H44441003_PIP-SCONN,HA!!!F188!DQ(3)!!!!
S!M_J_DQ<40>!J9U2!108!@baseboard_fab2_lib.baseboard_fab2(sch_1):page82_i187@mstr_sconn.sconn288_h44441003(chips)!SCONN288_H44441003_PIP-SCONN,HA!!!F188!DQ(40)!!!!
S!M_J_DQ<41>!J9U2!253!@baseboard_fab2_lib.baseboard_fab2(sch_1):page82_i187@mstr_sconn.sconn288_h44441003(chips)!SCONN288_H44441003_PIP-SCONN,HA!!!F188!DQ(41)!!!!
S!M_J_DQ<42>!J9U2!115!@baseboard_fab2_lib.baseboard_fab2(sch_1):page82_i187@mstr_sconn.sconn288_h44441003(chips)!SCONN288_H44441003_PIP-SCONN,HA!!!F188!DQ(42)!!!!
S!M_J_DQ<43>!J9U2!260!@baseboard_fab2_lib.baseboard_fab2(sch_1):page82_i187@mstr_sconn.sconn288_h44441003(chips)!SCONN288_H44441003_PIP-SCONN,HA!!!F188!DQ(43)!!!!
S!M_J_DQ<44>!J9U2!106!@baseboard_fab2_lib.baseboard_fab2(sch_1):page82_i187@mstr_sconn.sconn288_h44441003(chips)!SCONN288_H44441003_PIP-SCONN,HA!!!F188!DQ(44)!!!!
S!M_J_DQ<45>!J9U2!251!@baseboard_fab2_lib.baseboard_fab2(sch_1):page82_i187@mstr_sconn.sconn288_h44441003(chips)!SCONN288_H44441003_PIP-SCONN,HA!!!F188!DQ(45)!!!!
S!M_J_DQ<46>!J9U2!113!@baseboard_fab2_lib.baseboard_fab2(sch_1):page82_i187@mstr_sconn.sconn288_h44441003(chips)!SCONN288_H44441003_PIP-SCONN,HA!!!F188!DQ(46)!!!!
S!M_J_DQ<47>!J9U2!258!@baseboard_fab2_lib.baseboard_fab2(sch_1):page82_i187@mstr_sconn.sconn288_h44441003(chips)!SCONN288_H44441003_PIP-SCONN,HA!!!F188!DQ(47)!!!!
S!M_J_DQ<48>!J9U2!119!@baseboard_fab2_lib.baseboard_fab2(sch_1):page82_i187@mstr_sconn.sconn288_h44441003(chips)!SCONN288_H44441003_PIP-SCONN,HA!!!F188!DQ(48)!!!!
S!M_J_DQ<49>!J9U2!264!@baseboard_fab2_lib.baseboard_fab2(sch_1):page82_i187@mstr_sconn.sconn288_h44441003(chips)!SCONN288_H44441003_PIP-SCONN,HA!!!F188!DQ(49)!!!!
S!M_J_DQ<4>!J9U2!3!@baseboard_fab2_lib.baseboard_fab2(sch_1):page82_i187@mstr_sconn.sconn288_h44441003(chips)!SCONN288_H44441003_PIP-SCONN,HA!!!F188!DQ(4)!!!!
S!M_J_DQ<50>!J9U2!126!@baseboard_fab2_lib.baseboard_fab2(sch_1):page82_i187@mstr_sconn.sconn288_h44441003(chips)!SCONN288_H44441003_PIP-SCONN,HA!!!F188!DQ(50)!!!!
S!M_J_DQ<51>!J9U2!271!@baseboard_fab2_lib.baseboard_fab2(sch_1):page82_i187@mstr_sconn.sconn288_h44441003(chips)!SCONN288_H44441003_PIP-SCONN,HA!!!F188!DQ(51)!!!!
S!M_J_DQ<52>!J9U2!117!@baseboard_fab2_lib.baseboard_fab2(sch_1):page82_i187@mstr_sconn.sconn288_h44441003(chips)!SCONN288_H44441003_PIP-SCONN,HA!!!F188!DQ(52)!!!!
S!M_J_DQ<53>!J9U2!262!@baseboard_fab2_lib.baseboard_fab2(sch_1):page82_i187@mstr_sconn.sconn288_h44441003(chips)!SCONN288_H44441003_PIP-SCONN,HA!!!F188!DQ(53)!!!!
S!M_J_DQ<54>!J9U2!124!@baseboard_fab2_lib.baseboard_fab2(sch_1):page82_i187@mstr_sconn.sconn288_h44441003(chips)!SCONN288_H44441003_PIP-SCONN,HA!!!F188!DQ(54)!!!!
S!M_J_DQ<55>!J9U2!269!@baseboard_fab2_lib.baseboard_fab2(sch_1):page82_i187@mstr_sconn.sconn288_h44441003(chips)!SCONN288_H44441003_PIP-SCONN,HA!!!F188!DQ(55)!!!!
S!M_J_DQ<56>!J9U2!130!@baseboard_fab2_lib.baseboard_fab2(sch_1):page82_i187@mstr_sconn.sconn288_h44441003(chips)!SCONN288_H44441003_PIP-SCONN,HA!!!F188!DQ(56)!!!!
S!M_J_DQ<57>!J9U2!275!@baseboard_fab2_lib.baseboard_fab2(sch_1):page82_i187@mstr_sconn.sconn288_h44441003(chips)!SCONN288_H44441003_PIP-SCONN,HA!!!F188!DQ(57)!!!!
S!M_J_DQ<58>!J9U2!137!@baseboard_fab2_lib.baseboard_fab2(sch_1):page82_i187@mstr_sconn.sconn288_h44441003(chips)!SCONN288_H44441003_PIP-SCONN,HA!!!F188!DQ(58)!!!!
S!M_J_DQ<59>!J9U2!282!@baseboard_fab2_lib.baseboard_fab2(sch_1):page82_i187@mstr_sconn.sconn288_h44441003(chips)!SCONN288_H44441003_PIP-SCONN,HA!!!F188!DQ(59)!!!!
S!M_J_DQ<5>!J9U2!148!@baseboard_fab2_lib.baseboard_fab2(sch_1):page82_i187@mstr_sconn.sconn288_h44441003(chips)!SCONN288_H44441003_PIP-SCONN,HA!!!F188!DQ(5)!!!!
S!M_J_DQ<60>!J9U2!128!@baseboard_fab2_lib.baseboard_fab2(sch_1):page82_i187@mstr_sconn.sconn288_h44441003(chips)!SCONN288_H44441003_PIP-SCONN,HA!!!F188!DQ(60)!!!!
S!M_J_DQ<61>!J9U2!273!@baseboard_fab2_lib.baseboard_fab2(sch_1):page82_i187@mstr_sconn.sconn288_h44441003(chips)!SCONN288_H44441003_PIP-SCONN,HA!!!F188!DQ(61)!!!!
S!M_J_DQ<62>!J9U2!135!@baseboard_fab2_lib.baseboard_fab2(sch_1):page82_i187@mstr_sconn.sconn288_h44441003(chips)!SCONN288_H44441003_PIP-SCONN,HA!!!F188!DQ(62)!!!!
S!M_J_DQ<63>!J9U2!280!@baseboard_fab2_lib.baseboard_fab2(sch_1):page82_i187@mstr_sconn.sconn288_h44441003(chips)!SCONN288_H44441003_PIP-SCONN,HA!!!F188!DQ(63)!!!!
S!M_J_DQ<6>!J9U2!10!@baseboard_fab2_lib.baseboard_fab2(sch_1):page82_i187@mstr_sconn.sconn288_h44441003(chips)!SCONN288_H44441003_PIP-SCONN,HA!!!F188!DQ(6)!!!!
S!M_J_DQ<7>!J9U2!155!@baseboard_fab2_lib.baseboard_fab2(sch_1):page82_i187@mstr_sconn.sconn288_h44441003(chips)!SCONN288_H44441003_PIP-SCONN,HA!!!F188!DQ(7)!!!!
S!M_J_DQ<8>!J9U2!16!@baseboard_fab2_lib.baseboard_fab2(sch_1):page82_i187@mstr_sconn.sconn288_h44441003(chips)!SCONN288_H44441003_PIP-SCONN,HA!!!F188!DQ(8)!!!!
S!M_J_DQ<9>!J9U2!161!@baseboard_fab2_lib.baseboard_fab2(sch_1):page82_i187@mstr_sconn.sconn288_h44441003(chips)!SCONN288_H44441003_PIP-SCONN,HA!!!F188!DQ(9)!!!!
S!FM_DIMM_EVENT_COD_N!J9U2!78!@baseboard_fab2_lib.baseboard_fab2(sch_1):page82_i187@mstr_sconn.sconn288_h44441003(chips)!SCONN288_H44441003_PIP-SCONN,HA!!!F188!EVENT_N!!!!
S!M_J_ODT<2>!J9U2!87!@baseboard_fab2_lib.baseboard_fab2(sch_1):page82_i187@mstr_sconn.sconn288_h44441003(chips)!SCONN288_H44441003_PIP-SCONN,HA!!!F188!ODT(0)!!!!
S!M_J_ODT<3>!J9U2!91!@baseboard_fab2_lib.baseboard_fab2(sch_1):page82_i187@mstr_sconn.sconn288_h44441003(chips)!SCONN288_H44441003_PIP-SCONN,HA!!!F188!ODT(1)!!!!
S!M_J_PAR!J9U2!222!@baseboard_fab2_lib.baseboard_fab2(sch_1):page82_i187@mstr_sconn.sconn288_h44441003(chips)!SCONN288_H44441003_PIP-SCONN,HA!!!F188!PAR!!!!
S!M_GHJ_RST_N!J9U2!58!@baseboard_fab2_lib.baseboard_fab2(sch_1):page82_i187@mstr_sconn.sconn288_h44441003(chips)!SCONN288_H44441003_PIP-SCONN,HA!!!F188!RESET_N!!!!
S!TP_CH_J_DIMM_J1_RFU_0!J9U2!205!@baseboard_fab2_lib.baseboard_fab2(sch_1):page82_i187@mstr_sconn.sconn288_h44441003(chips)!SCONN288_H44441003_PIP-SCONN,HA!!!F188!RFU(0)!!!!
S!TP_CH_J_DIMM_J1_RFU_1!J9U2!227!@baseboard_fab2_lib.baseboard_fab2(sch_1):page82_i187@mstr_sconn.sconn288_h44441003(chips)!SCONN288_H44441003_PIP-SCONN,HA!!!F188!RFU(1)!!!!
S!TP_CH_J_DIMM_J1_RFU_2!J9U2!144!@baseboard_fab2_lib.baseboard_fab2(sch_1):page82_i187@mstr_sconn.sconn288_h44441003(chips)!SCONN288_H44441003_PIP-SCONN,HA!!!F188!RFU(2)!!!!
S!M_J_CS_N<4>!J9U2!84!@baseboard_fab2_lib.baseboard_fab2(sch_1):page82_i187@mstr_sconn.sconn288_h44441003(chips)!SCONN288_H44441003_PIP-SCONN,HA!!!F188!S0_N!!!!
S!M_J_CS_N<5>!J9U2!89!@baseboard_fab2_lib.baseboard_fab2(sch_1):page82_i187@mstr_sconn.sconn288_h44441003(chips)!SCONN288_H44441003_PIP-SCONN,HA!!!F188!S1_N!!!!
S!M_J_CS_N<6>!J9U2!93!@baseboard_fab2_lib.baseboard_fab2(sch_1):page82_i187@mstr_sconn.sconn288_h44441003(chips)!SCONN288_H44441003_PIP-SCONN,HA!!!F188!S2_N_C(0)!!!!
S!M_J_CS_N<7>!J9U2!237!@baseboard_fab2_lib.baseboard_fab2(sch_1):page82_i187@mstr_sconn.sconn288_h44441003(chips)!SCONN288_H44441003_PIP-SCONN,HA!!!F188!S3_N_C(1)!!!!
S!PVPP_GHJ!J9U2!139!@baseboard_fab2_lib.baseboard_fab2(sch_1):page82_i187@mstr_sconn.sconn288_h44441003(chips)!SCONN288_H44441003_PIP-SCONN,HA!!!F188!SA(0)!!!!
S!GND!J9U2!140!@baseboard_fab2_lib.baseboard_fab2(sch_1):page82_i187@mstr_sconn.sconn288_h44441003(chips)!SCONN288_H44441003_PIP-SCONN,HA!!!F188!SA(1)!!!!
S!PVPP_GHJ!J9U2!238!@baseboard_fab2_lib.baseboard_fab2(sch_1):page82_i187@mstr_sconn.sconn288_h44441003(chips)!SCONN288_H44441003_PIP-SCONN,HA!!!F188!SA(2)!!!!
S!FM_ADR_COMPLETE_GHJ_N!J9U2!230!@baseboard_fab2_lib.baseboard_fab2(sch_1):page82_i187@mstr_sconn.sconn288_h44441003(chips)!SCONN288_H44441003_PIP-SCONN,HA!!!F188!SAVE_N_NC!!!!
S!SMB_DDR_GHJ_VPP_SCL!J9U2!141!@baseboard_fab2_lib.baseboard_fab2(sch_1):page82_i187@mstr_sconn.sconn288_h44441003(chips)!SCONN288_H44441003_PIP-SCONN,HA!!!F188!SCL!!!!
S!SMB_DDR_GHJ_VPP_SDA!J9U2!285!@baseboard_fab2_lib.baseboard_fab2(sch_1):page82_i187@mstr_sconn.sconn288_h44441003(chips)!SCONN288_H44441003_PIP-SCONN,HA!!!F188!SDA!!!!
S!PVPP_GHJ!J9U2!284!@baseboard_fab2_lib.baseboard_fab2(sch_1):page82_i187@mstr_sconn.sconn288_h44441003(chips)!SCONN288_H44441003_PIP-SCONN,HA!!!F188!VDDSPD!!!!
S!M_J_VREF!J9U2!146!@baseboard_fab2_lib.baseboard_fab2(sch_1):page82_i187@mstr_sconn.sconn288_h44441003(chips)!SCONN288_H44441003_PIP-SCONN,HA!!!F188!VREFCA!!!!
S!M_J_DQS_DN<0>!J9U2!152!@baseboard_fab2_lib.baseboard_fab2(sch_1):page82_i64@mstr_sconn.sconn288_h44441003(chips)!SCONN288_H44441003_PIP-SCONN,HA!!!F187!DQS0N!!!!
S!M_J_DQS_DP<0>!J9U2!153!@baseboard_fab2_lib.baseboard_fab2(sch_1):page82_i64@mstr_sconn.sconn288_h44441003(chips)!SCONN288_H44441003_PIP-SCONN,HA!!!F187!DQS0P!!!!
S!M_J_DQS_DN<10>!J9U2!19!@baseboard_fab2_lib.baseboard_fab2(sch_1):page82_i64@mstr_sconn.sconn288_h44441003(chips)!SCONN288_H44441003_PIP-SCONN,HA!!!F187!DQS10N!!!!
S!M_J_DQS_DP<10>!J9U2!18!@baseboard_fab2_lib.baseboard_fab2(sch_1):page82_i64@mstr_sconn.sconn288_h44441003(chips)!SCONN288_H44441003_PIP-SCONN,HA!!!F187!DQS10P!!!!
S!M_J_DQS_DN<11>!J9U2!30!@baseboard_fab2_lib.baseboard_fab2(sch_1):page82_i64@mstr_sconn.sconn288_h44441003(chips)!SCONN288_H44441003_PIP-SCONN,HA!!!F187!DQS11N!!!!
S!M_J_DQS_DP<11>!J9U2!29!@baseboard_fab2_lib.baseboard_fab2(sch_1):page82_i64@mstr_sconn.sconn288_h44441003(chips)!SCONN288_H44441003_PIP-SCONN,HA!!!F187!DQS11P!!!!
S!M_J_DQS_DN<12>!J9U2!41!@baseboard_fab2_lib.baseboard_fab2(sch_1):page82_i64@mstr_sconn.sconn288_h44441003(chips)!SCONN288_H44441003_PIP-SCONN,HA!!!F187!DQS12N!!!!
S!M_J_DQS_DP<12>!J9U2!40!@baseboard_fab2_lib.baseboard_fab2(sch_1):page82_i64@mstr_sconn.sconn288_h44441003(chips)!SCONN288_H44441003_PIP-SCONN,HA!!!F187!DQS12P!!!!
S!M_J_DQS_DN<13>!J9U2!100!@baseboard_fab2_lib.baseboard_fab2(sch_1):page82_i64@mstr_sconn.sconn288_h44441003(chips)!SCONN288_H44441003_PIP-SCONN,HA!!!F187!DQS13N!!!!
S!M_J_DQS_DP<13>!J9U2!99!@baseboard_fab2_lib.baseboard_fab2(sch_1):page82_i64@mstr_sconn.sconn288_h44441003(chips)!SCONN288_H44441003_PIP-SCONN,HA!!!F187!DQS13P!!!!
S!M_J_DQS_DN<14>!J9U2!111!@baseboard_fab2_lib.baseboard_fab2(sch_1):page82_i64@mstr_sconn.sconn288_h44441003(chips)!SCONN288_H44441003_PIP-SCONN,HA!!!F187!DQS14N!!!!
S!M_J_DQS_DP<14>!J9U2!110!@baseboard_fab2_lib.baseboard_fab2(sch_1):page82_i64@mstr_sconn.sconn288_h44441003(chips)!SCONN288_H44441003_PIP-SCONN,HA!!!F187!DQS14P!!!!
S!M_J_DQS_DN<15>!J9U2!122!@baseboard_fab2_lib.baseboard_fab2(sch_1):page82_i64@mstr_sconn.sconn288_h44441003(chips)!SCONN288_H44441003_PIP-SCONN,HA!!!F187!DQS15N!!!!
S!M_J_DQS_DP<15>!J9U2!121!@baseboard_fab2_lib.baseboard_fab2(sch_1):page82_i64@mstr_sconn.sconn288_h44441003(chips)!SCONN288_H44441003_PIP-SCONN,HA!!!F187!DQS15P!!!!
S!M_J_DQS_DN<16>!J9U2!133!@baseboard_fab2_lib.baseboard_fab2(sch_1):page82_i64@mstr_sconn.sconn288_h44441003(chips)!SCONN288_H44441003_PIP-SCONN,HA!!!F187!DQS16N!!!!
S!M_J_DQS_DP<16>!J9U2!132!@baseboard_fab2_lib.baseboard_fab2(sch_1):page82_i64@mstr_sconn.sconn288_h44441003(chips)!SCONN288_H44441003_PIP-SCONN,HA!!!F187!DQS16P!!!!
S!M_J_DQS_DN<17>!J9U2!52!@baseboard_fab2_lib.baseboard_fab2(sch_1):page82_i64@mstr_sconn.sconn288_h44441003(chips)!SCONN288_H44441003_PIP-SCONN,HA!!!F187!DQS17N!!!!
S!M_J_DQS_DP<17>!J9U2!51!@baseboard_fab2_lib.baseboard_fab2(sch_1):page82_i64@mstr_sconn.sconn288_h44441003(chips)!SCONN288_H44441003_PIP-SCONN,HA!!!F187!DQS17P!!!!
S!M_J_DQS_DN<1>!J9U2!163!@baseboard_fab2_lib.baseboard_fab2(sch_1):page82_i64@mstr_sconn.sconn288_h44441003(chips)!SCONN288_H44441003_PIP-SCONN,HA!!!F187!DQS1N!!!!
S!M_J_DQS_DP<1>!J9U2!164!@baseboard_fab2_lib.baseboard_fab2(sch_1):page82_i64@mstr_sconn.sconn288_h44441003(chips)!SCONN288_H44441003_PIP-SCONN,HA!!!F187!DQS1P!!!!
S!M_J_DQS_DN<2>!J9U2!174!@baseboard_fab2_lib.baseboard_fab2(sch_1):page82_i64@mstr_sconn.sconn288_h44441003(chips)!SCONN288_H44441003_PIP-SCONN,HA!!!F187!DQS2N!!!!
S!M_J_DQS_DP<2>!J9U2!175!@baseboard_fab2_lib.baseboard_fab2(sch_1):page82_i64@mstr_sconn.sconn288_h44441003(chips)!SCONN288_H44441003_PIP-SCONN,HA!!!F187!DQS2P!!!!
S!M_J_DQS_DN<3>!J9U2!185!@baseboard_fab2_lib.baseboard_fab2(sch_1):page82_i64@mstr_sconn.sconn288_h44441003(chips)!SCONN288_H44441003_PIP-SCONN,HA!!!F187!DQS3N!!!!
S!M_J_DQS_DP<3>!J9U2!186!@baseboard_fab2_lib.baseboard_fab2(sch_1):page82_i64@mstr_sconn.sconn288_h44441003(chips)!SCONN288_H44441003_PIP-SCONN,HA!!!F187!DQS3P!!!!
S!M_J_DQS_DN<4>!J9U2!244!@baseboard_fab2_lib.baseboard_fab2(sch_1):page82_i64@mstr_sconn.sconn288_h44441003(chips)!SCONN288_H44441003_PIP-SCONN,HA!!!F187!DQS4N!!!!
S!M_J_DQS_DP<4>!J9U2!245!@baseboard_fab2_lib.baseboard_fab2(sch_1):page82_i64@mstr_sconn.sconn288_h44441003(chips)!SCONN288_H44441003_PIP-SCONN,HA!!!F187!DQS4P!!!!
S!M_J_DQS_DN<5>!J9U2!255!@baseboard_fab2_lib.baseboard_fab2(sch_1):page82_i64@mstr_sconn.sconn288_h44441003(chips)!SCONN288_H44441003_PIP-SCONN,HA!!!F187!DQS5N!!!!
S!M_J_DQS_DP<5>!J9U2!256!@baseboard_fab2_lib.baseboard_fab2(sch_1):page82_i64@mstr_sconn.sconn288_h44441003(chips)!SCONN288_H44441003_PIP-SCONN,HA!!!F187!DQS5P!!!!
S!M_J_DQS_DN<6>!J9U2!266!@baseboard_fab2_lib.baseboard_fab2(sch_1):page82_i64@mstr_sconn.sconn288_h44441003(chips)!SCONN288_H44441003_PIP-SCONN,HA!!!F187!DQS6N!!!!
S!M_J_DQS_DP<6>!J9U2!267!@baseboard_fab2_lib.baseboard_fab2(sch_1):page82_i64@mstr_sconn.sconn288_h44441003(chips)!SCONN288_H44441003_PIP-SCONN,HA!!!F187!DQS6P!!!!
S!M_J_DQS_DN<7>!J9U2!277!@baseboard_fab2_lib.baseboard_fab2(sch_1):page82_i64@mstr_sconn.sconn288_h44441003(chips)!SCONN288_H44441003_PIP-SCONN,HA!!!F187!DQS7N!!!!
S!M_J_DQS_DP<7>!J9U2!278!@baseboard_fab2_lib.baseboard_fab2(sch_1):page82_i64@mstr_sconn.sconn288_h44441003(chips)!SCONN288_H44441003_PIP-SCONN,HA!!!F187!DQS7P!!!!
S!M_J_DQS_DN<8>!J9U2!196!@baseboard_fab2_lib.baseboard_fab2(sch_1):page82_i64@mstr_sconn.sconn288_h44441003(chips)!SCONN288_H44441003_PIP-SCONN,HA!!!F187!DQS8N!!!!
S!M_J_DQS_DP<8>!J9U2!197!@baseboard_fab2_lib.baseboard_fab2(sch_1):page82_i64@mstr_sconn.sconn288_h44441003(chips)!SCONN288_H44441003_PIP-SCONN,HA!!!F187!DQS8P!!!!
S!M_J_DQS_DN<9>!J9U2!8!@baseboard_fab2_lib.baseboard_fab2(sch_1):page82_i64@mstr_sconn.sconn288_h44441003(chips)!SCONN288_H44441003_PIP-SCONN,HA!!!F187!DQS9N!!!!
S!M_J_DQS_DP<9>!J9U2!7!@baseboard_fab2_lib.baseboard_fab2(sch_1):page82_i64@mstr_sconn.sconn288_h44441003(chips)!SCONN288_H44441003_PIP-SCONN,HA!!!F187!DQS9P!!!!
S!GND!J9U2!283!@baseboard_fab2_lib.baseboard_fab2(sch_1):page82_i188@mstr_sconn.sconn288_h44441003(chips)!SCONN288_H44441003_PIP-SCONN,HA!!!F186!VSS(0)!!!!
S!GND!J9U2!261!@baseboard_fab2_lib.baseboard_fab2(sch_1):page82_i188@mstr_sconn.sconn288_h44441003(chips)!SCONN288_H44441003_PIP-SCONN,HA!!!F186!VSS(10)!!!!
S!GND!J9U2!259!@baseboard_fab2_lib.baseboard_fab2(sch_1):page82_i188@mstr_sconn.sconn288_h44441003(chips)!SCONN288_H44441003_PIP-SCONN,HA!!!F186!VSS(11)!!!!
S!GND!J9U2!257!@baseboard_fab2_lib.baseboard_fab2(sch_1):page82_i188@mstr_sconn.sconn288_h44441003(chips)!SCONN288_H44441003_PIP-SCONN,HA!!!F186!VSS(12)!!!!
S!GND!J9U2!254!@baseboard_fab2_lib.baseboard_fab2(sch_1):page82_i188@mstr_sconn.sconn288_h44441003(chips)!SCONN288_H44441003_PIP-SCONN,HA!!!F186!VSS(13)!!!!
S!GND!J9U2!252!@baseboard_fab2_lib.baseboard_fab2(sch_1):page82_i188@mstr_sconn.sconn288_h44441003(chips)!SCONN288_H44441003_PIP-SCONN,HA!!!F186!VSS(14)!!!!
S!GND!J9U2!250!@baseboard_fab2_lib.baseboard_fab2(sch_1):page82_i188@mstr_sconn.sconn288_h44441003(chips)!SCONN288_H44441003_PIP-SCONN,HA!!!F186!VSS(15)!!!!
S!GND!J9U2!248!@baseboard_fab2_lib.baseboard_fab2(sch_1):page82_i188@mstr_sconn.sconn288_h44441003(chips)!SCONN288_H44441003_PIP-SCONN,HA!!!F186!VSS(16)!!!!
S!GND!J9U2!246!@baseboard_fab2_lib.baseboard_fab2(sch_1):page82_i188@mstr_sconn.sconn288_h44441003(chips)!SCONN288_H44441003_PIP-SCONN,HA!!!F186!VSS(17)!!!!
S!GND!J9U2!243!@baseboard_fab2_lib.baseboard_fab2(sch_1):page82_i188@mstr_sconn.sconn288_h44441003(chips)!SCONN288_H44441003_PIP-SCONN,HA!!!F186!VSS(18)!!!!
S!GND!J9U2!241!@baseboard_fab2_lib.baseboard_fab2(sch_1):page82_i188@mstr_sconn.sconn288_h44441003(chips)!SCONN288_H44441003_PIP-SCONN,HA!!!F186!VSS(19)!!!!
S!GND!J9U2!281!@baseboard_fab2_lib.baseboard_fab2(sch_1):page82_i188@mstr_sconn.sconn288_h44441003(chips)!SCONN288_H44441003_PIP-SCONN,HA!!!F186!VSS(1)!!!!
S!GND!J9U2!239!@baseboard_fab2_lib.baseboard_fab2(sch_1):page82_i188@mstr_sconn.sconn288_h44441003(chips)!SCONN288_H44441003_PIP-SCONN,HA!!!F186!VSS(20)!!!!
S!GND!J9U2!202!@baseboard_fab2_lib.baseboard_fab2(sch_1):page82_i188@mstr_sconn.sconn288_h44441003(chips)!SCONN288_H44441003_PIP-SCONN,HA!!!F186!VSS(21)!!!!
S!GND!J9U2!200!@baseboard_fab2_lib.baseboard_fab2(sch_1):page82_i188@mstr_sconn.sconn288_h44441003(chips)!SCONN288_H44441003_PIP-SCONN,HA!!!F186!VSS(22)!!!!
S!GND!J9U2!198!@baseboard_fab2_lib.baseboard_fab2(sch_1):page82_i188@mstr_sconn.sconn288_h44441003(chips)!SCONN288_H44441003_PIP-SCONN,HA!!!F186!VSS(23)!!!!
S!GND!J9U2!195!@baseboard_fab2_lib.baseboard_fab2(sch_1):page82_i188@mstr_sconn.sconn288_h44441003(chips)!SCONN288_H44441003_PIP-SCONN,HA!!!F186!VSS(24)!!!!
S!GND!J9U2!193!@baseboard_fab2_lib.baseboard_fab2(sch_1):page82_i188@mstr_sconn.sconn288_h44441003(chips)!SCONN288_H44441003_PIP-SCONN,HA!!!F186!VSS(25)!!!!
S!GND!J9U2!191!@baseboard_fab2_lib.baseboard_fab2(sch_1):page82_i188@mstr_sconn.sconn288_h44441003(chips)!SCONN288_H44441003_PIP-SCONN,HA!!!F186!VSS(26)!!!!
S!GND!J9U2!189!@baseboard_fab2_lib.baseboard_fab2(sch_1):page82_i188@mstr_sconn.sconn288_h44441003(chips)!SCONN288_H44441003_PIP-SCONN,HA!!!F186!VSS(27)!!!!
S!GND!J9U2!187!@baseboard_fab2_lib.baseboard_fab2(sch_1):page82_i188@mstr_sconn.sconn288_h44441003(chips)!SCONN288_H44441003_PIP-SCONN,HA!!!F186!VSS(28)!!!!
S!GND!J9U2!184!@baseboard_fab2_lib.baseboard_fab2(sch_1):page82_i188@mstr_sconn.sconn288_h44441003(chips)!SCONN288_H44441003_PIP-SCONN,HA!!!F186!VSS(29)!!!!
S!GND!J9U2!279!@baseboard_fab2_lib.baseboard_fab2(sch_1):page82_i188@mstr_sconn.sconn288_h44441003(chips)!SCONN288_H44441003_PIP-SCONN,HA!!!F186!VSS(2)!!!!
S!GND!J9U2!182!@baseboard_fab2_lib.baseboard_fab2(sch_1):page82_i188@mstr_sconn.sconn288_h44441003(chips)!SCONN288_H44441003_PIP-SCONN,HA!!!F186!VSS(30)!!!!
S!GND!J9U2!180!@baseboard_fab2_lib.baseboard_fab2(sch_1):page82_i188@mstr_sconn.sconn288_h44441003(chips)!SCONN288_H44441003_PIP-SCONN,HA!!!F186!VSS(31)!!!!
S!GND!J9U2!178!@baseboard_fab2_lib.baseboard_fab2(sch_1):page82_i188@mstr_sconn.sconn288_h44441003(chips)!SCONN288_H44441003_PIP-SCONN,HA!!!F186!VSS(32)!!!!
S!GND!J9U2!176!@baseboard_fab2_lib.baseboard_fab2(sch_1):page82_i188@mstr_sconn.sconn288_h44441003(chips)!SCONN288_H44441003_PIP-SCONN,HA!!!F186!VSS(33)!!!!
S!GND!J9U2!173!@baseboard_fab2_lib.baseboard_fab2(sch_1):page82_i188@mstr_sconn.sconn288_h44441003(chips)!SCONN288_H44441003_PIP-SCONN,HA!!!F186!VSS(34)!!!!
S!GND!J9U2!171!@baseboard_fab2_lib.baseboard_fab2(sch_1):page82_i188@mstr_sconn.sconn288_h44441003(chips)!SCONN288_H44441003_PIP-SCONN,HA!!!F186!VSS(35)!!!!
S!GND!J9U2!169!@baseboard_fab2_lib.baseboard_fab2(sch_1):page82_i188@mstr_sconn.sconn288_h44441003(chips)!SCONN288_H44441003_PIP-SCONN,HA!!!F186!VSS(36)!!!!
S!GND!J9U2!167!@baseboard_fab2_lib.baseboard_fab2(sch_1):page82_i188@mstr_sconn.sconn288_h44441003(chips)!SCONN288_H44441003_PIP-SCONN,HA!!!F186!VSS(37)!!!!
S!GND!J9U2!165!@baseboard_fab2_lib.baseboard_fab2(sch_1):page82_i188@mstr_sconn.sconn288_h44441003(chips)!SCONN288_H44441003_PIP-SCONN,HA!!!F186!VSS(38)!!!!
S!GND!J9U2!162!@baseboard_fab2_lib.baseboard_fab2(sch_1):page82_i188@mstr_sconn.sconn288_h44441003(chips)!SCONN288_H44441003_PIP-SCONN,HA!!!F186!VSS(39)!!!!
S!GND!J9U2!276!@baseboard_fab2_lib.baseboard_fab2(sch_1):page82_i188@mstr_sconn.sconn288_h44441003(chips)!SCONN288_H44441003_PIP-SCONN,HA!!!F186!VSS(3)!!!!
S!GND!J9U2!160!@baseboard_fab2_lib.baseboard_fab2(sch_1):page82_i188@mstr_sconn.sconn288_h44441003(chips)!SCONN288_H44441003_PIP-SCONN,HA!!!F186!VSS(40)!!!!
S!GND!J9U2!158!@baseboard_fab2_lib.baseboard_fab2(sch_1):page82_i188@mstr_sconn.sconn288_h44441003(chips)!SCONN288_H44441003_PIP-SCONN,HA!!!F186!VSS(41)!!!!
S!GND!J9U2!156!@baseboard_fab2_lib.baseboard_fab2(sch_1):page82_i188@mstr_sconn.sconn288_h44441003(chips)!SCONN288_H44441003_PIP-SCONN,HA!!!F186!VSS(42)!!!!
S!GND!J9U2!154!@baseboard_fab2_lib.baseboard_fab2(sch_1):page82_i188@mstr_sconn.sconn288_h44441003(chips)!SCONN288_H44441003_PIP-SCONN,HA!!!F186!VSS(43)!!!!
S!GND!J9U2!151!@baseboard_fab2_lib.baseboard_fab2(sch_1):page82_i188@mstr_sconn.sconn288_h44441003(chips)!SCONN288_H44441003_PIP-SCONN,HA!!!F186!VSS(44)!!!!
S!GND!J9U2!149!@baseboard_fab2_lib.baseboard_fab2(sch_1):page82_i188@mstr_sconn.sconn288_h44441003(chips)!SCONN288_H44441003_PIP-SCONN,HA!!!F186!VSS(45)!!!!
S!GND!J9U2!147!@baseboard_fab2_lib.baseboard_fab2(sch_1):page82_i188@mstr_sconn.sconn288_h44441003(chips)!SCONN288_H44441003_PIP-SCONN,HA!!!F186!VSS(46)!!!!
S!GND!J9U2!138!@baseboard_fab2_lib.baseboard_fab2(sch_1):page82_i188@mstr_sconn.sconn288_h44441003(chips)!SCONN288_H44441003_PIP-SCONN,HA!!!F186!VSS(47)!!!!
S!GND!J9U2!136!@baseboard_fab2_lib.baseboard_fab2(sch_1):page82_i188@mstr_sconn.sconn288_h44441003(chips)!SCONN288_H44441003_PIP-SCONN,HA!!!F186!VSS(48)!!!!
S!GND!J9U2!134!@baseboard_fab2_lib.baseboard_fab2(sch_1):page82_i188@mstr_sconn.sconn288_h44441003(chips)!SCONN288_H44441003_PIP-SCONN,HA!!!F186!VSS(49)!!!!
S!GND!J9U2!274!@baseboard_fab2_lib.baseboard_fab2(sch_1):page82_i188@mstr_sconn.sconn288_h44441003(chips)!SCONN288_H44441003_PIP-SCONN,HA!!!F186!VSS(4)!!!!
S!GND!J9U2!131!@baseboard_fab2_lib.baseboard_fab2(sch_1):page82_i188@mstr_sconn.sconn288_h44441003(chips)!SCONN288_H44441003_PIP-SCONN,HA!!!F186!VSS(50)!!!!
S!GND!J9U2!129!@baseboard_fab2_lib.baseboard_fab2(sch_1):page82_i188@mstr_sconn.sconn288_h44441003(chips)!SCONN288_H44441003_PIP-SCONN,HA!!!F186!VSS(51)!!!!
S!GND!J9U2!127!@baseboard_fab2_lib.baseboard_fab2(sch_1):page82_i188@mstr_sconn.sconn288_h44441003(chips)!SCONN288_H44441003_PIP-SCONN,HA!!!F186!VSS(52)!!!!
S!GND!J9U2!125!@baseboard_fab2_lib.baseboard_fab2(sch_1):page82_i188@mstr_sconn.sconn288_h44441003(chips)!SCONN288_H44441003_PIP-SCONN,HA!!!F186!VSS(53)!!!!
S!GND!J9U2!123!@baseboard_fab2_lib.baseboard_fab2(sch_1):page82_i188@mstr_sconn.sconn288_h44441003(chips)!SCONN288_H44441003_PIP-SCONN,HA!!!F186!VSS(54)!!!!
S!GND!J9U2!120!@baseboard_fab2_lib.baseboard_fab2(sch_1):page82_i188@mstr_sconn.sconn288_h44441003(chips)!SCONN288_H44441003_PIP-SCONN,HA!!!F186!VSS(55)!!!!
S!GND!J9U2!118!@baseboard_fab2_lib.baseboard_fab2(sch_1):page82_i188@mstr_sconn.sconn288_h44441003(chips)!SCONN288_H44441003_PIP-SCONN,HA!!!F186!VSS(56)!!!!
S!GND!J9U2!116!@baseboard_fab2_lib.baseboard_fab2(sch_1):page82_i188@mstr_sconn.sconn288_h44441003(chips)!SCONN288_H44441003_PIP-SCONN,HA!!!F186!VSS(57)!!!!
S!GND!J9U2!114!@baseboard_fab2_lib.baseboard_fab2(sch_1):page82_i188@mstr_sconn.sconn288_h44441003(chips)!SCONN288_H44441003_PIP-SCONN,HA!!!F186!VSS(58)!!!!
S!GND!J9U2!112!@baseboard_fab2_lib.baseboard_fab2(sch_1):page82_i188@mstr_sconn.sconn288_h44441003(chips)!SCONN288_H44441003_PIP-SCONN,HA!!!F186!VSS(59)!!!!
S!GND!J9U2!272!@baseboard_fab2_lib.baseboard_fab2(sch_1):page82_i188@mstr_sconn.sconn288_h44441003(chips)!SCONN288_H44441003_PIP-SCONN,HA!!!F186!VSS(5)!!!!
S!GND!J9U2!109!@baseboard_fab2_lib.baseboard_fab2(sch_1):page82_i188@mstr_sconn.sconn288_h44441003(chips)!SCONN288_H44441003_PIP-SCONN,HA!!!F186!VSS(60)!!!!
S!GND!J9U2!107!@baseboard_fab2_lib.baseboard_fab2(sch_1):page82_i188@mstr_sconn.sconn288_h44441003(chips)!SCONN288_H44441003_PIP-SCONN,HA!!!F186!VSS(61)!!!!
S!GND!J9U2!105!@baseboard_fab2_lib.baseboard_fab2(sch_1):page82_i188@mstr_sconn.sconn288_h44441003(chips)!SCONN288_H44441003_PIP-SCONN,HA!!!F186!VSS(62)!!!!
S!GND!J9U2!103!@baseboard_fab2_lib.baseboard_fab2(sch_1):page82_i188@mstr_sconn.sconn288_h44441003(chips)!SCONN288_H44441003_PIP-SCONN,HA!!!F186!VSS(63)!!!!
S!GND!J9U2!101!@baseboard_fab2_lib.baseboard_fab2(sch_1):page82_i188@mstr_sconn.sconn288_h44441003(chips)!SCONN288_H44441003_PIP-SCONN,HA!!!F186!VSS(64)!!!!
S!GND!J9U2!98!@baseboard_fab2_lib.baseboard_fab2(sch_1):page82_i188@mstr_sconn.sconn288_h44441003(chips)!SCONN288_H44441003_PIP-SCONN,HA!!!F186!VSS(65)!!!!
S!GND!J9U2!96!@baseboard_fab2_lib.baseboard_fab2(sch_1):page82_i188@mstr_sconn.sconn288_h44441003(chips)!SCONN288_H44441003_PIP-SCONN,HA!!!F186!VSS(66)!!!!
S!GND!J9U2!94!@baseboard_fab2_lib.baseboard_fab2(sch_1):page82_i188@mstr_sconn.sconn288_h44441003(chips)!SCONN288_H44441003_PIP-SCONN,HA!!!F186!VSS(67)!!!!
S!GND!J9U2!57!@baseboard_fab2_lib.baseboard_fab2(sch_1):page82_i188@mstr_sconn.sconn288_h44441003(chips)!SCONN288_H44441003_PIP-SCONN,HA!!!F186!VSS(68)!!!!
S!GND!J9U2!55!@baseboard_fab2_lib.baseboard_fab2(sch_1):page82_i188@mstr_sconn.sconn288_h44441003(chips)!SCONN288_H44441003_PIP-SCONN,HA!!!F186!VSS(69)!!!!
S!GND!J9U2!270!@baseboard_fab2_lib.baseboard_fab2(sch_1):page82_i188@mstr_sconn.sconn288_h44441003(chips)!SCONN288_H44441003_PIP-SCONN,HA!!!F186!VSS(6)!!!!
S!GND!J9U2!53!@baseboard_fab2_lib.baseboard_fab2(sch_1):page82_i188@mstr_sconn.sconn288_h44441003(chips)!SCONN288_H44441003_PIP-SCONN,HA!!!F186!VSS(70)!!!!
S!GND!J9U2!50!@baseboard_fab2_lib.baseboard_fab2(sch_1):page82_i188@mstr_sconn.sconn288_h44441003(chips)!SCONN288_H44441003_PIP-SCONN,HA!!!F186!VSS(71)!!!!
S!GND!J9U2!48!@baseboard_fab2_lib.baseboard_fab2(sch_1):page82_i188@mstr_sconn.sconn288_h44441003(chips)!SCONN288_H44441003_PIP-SCONN,HA!!!F186!VSS(72)!!!!
S!GND!J9U2!46!@baseboard_fab2_lib.baseboard_fab2(sch_1):page82_i188@mstr_sconn.sconn288_h44441003(chips)!SCONN288_H44441003_PIP-SCONN,HA!!!F186!VSS(73)!!!!
S!GND!J9U2!44!@baseboard_fab2_lib.baseboard_fab2(sch_1):page82_i188@mstr_sconn.sconn288_h44441003(chips)!SCONN288_H44441003_PIP-SCONN,HA!!!F186!VSS(74)!!!!
S!GND!J9U2!42!@baseboard_fab2_lib.baseboard_fab2(sch_1):page82_i188@mstr_sconn.sconn288_h44441003(chips)!SCONN288_H44441003_PIP-SCONN,HA!!!F186!VSS(75)!!!!
S!GND!J9U2!39!@baseboard_fab2_lib.baseboard_fab2(sch_1):page82_i188@mstr_sconn.sconn288_h44441003(chips)!SCONN288_H44441003_PIP-SCONN,HA!!!F186!VSS(76)!!!!
S!GND!J9U2!37!@baseboard_fab2_lib.baseboard_fab2(sch_1):page82_i188@mstr_sconn.sconn288_h44441003(chips)!SCONN288_H44441003_PIP-SCONN,HA!!!F186!VSS(77)!!!!
S!GND!J9U2!35!@baseboard_fab2_lib.baseboard_fab2(sch_1):page82_i188@mstr_sconn.sconn288_h44441003(chips)!SCONN288_H44441003_PIP-SCONN,HA!!!F186!VSS(78)!!!!
S!GND!J9U2!33!@baseboard_fab2_lib.baseboard_fab2(sch_1):page82_i188@mstr_sconn.sconn288_h44441003(chips)!SCONN288_H44441003_PIP-SCONN,HA!!!F186!VSS(79)!!!!
S!GND!J9U2!268!@baseboard_fab2_lib.baseboard_fab2(sch_1):page82_i188@mstr_sconn.sconn288_h44441003(chips)!SCONN288_H44441003_PIP-SCONN,HA!!!F186!VSS(7)!!!!
S!GND!J9U2!31!@baseboard_fab2_lib.baseboard_fab2(sch_1):page82_i188@mstr_sconn.sconn288_h44441003(chips)!SCONN288_H44441003_PIP-SCONN,HA!!!F186!VSS(80)!!!!
S!GND!J9U2!28!@baseboard_fab2_lib.baseboard_fab2(sch_1):page82_i188@mstr_sconn.sconn288_h44441003(chips)!SCONN288_H44441003_PIP-SCONN,HA!!!F186!VSS(81)!!!!
S!GND!J9U2!26!@baseboard_fab2_lib.baseboard_fab2(sch_1):page82_i188@mstr_sconn.sconn288_h44441003(chips)!SCONN288_H44441003_PIP-SCONN,HA!!!F186!VSS(82)!!!!
S!GND!J9U2!24!@baseboard_fab2_lib.baseboard_fab2(sch_1):page82_i188@mstr_sconn.sconn288_h44441003(chips)!SCONN288_H44441003_PIP-SCONN,HA!!!F186!VSS(83)!!!!
S!GND!J9U2!22!@baseboard_fab2_lib.baseboard_fab2(sch_1):page82_i188@mstr_sconn.sconn288_h44441003(chips)!SCONN288_H44441003_PIP-SCONN,HA!!!F186!VSS(84)!!!!
S!GND!J9U2!20!@baseboard_fab2_lib.baseboard_fab2(sch_1):page82_i188@mstr_sconn.sconn288_h44441003(chips)!SCONN288_H44441003_PIP-SCONN,HA!!!F186!VSS(85)!!!!
S!GND!J9U2!17!@baseboard_fab2_lib.baseboard_fab2(sch_1):page82_i188@mstr_sconn.sconn288_h44441003(chips)!SCONN288_H44441003_PIP-SCONN,HA!!!F186!VSS(86)!!!!
S!GND!J9U2!15!@baseboard_fab2_lib.baseboard_fab2(sch_1):page82_i188@mstr_sconn.sconn288_h44441003(chips)!SCONN288_H44441003_PIP-SCONN,HA!!!F186!VSS(87)!!!!
S!GND!J9U2!13!@baseboard_fab2_lib.baseboard_fab2(sch_1):page82_i188@mstr_sconn.sconn288_h44441003(chips)!SCONN288_H44441003_PIP-SCONN,HA!!!F186!VSS(88)!!!!
S!GND!J9U2!11!@baseboard_fab2_lib.baseboard_fab2(sch_1):page82_i188@mstr_sconn.sconn288_h44441003(chips)!SCONN288_H44441003_PIP-SCONN,HA!!!F186!VSS(89)!!!!
S!GND!J9U2!265!@baseboard_fab2_lib.baseboard_fab2(sch_1):page82_i188@mstr_sconn.sconn288_h44441003(chips)!SCONN288_H44441003_PIP-SCONN,HA!!!F186!VSS(8)!!!!
S!GND!J9U2!9!@baseboard_fab2_lib.baseboard_fab2(sch_1):page82_i188@mstr_sconn.sconn288_h44441003(chips)!SCONN288_H44441003_PIP-SCONN,HA!!!F186!VSS(90)!!!!
S!GND!J9U2!6!@baseboard_fab2_lib.baseboard_fab2(sch_1):page82_i188@mstr_sconn.sconn288_h44441003(chips)!SCONN288_H44441003_PIP-SCONN,HA!!!F186!VSS(91)!!!!
S!GND!J9U2!4!@baseboard_fab2_lib.baseboard_fab2(sch_1):page82_i188@mstr_sconn.sconn288_h44441003(chips)!SCONN288_H44441003_PIP-SCONN,HA!!!F186!VSS(92)!!!!
S!GND!J9U2!2!@baseboard_fab2_lib.baseboard_fab2(sch_1):page82_i188@mstr_sconn.sconn288_h44441003(chips)!SCONN288_H44441003_PIP-SCONN,HA!!!F186!VSS(93)!!!!
S!GND!J9U2!263!@baseboard_fab2_lib.baseboard_fab2(sch_1):page82_i188@mstr_sconn.sconn288_h44441003(chips)!SCONN288_H44441003_PIP-SCONN,HA!!!F186!VSS(9)!!!!
S!P12V_NVDIMM_GHJ!J9U2!145!@baseboard_fab2_lib.baseboard_fab2(sch_1):page82_i171@mstr_sconn.sconn288_h44441003(chips)!SCONN288_H44441003_PIP-SCONN,HA!!!F185!\12v\(0)!!!!
S!P12V_NVDIMM_GHJ!J9U2!1!@baseboard_fab2_lib.baseboard_fab2(sch_1):page82_i171@mstr_sconn.sconn288_h44441003(chips)!SCONN288_H44441003_PIP-SCONN,HA!!!F185!\12v\(1)!!!!
S!PVDDQ_GHJ!J9U2!236!@baseboard_fab2_lib.baseboard_fab2(sch_1):page82_i171@mstr_sconn.sconn288_h44441003(chips)!SCONN288_H44441003_PIP-SCONN,HA!!!F185!VDD(0)!!!!
S!PVDDQ_GHJ!J9U2!209!@baseboard_fab2_lib.baseboard_fab2(sch_1):page82_i171@mstr_sconn.sconn288_h44441003(chips)!SCONN288_H44441003_PIP-SCONN,HA!!!F185!VDD(10)!!!!
S!PVDDQ_GHJ!J9U2!206!@baseboard_fab2_lib.baseboard_fab2(sch_1):page82_i171@mstr_sconn.sconn288_h44441003(chips)!SCONN288_H44441003_PIP-SCONN,HA!!!F185!VDD(11)!!!!
S!PVDDQ_GHJ!J9U2!204!@baseboard_fab2_lib.baseboard_fab2(sch_1):page82_i171@mstr_sconn.sconn288_h44441003(chips)!SCONN288_H44441003_PIP-SCONN,HA!!!F185!VDD(12)!!!!
S!PVDDQ_GHJ!J9U2!92!@baseboard_fab2_lib.baseboard_fab2(sch_1):page82_i171@mstr_sconn.sconn288_h44441003(chips)!SCONN288_H44441003_PIP-SCONN,HA!!!F185!VDD(13)!!!!
S!PVDDQ_GHJ!J9U2!90!@baseboard_fab2_lib.baseboard_fab2(sch_1):page82_i171@mstr_sconn.sconn288_h44441003(chips)!SCONN288_H44441003_PIP-SCONN,HA!!!F185!VDD(14)!!!!
S!PVDDQ_GHJ!J9U2!88!@baseboard_fab2_lib.baseboard_fab2(sch_1):page82_i171@mstr_sconn.sconn288_h44441003(chips)!SCONN288_H44441003_PIP-SCONN,HA!!!F185!VDD(15)!!!!
S!PVDDQ_GHJ!J9U2!85!@baseboard_fab2_lib.baseboard_fab2(sch_1):page82_i171@mstr_sconn.sconn288_h44441003(chips)!SCONN288_H44441003_PIP-SCONN,HA!!!F185!VDD(16)!!!!
S!PVDDQ_GHJ!J9U2!83!@baseboard_fab2_lib.baseboard_fab2(sch_1):page82_i171@mstr_sconn.sconn288_h44441003(chips)!SCONN288_H44441003_PIP-SCONN,HA!!!F185!VDD(17)!!!!
S!PVDDQ_GHJ!J9U2!80!@baseboard_fab2_lib.baseboard_fab2(sch_1):page82_i171@mstr_sconn.sconn288_h44441003(chips)!SCONN288_H44441003_PIP-SCONN,HA!!!F185!VDD(18)!!!!
S!PVDDQ_GHJ!J9U2!76!@baseboard_fab2_lib.baseboard_fab2(sch_1):page82_i171@mstr_sconn.sconn288_h44441003(chips)!SCONN288_H44441003_PIP-SCONN,HA!!!F185!VDD(19)!!!!
S!PVDDQ_GHJ!J9U2!233!@baseboard_fab2_lib.baseboard_fab2(sch_1):page82_i171@mstr_sconn.sconn288_h44441003(chips)!SCONN288_H44441003_PIP-SCONN,HA!!!F185!VDD(1)!!!!
S!PVDDQ_GHJ!J9U2!73!@baseboard_fab2_lib.baseboard_fab2(sch_1):page82_i171@mstr_sconn.sconn288_h44441003(chips)!SCONN288_H44441003_PIP-SCONN,HA!!!F185!VDD(20)!!!!
S!PVDDQ_GHJ!J9U2!70!@baseboard_fab2_lib.baseboard_fab2(sch_1):page82_i171@mstr_sconn.sconn288_h44441003(chips)!SCONN288_H44441003_PIP-SCONN,HA!!!F185!VDD(21)!!!!
S!PVDDQ_GHJ!J9U2!67!@baseboard_fab2_lib.baseboard_fab2(sch_1):page82_i171@mstr_sconn.sconn288_h44441003(chips)!SCONN288_H44441003_PIP-SCONN,HA!!!F185!VDD(22)!!!!
S!PVDDQ_GHJ!J9U2!64!@baseboard_fab2_lib.baseboard_fab2(sch_1):page82_i171@mstr_sconn.sconn288_h44441003(chips)!SCONN288_H44441003_PIP-SCONN,HA!!!F185!VDD(23)!!!!
S!PVDDQ_GHJ!J9U2!61!@baseboard_fab2_lib.baseboard_fab2(sch_1):page82_i171@mstr_sconn.sconn288_h44441003(chips)!SCONN288_H44441003_PIP-SCONN,HA!!!F185!VDD(24)!!!!
S!PVDDQ_GHJ!J9U2!59!@baseboard_fab2_lib.baseboard_fab2(sch_1):page82_i171@mstr_sconn.sconn288_h44441003(chips)!SCONN288_H44441003_PIP-SCONN,HA!!!F185!VDD(25)!!!!
S!PVDDQ_GHJ!J9U2!231!@baseboard_fab2_lib.baseboard_fab2(sch_1):page82_i171@mstr_sconn.sconn288_h44441003(chips)!SCONN288_H44441003_PIP-SCONN,HA!!!F185!VDD(2)!!!!
S!PVDDQ_GHJ!J9U2!229!@baseboard_fab2_lib.baseboard_fab2(sch_1):page82_i171@mstr_sconn.sconn288_h44441003(chips)!SCONN288_H44441003_PIP-SCONN,HA!!!F185!VDD(3)!!!!
S!PVDDQ_GHJ!J9U2!226!@baseboard_fab2_lib.baseboard_fab2(sch_1):page82_i171@mstr_sconn.sconn288_h44441003(chips)!SCONN288_H44441003_PIP-SCONN,HA!!!F185!VDD(4)!!!!
S!PVDDQ_GHJ!J9U2!223!@baseboard_fab2_lib.baseboard_fab2(sch_1):page82_i171@mstr_sconn.sconn288_h44441003(chips)!SCONN288_H44441003_PIP-SCONN,HA!!!F185!VDD(5)!!!!
S!PVDDQ_GHJ!J9U2!220!@baseboard_fab2_lib.baseboard_fab2(sch_1):page82_i171@mstr_sconn.sconn288_h44441003(chips)!SCONN288_H44441003_PIP-SCONN,HA!!!F185!VDD(6)!!!!
S!PVDDQ_GHJ!J9U2!217!@baseboard_fab2_lib.baseboard_fab2(sch_1):page82_i171@mstr_sconn.sconn288_h44441003(chips)!SCONN288_H44441003_PIP-SCONN,HA!!!F185!VDD(7)!!!!
S!PVDDQ_GHJ!J9U2!215!@baseboard_fab2_lib.baseboard_fab2(sch_1):page82_i171@mstr_sconn.sconn288_h44441003(chips)!SCONN288_H44441003_PIP-SCONN,HA!!!F185!VDD(8)!!!!
S!PVDDQ_GHJ!J9U2!212!@baseboard_fab2_lib.baseboard_fab2(sch_1):page82_i171@mstr_sconn.sconn288_h44441003(chips)!SCONN288_H44441003_PIP-SCONN,HA!!!F185!VDD(9)!!!!
S!PVPP_GHJ!J9U2!287!@baseboard_fab2_lib.baseboard_fab2(sch_1):page82_i171@mstr_sconn.sconn288_h44441003(chips)!SCONN288_H44441003_PIP-SCONN,HA!!!F185!VPP(0)!!!!
S!PVPP_GHJ!J9U2!286!@baseboard_fab2_lib.baseboard_fab2(sch_1):page82_i171@mstr_sconn.sconn288_h44441003(chips)!SCONN288_H44441003_PIP-SCONN,HA!!!F185!VPP(1)!!!!
S!PVPP_GHJ!J9U2!288!@baseboard_fab2_lib.baseboard_fab2(sch_1):page82_i171@mstr_sconn.sconn288_h44441003(chips)!SCONN288_H44441003_PIP-SCONN,HA!!!F185!VPP(2)!!!!
S!PVPP_GHJ!J9U2!143!@baseboard_fab2_lib.baseboard_fab2(sch_1):page82_i171@mstr_sconn.sconn288_h44441003(chips)!SCONN288_H44441003_PIP-SCONN,HA!!!F185!VPP(3)!!!!
S!PVPP_GHJ!J9U2!142!@baseboard_fab2_lib.baseboard_fab2(sch_1):page82_i171@mstr_sconn.sconn288_h44441003(chips)!SCONN288_H44441003_PIP-SCONN,HA!!!F185!VPP(4)!!!!
S!PVTT_GHJ!J9U2!221!@baseboard_fab2_lib.baseboard_fab2(sch_1):page82_i171@mstr_sconn.sconn288_h44441003(chips)!SCONN288_H44441003_PIP-SCONN,HA!!!F185!VTT(0)!!!!
S!PVTT_GHJ!J9U2!77!@baseboard_fab2_lib.baseboard_fab2(sch_1):page82_i171@mstr_sconn.sconn288_h44441003(chips)!SCONN288_H44441003_PIP-SCONN,HA!!!F185!VTT(1)!!!!
S!M_K_MA<0>!J9M1!79!@baseboard_fab2_lib.baseboard_fab2(sch_1):page84_i14@mstr_sconn.sconn288_h44441003(chips)!SCONN288_H44441003_PIP-SCONN,HA!!!F200!A0!!!!
S!M_K_MA<1>!J9M1!72!@baseboard_fab2_lib.baseboard_fab2(sch_1):page84_i14@mstr_sconn.sconn288_h44441003(chips)!SCONN288_H44441003_PIP-SCONN,HA!!!F200!A1!!!!
S!M_K_MA<10>!J9M1!225!@baseboard_fab2_lib.baseboard_fab2(sch_1):page84_i14@mstr_sconn.sconn288_h44441003(chips)!SCONN288_H44441003_PIP-SCONN,HA!!!F200!A10!!!!
S!M_K_MA<11>!J9M1!210!@baseboard_fab2_lib.baseboard_fab2(sch_1):page84_i14@mstr_sconn.sconn288_h44441003(chips)!SCONN288_H44441003_PIP-SCONN,HA!!!F200!A11!!!!
S!M_K_MA<12>!J9M1!65!@baseboard_fab2_lib.baseboard_fab2(sch_1):page84_i14@mstr_sconn.sconn288_h44441003(chips)!SCONN288_H44441003_PIP-SCONN,HA!!!F200!A12!!!!
S!M_K_MA<13>!J9M1!232!@baseboard_fab2_lib.baseboard_fab2(sch_1):page84_i14@mstr_sconn.sconn288_h44441003(chips)!SCONN288_H44441003_PIP-SCONN,HA!!!F200!A13!!!!
S!M_K_MA<14>!J9M1!228!@baseboard_fab2_lib.baseboard_fab2(sch_1):page84_i14@mstr_sconn.sconn288_h44441003(chips)!SCONN288_H44441003_PIP-SCONN,HA!!!F200!A14_WE_N!!!!
S!M_K_MA<15>!J9M1!86!@baseboard_fab2_lib.baseboard_fab2(sch_1):page84_i14@mstr_sconn.sconn288_h44441003(chips)!SCONN288_H44441003_PIP-SCONN,HA!!!F200!A15_CAS_N!!!!
S!M_K_MA<16>!J9M1!82!@baseboard_fab2_lib.baseboard_fab2(sch_1):page84_i14@mstr_sconn.sconn288_h44441003(chips)!SCONN288_H44441003_PIP-SCONN,HA!!!F200!A16_RAS_N!!!!
S!M_K_MA<17>!J9M1!234!@baseboard_fab2_lib.baseboard_fab2(sch_1):page84_i14@mstr_sconn.sconn288_h44441003(chips)!SCONN288_H44441003_PIP-SCONN,HA!!!F200!A17!!!!
S!M_K_MA<2>!J9M1!216!@baseboard_fab2_lib.baseboard_fab2(sch_1):page84_i14@mstr_sconn.sconn288_h44441003(chips)!SCONN288_H44441003_PIP-SCONN,HA!!!F200!A2!!!!
S!M_K_MA<3>!J9M1!71!@baseboard_fab2_lib.baseboard_fab2(sch_1):page84_i14@mstr_sconn.sconn288_h44441003(chips)!SCONN288_H44441003_PIP-SCONN,HA!!!F200!A3!!!!
S!M_K_MA<4>!J9M1!214!@baseboard_fab2_lib.baseboard_fab2(sch_1):page84_i14@mstr_sconn.sconn288_h44441003(chips)!SCONN288_H44441003_PIP-SCONN,HA!!!F200!A4!!!!
S!M_K_MA<5>!J9M1!213!@baseboard_fab2_lib.baseboard_fab2(sch_1):page84_i14@mstr_sconn.sconn288_h44441003(chips)!SCONN288_H44441003_PIP-SCONN,HA!!!F200!A5!!!!
S!M_K_MA<6>!J9M1!69!@baseboard_fab2_lib.baseboard_fab2(sch_1):page84_i14@mstr_sconn.sconn288_h44441003(chips)!SCONN288_H44441003_PIP-SCONN,HA!!!F200!A6!!!!
S!M_K_MA<7>!J9M1!211!@baseboard_fab2_lib.baseboard_fab2(sch_1):page84_i14@mstr_sconn.sconn288_h44441003(chips)!SCONN288_H44441003_PIP-SCONN,HA!!!F200!A7!!!!
S!M_K_MA<8>!J9M1!68!@baseboard_fab2_lib.baseboard_fab2(sch_1):page84_i14@mstr_sconn.sconn288_h44441003(chips)!SCONN288_H44441003_PIP-SCONN,HA!!!F200!A8!!!!
S!M_K_MA<9>!J9M1!66!@baseboard_fab2_lib.baseboard_fab2(sch_1):page84_i14@mstr_sconn.sconn288_h44441003(chips)!SCONN288_H44441003_PIP-SCONN,HA!!!F200!A9!!!!
S!M_K_ACT_N!J9M1!62!@baseboard_fab2_lib.baseboard_fab2(sch_1):page84_i14@mstr_sconn.sconn288_h44441003(chips)!SCONN288_H44441003_PIP-SCONN,HA!!!F200!ACT_N!!!!
S!M_K_ALERT_N!J9M1!208!@baseboard_fab2_lib.baseboard_fab2(sch_1):page84_i14@mstr_sconn.sconn288_h44441003(chips)!SCONN288_H44441003_PIP-SCONN,HA!!!F200!ALERT_N!!!!
S!M_K_BA<0>!J9M1!81!@baseboard_fab2_lib.baseboard_fab2(sch_1):page84_i14@mstr_sconn.sconn288_h44441003(chips)!SCONN288_H44441003_PIP-SCONN,HA!!!F200!BA(0)!!!!
S!M_K_BA<1>!J9M1!224!@baseboard_fab2_lib.baseboard_fab2(sch_1):page84_i14@mstr_sconn.sconn288_h44441003(chips)!SCONN288_H44441003_PIP-SCONN,HA!!!F200!BA(1)!!!!
S!M_K_BG<0>!J9M1!63!@baseboard_fab2_lib.baseboard_fab2(sch_1):page84_i14@mstr_sconn.sconn288_h44441003(chips)!SCONN288_H44441003_PIP-SCONN,HA!!!F200!BG(0)!!!!
S!M_K_BG<1>!J9M1!207!@baseboard_fab2_lib.baseboard_fab2(sch_1):page84_i14@mstr_sconn.sconn288_h44441003(chips)!SCONN288_H44441003_PIP-SCONN,HA!!!F200!BG(1)!!!!
S!M_K_C<2>!J9M1!235!@baseboard_fab2_lib.baseboard_fab2(sch_1):page84_i14@mstr_sconn.sconn288_h44441003(chips)!SCONN288_H44441003_PIP-SCONN,HA!!!F200!C(2)!!!!
S!M_K_ECC<0>!J9M1!49!@baseboard_fab2_lib.baseboard_fab2(sch_1):page84_i14@mstr_sconn.sconn288_h44441003(chips)!SCONN288_H44441003_PIP-SCONN,HA!!!F200!CB(0)!!!!
S!M_K_ECC<1>!J9M1!194!@baseboard_fab2_lib.baseboard_fab2(sch_1):page84_i14@mstr_sconn.sconn288_h44441003(chips)!SCONN288_H44441003_PIP-SCONN,HA!!!F200!CB(1)!!!!
S!M_K_ECC<2>!J9M1!56!@baseboard_fab2_lib.baseboard_fab2(sch_1):page84_i14@mstr_sconn.sconn288_h44441003(chips)!SCONN288_H44441003_PIP-SCONN,HA!!!F200!CB(2)!!!!
S!M_K_ECC<3>!J9M1!201!@baseboard_fab2_lib.baseboard_fab2(sch_1):page84_i14@mstr_sconn.sconn288_h44441003(chips)!SCONN288_H44441003_PIP-SCONN,HA!!!F200!CB(3)!!!!
S!M_K_ECC<4>!J9M1!47!@baseboard_fab2_lib.baseboard_fab2(sch_1):page84_i14@mstr_sconn.sconn288_h44441003(chips)!SCONN288_H44441003_PIP-SCONN,HA!!!F200!CB(4)!!!!
S!M_K_ECC<5>!J9M1!192!@baseboard_fab2_lib.baseboard_fab2(sch_1):page84_i14@mstr_sconn.sconn288_h44441003(chips)!SCONN288_H44441003_PIP-SCONN,HA!!!F200!CB(5)!!!!
S!M_K_ECC<6>!J9M1!54!@baseboard_fab2_lib.baseboard_fab2(sch_1):page84_i14@mstr_sconn.sconn288_h44441003(chips)!SCONN288_H44441003_PIP-SCONN,HA!!!F200!CB(6)!!!!
S!M_K_ECC<7>!J9M1!199!@baseboard_fab2_lib.baseboard_fab2(sch_1):page84_i14@mstr_sconn.sconn288_h44441003(chips)!SCONN288_H44441003_PIP-SCONN,HA!!!F200!CB(7)!!!!
S!M_K_CLK_DN<2>!J9M1!75!@baseboard_fab2_lib.baseboard_fab2(sch_1):page84_i14@mstr_sconn.sconn288_h44441003(chips)!SCONN288_H44441003_PIP-SCONN,HA!!!F200!CK0N!!!!
S!M_K_CLK_DP<2>!J9M1!74!@baseboard_fab2_lib.baseboard_fab2(sch_1):page84_i14@mstr_sconn.sconn288_h44441003(chips)!SCONN288_H44441003_PIP-SCONN,HA!!!F200!CK0P!!!!
S!M_K_CLK_DN<3>!J9M1!219!@baseboard_fab2_lib.baseboard_fab2(sch_1):page84_i14@mstr_sconn.sconn288_h44441003(chips)!SCONN288_H44441003_PIP-SCONN,HA!!!F200!CK1N!!!!
S!M_K_CLK_DP<3>!J9M1!218!@baseboard_fab2_lib.baseboard_fab2(sch_1):page84_i14@mstr_sconn.sconn288_h44441003(chips)!SCONN288_H44441003_PIP-SCONN,HA!!!F200!CK1P!!!!
S!M_K_CKE<2>!J9M1!60!@baseboard_fab2_lib.baseboard_fab2(sch_1):page84_i14@mstr_sconn.sconn288_h44441003(chips)!SCONN288_H44441003_PIP-SCONN,HA!!!F200!CKE(0)!!!!
S!M_K_CKE<3>!J9M1!203!@baseboard_fab2_lib.baseboard_fab2(sch_1):page84_i14@mstr_sconn.sconn288_h44441003(chips)!SCONN288_H44441003_PIP-SCONN,HA!!!F200!CKE(1)!!!!
S!M_K_DQ<0>!J9M1!5!@baseboard_fab2_lib.baseboard_fab2(sch_1):page84_i14@mstr_sconn.sconn288_h44441003(chips)!SCONN288_H44441003_PIP-SCONN,HA!!!F200!DQ(0)!!!!
S!M_K_DQ<10>!J9M1!23!@baseboard_fab2_lib.baseboard_fab2(sch_1):page84_i14@mstr_sconn.sconn288_h44441003(chips)!SCONN288_H44441003_PIP-SCONN,HA!!!F200!DQ(10)!!!!
S!M_K_DQ<11>!J9M1!168!@baseboard_fab2_lib.baseboard_fab2(sch_1):page84_i14@mstr_sconn.sconn288_h44441003(chips)!SCONN288_H44441003_PIP-SCONN,HA!!!F200!DQ(11)!!!!
S!M_K_DQ<12>!J9M1!14!@baseboard_fab2_lib.baseboard_fab2(sch_1):page84_i14@mstr_sconn.sconn288_h44441003(chips)!SCONN288_H44441003_PIP-SCONN,HA!!!F200!DQ(12)!!!!
S!M_K_DQ<13>!J9M1!159!@baseboard_fab2_lib.baseboard_fab2(sch_1):page84_i14@mstr_sconn.sconn288_h44441003(chips)!SCONN288_H44441003_PIP-SCONN,HA!!!F200!DQ(13)!!!!
S!M_K_DQ<14>!J9M1!21!@baseboard_fab2_lib.baseboard_fab2(sch_1):page84_i14@mstr_sconn.sconn288_h44441003(chips)!SCONN288_H44441003_PIP-SCONN,HA!!!F200!DQ(14)!!!!
S!M_K_DQ<15>!J9M1!166!@baseboard_fab2_lib.baseboard_fab2(sch_1):page84_i14@mstr_sconn.sconn288_h44441003(chips)!SCONN288_H44441003_PIP-SCONN,HA!!!F200!DQ(15)!!!!
S!M_K_DQ<16>!J9M1!27!@baseboard_fab2_lib.baseboard_fab2(sch_1):page84_i14@mstr_sconn.sconn288_h44441003(chips)!SCONN288_H44441003_PIP-SCONN,HA!!!F200!DQ(16)!!!!
S!M_K_DQ<17>!J9M1!172!@baseboard_fab2_lib.baseboard_fab2(sch_1):page84_i14@mstr_sconn.sconn288_h44441003(chips)!SCONN288_H44441003_PIP-SCONN,HA!!!F200!DQ(17)!!!!
S!M_K_DQ<18>!J9M1!34!@baseboard_fab2_lib.baseboard_fab2(sch_1):page84_i14@mstr_sconn.sconn288_h44441003(chips)!SCONN288_H44441003_PIP-SCONN,HA!!!F200!DQ(18)!!!!
S!M_K_DQ<19>!J9M1!179!@baseboard_fab2_lib.baseboard_fab2(sch_1):page84_i14@mstr_sconn.sconn288_h44441003(chips)!SCONN288_H44441003_PIP-SCONN,HA!!!F200!DQ(19)!!!!
S!M_K_DQ<1>!J9M1!150!@baseboard_fab2_lib.baseboard_fab2(sch_1):page84_i14@mstr_sconn.sconn288_h44441003(chips)!SCONN288_H44441003_PIP-SCONN,HA!!!F200!DQ(1)!!!!
S!M_K_DQ<20>!J9M1!25!@baseboard_fab2_lib.baseboard_fab2(sch_1):page84_i14@mstr_sconn.sconn288_h44441003(chips)!SCONN288_H44441003_PIP-SCONN,HA!!!F200!DQ(20)!!!!
S!M_K_DQ<21>!J9M1!170!@baseboard_fab2_lib.baseboard_fab2(sch_1):page84_i14@mstr_sconn.sconn288_h44441003(chips)!SCONN288_H44441003_PIP-SCONN,HA!!!F200!DQ(21)!!!!
S!M_K_DQ<22>!J9M1!32!@baseboard_fab2_lib.baseboard_fab2(sch_1):page84_i14@mstr_sconn.sconn288_h44441003(chips)!SCONN288_H44441003_PIP-SCONN,HA!!!F200!DQ(22)!!!!
S!M_K_DQ<23>!J9M1!177!@baseboard_fab2_lib.baseboard_fab2(sch_1):page84_i14@mstr_sconn.sconn288_h44441003(chips)!SCONN288_H44441003_PIP-SCONN,HA!!!F200!DQ(23)!!!!
S!M_K_DQ<24>!J9M1!38!@baseboard_fab2_lib.baseboard_fab2(sch_1):page84_i14@mstr_sconn.sconn288_h44441003(chips)!SCONN288_H44441003_PIP-SCONN,HA!!!F200!DQ(24)!!!!
S!M_K_DQ<25>!J9M1!183!@baseboard_fab2_lib.baseboard_fab2(sch_1):page84_i14@mstr_sconn.sconn288_h44441003(chips)!SCONN288_H44441003_PIP-SCONN,HA!!!F200!DQ(25)!!!!
S!M_K_DQ<26>!J9M1!45!@baseboard_fab2_lib.baseboard_fab2(sch_1):page84_i14@mstr_sconn.sconn288_h44441003(chips)!SCONN288_H44441003_PIP-SCONN,HA!!!F200!DQ(26)!!!!
S!M_K_DQ<27>!J9M1!190!@baseboard_fab2_lib.baseboard_fab2(sch_1):page84_i14@mstr_sconn.sconn288_h44441003(chips)!SCONN288_H44441003_PIP-SCONN,HA!!!F200!DQ(27)!!!!
S!M_K_DQ<28>!J9M1!36!@baseboard_fab2_lib.baseboard_fab2(sch_1):page84_i14@mstr_sconn.sconn288_h44441003(chips)!SCONN288_H44441003_PIP-SCONN,HA!!!F200!DQ(28)!!!!
S!M_K_DQ<29>!J9M1!181!@baseboard_fab2_lib.baseboard_fab2(sch_1):page84_i14@mstr_sconn.sconn288_h44441003(chips)!SCONN288_H44441003_PIP-SCONN,HA!!!F200!DQ(29)!!!!
S!M_K_DQ<2>!J9M1!12!@baseboard_fab2_lib.baseboard_fab2(sch_1):page84_i14@mstr_sconn.sconn288_h44441003(chips)!SCONN288_H44441003_PIP-SCONN,HA!!!F200!DQ(2)!!!!
S!M_K_DQ<30>!J9M1!43!@baseboard_fab2_lib.baseboard_fab2(sch_1):page84_i14@mstr_sconn.sconn288_h44441003(chips)!SCONN288_H44441003_PIP-SCONN,HA!!!F200!DQ(30)!!!!
S!M_K_DQ<31>!J9M1!188!@baseboard_fab2_lib.baseboard_fab2(sch_1):page84_i14@mstr_sconn.sconn288_h44441003(chips)!SCONN288_H44441003_PIP-SCONN,HA!!!F200!DQ(31)!!!!
S!M_K_DQ<32>!J9M1!97!@baseboard_fab2_lib.baseboard_fab2(sch_1):page84_i14@mstr_sconn.sconn288_h44441003(chips)!SCONN288_H44441003_PIP-SCONN,HA!!!F200!DQ(32)!!!!
S!M_K_DQ<33>!J9M1!242!@baseboard_fab2_lib.baseboard_fab2(sch_1):page84_i14@mstr_sconn.sconn288_h44441003(chips)!SCONN288_H44441003_PIP-SCONN,HA!!!F200!DQ(33)!!!!
S!M_K_DQ<34>!J9M1!104!@baseboard_fab2_lib.baseboard_fab2(sch_1):page84_i14@mstr_sconn.sconn288_h44441003(chips)!SCONN288_H44441003_PIP-SCONN,HA!!!F200!DQ(34)!!!!
S!M_K_DQ<35>!J9M1!249!@baseboard_fab2_lib.baseboard_fab2(sch_1):page84_i14@mstr_sconn.sconn288_h44441003(chips)!SCONN288_H44441003_PIP-SCONN,HA!!!F200!DQ(35)!!!!
S!M_K_DQ<36>!J9M1!95!@baseboard_fab2_lib.baseboard_fab2(sch_1):page84_i14@mstr_sconn.sconn288_h44441003(chips)!SCONN288_H44441003_PIP-SCONN,HA!!!F200!DQ(36)!!!!
S!M_K_DQ<37>!J9M1!240!@baseboard_fab2_lib.baseboard_fab2(sch_1):page84_i14@mstr_sconn.sconn288_h44441003(chips)!SCONN288_H44441003_PIP-SCONN,HA!!!F200!DQ(37)!!!!
S!M_K_DQ<38>!J9M1!102!@baseboard_fab2_lib.baseboard_fab2(sch_1):page84_i14@mstr_sconn.sconn288_h44441003(chips)!SCONN288_H44441003_PIP-SCONN,HA!!!F200!DQ(38)!!!!
S!M_K_DQ<39>!J9M1!247!@baseboard_fab2_lib.baseboard_fab2(sch_1):page84_i14@mstr_sconn.sconn288_h44441003(chips)!SCONN288_H44441003_PIP-SCONN,HA!!!F200!DQ(39)!!!!
S!M_K_DQ<3>!J9M1!157!@baseboard_fab2_lib.baseboard_fab2(sch_1):page84_i14@mstr_sconn.sconn288_h44441003(chips)!SCONN288_H44441003_PIP-SCONN,HA!!!F200!DQ(3)!!!!
S!M_K_DQ<40>!J9M1!108!@baseboard_fab2_lib.baseboard_fab2(sch_1):page84_i14@mstr_sconn.sconn288_h44441003(chips)!SCONN288_H44441003_PIP-SCONN,HA!!!F200!DQ(40)!!!!
S!M_K_DQ<41>!J9M1!253!@baseboard_fab2_lib.baseboard_fab2(sch_1):page84_i14@mstr_sconn.sconn288_h44441003(chips)!SCONN288_H44441003_PIP-SCONN,HA!!!F200!DQ(41)!!!!
S!M_K_DQ<42>!J9M1!115!@baseboard_fab2_lib.baseboard_fab2(sch_1):page84_i14@mstr_sconn.sconn288_h44441003(chips)!SCONN288_H44441003_PIP-SCONN,HA!!!F200!DQ(42)!!!!
S!M_K_DQ<43>!J9M1!260!@baseboard_fab2_lib.baseboard_fab2(sch_1):page84_i14@mstr_sconn.sconn288_h44441003(chips)!SCONN288_H44441003_PIP-SCONN,HA!!!F200!DQ(43)!!!!
S!M_K_DQ<44>!J9M1!106!@baseboard_fab2_lib.baseboard_fab2(sch_1):page84_i14@mstr_sconn.sconn288_h44441003(chips)!SCONN288_H44441003_PIP-SCONN,HA!!!F200!DQ(44)!!!!
S!M_K_DQ<45>!J9M1!251!@baseboard_fab2_lib.baseboard_fab2(sch_1):page84_i14@mstr_sconn.sconn288_h44441003(chips)!SCONN288_H44441003_PIP-SCONN,HA!!!F200!DQ(45)!!!!
S!M_K_DQ<46>!J9M1!113!@baseboard_fab2_lib.baseboard_fab2(sch_1):page84_i14@mstr_sconn.sconn288_h44441003(chips)!SCONN288_H44441003_PIP-SCONN,HA!!!F200!DQ(46)!!!!
S!M_K_DQ<47>!J9M1!258!@baseboard_fab2_lib.baseboard_fab2(sch_1):page84_i14@mstr_sconn.sconn288_h44441003(chips)!SCONN288_H44441003_PIP-SCONN,HA!!!F200!DQ(47)!!!!
S!M_K_DQ<48>!J9M1!119!@baseboard_fab2_lib.baseboard_fab2(sch_1):page84_i14@mstr_sconn.sconn288_h44441003(chips)!SCONN288_H44441003_PIP-SCONN,HA!!!F200!DQ(48)!!!!
S!M_K_DQ<49>!J9M1!264!@baseboard_fab2_lib.baseboard_fab2(sch_1):page84_i14@mstr_sconn.sconn288_h44441003(chips)!SCONN288_H44441003_PIP-SCONN,HA!!!F200!DQ(49)!!!!
S!M_K_DQ<4>!J9M1!3!@baseboard_fab2_lib.baseboard_fab2(sch_1):page84_i14@mstr_sconn.sconn288_h44441003(chips)!SCONN288_H44441003_PIP-SCONN,HA!!!F200!DQ(4)!!!!
S!M_K_DQ<50>!J9M1!126!@baseboard_fab2_lib.baseboard_fab2(sch_1):page84_i14@mstr_sconn.sconn288_h44441003(chips)!SCONN288_H44441003_PIP-SCONN,HA!!!F200!DQ(50)!!!!
S!M_K_DQ<51>!J9M1!271!@baseboard_fab2_lib.baseboard_fab2(sch_1):page84_i14@mstr_sconn.sconn288_h44441003(chips)!SCONN288_H44441003_PIP-SCONN,HA!!!F200!DQ(51)!!!!
S!M_K_DQ<52>!J9M1!117!@baseboard_fab2_lib.baseboard_fab2(sch_1):page84_i14@mstr_sconn.sconn288_h44441003(chips)!SCONN288_H44441003_PIP-SCONN,HA!!!F200!DQ(52)!!!!
S!M_K_DQ<53>!J9M1!262!@baseboard_fab2_lib.baseboard_fab2(sch_1):page84_i14@mstr_sconn.sconn288_h44441003(chips)!SCONN288_H44441003_PIP-SCONN,HA!!!F200!DQ(53)!!!!
S!M_K_DQ<54>!J9M1!124!@baseboard_fab2_lib.baseboard_fab2(sch_1):page84_i14@mstr_sconn.sconn288_h44441003(chips)!SCONN288_H44441003_PIP-SCONN,HA!!!F200!DQ(54)!!!!
S!M_K_DQ<55>!J9M1!269!@baseboard_fab2_lib.baseboard_fab2(sch_1):page84_i14@mstr_sconn.sconn288_h44441003(chips)!SCONN288_H44441003_PIP-SCONN,HA!!!F200!DQ(55)!!!!
S!M_K_DQ<56>!J9M1!130!@baseboard_fab2_lib.baseboard_fab2(sch_1):page84_i14@mstr_sconn.sconn288_h44441003(chips)!SCONN288_H44441003_PIP-SCONN,HA!!!F200!DQ(56)!!!!
S!M_K_DQ<57>!J9M1!275!@baseboard_fab2_lib.baseboard_fab2(sch_1):page84_i14@mstr_sconn.sconn288_h44441003(chips)!SCONN288_H44441003_PIP-SCONN,HA!!!F200!DQ(57)!!!!
S!M_K_DQ<58>!J9M1!137!@baseboard_fab2_lib.baseboard_fab2(sch_1):page84_i14@mstr_sconn.sconn288_h44441003(chips)!SCONN288_H44441003_PIP-SCONN,HA!!!F200!DQ(58)!!!!
S!M_K_DQ<59>!J9M1!282!@baseboard_fab2_lib.baseboard_fab2(sch_1):page84_i14@mstr_sconn.sconn288_h44441003(chips)!SCONN288_H44441003_PIP-SCONN,HA!!!F200!DQ(59)!!!!
S!M_K_DQ<5>!J9M1!148!@baseboard_fab2_lib.baseboard_fab2(sch_1):page84_i14@mstr_sconn.sconn288_h44441003(chips)!SCONN288_H44441003_PIP-SCONN,HA!!!F200!DQ(5)!!!!
S!M_K_DQ<60>!J9M1!128!@baseboard_fab2_lib.baseboard_fab2(sch_1):page84_i14@mstr_sconn.sconn288_h44441003(chips)!SCONN288_H44441003_PIP-SCONN,HA!!!F200!DQ(60)!!!!
S!M_K_DQ<61>!J9M1!273!@baseboard_fab2_lib.baseboard_fab2(sch_1):page84_i14@mstr_sconn.sconn288_h44441003(chips)!SCONN288_H44441003_PIP-SCONN,HA!!!F200!DQ(61)!!!!
S!M_K_DQ<62>!J9M1!135!@baseboard_fab2_lib.baseboard_fab2(sch_1):page84_i14@mstr_sconn.sconn288_h44441003(chips)!SCONN288_H44441003_PIP-SCONN,HA!!!F200!DQ(62)!!!!
S!M_K_DQ<63>!J9M1!280!@baseboard_fab2_lib.baseboard_fab2(sch_1):page84_i14@mstr_sconn.sconn288_h44441003(chips)!SCONN288_H44441003_PIP-SCONN,HA!!!F200!DQ(63)!!!!
S!M_K_DQ<6>!J9M1!10!@baseboard_fab2_lib.baseboard_fab2(sch_1):page84_i14@mstr_sconn.sconn288_h44441003(chips)!SCONN288_H44441003_PIP-SCONN,HA!!!F200!DQ(6)!!!!
S!M_K_DQ<7>!J9M1!155!@baseboard_fab2_lib.baseboard_fab2(sch_1):page84_i14@mstr_sconn.sconn288_h44441003(chips)!SCONN288_H44441003_PIP-SCONN,HA!!!F200!DQ(7)!!!!
S!M_K_DQ<8>!J9M1!16!@baseboard_fab2_lib.baseboard_fab2(sch_1):page84_i14@mstr_sconn.sconn288_h44441003(chips)!SCONN288_H44441003_PIP-SCONN,HA!!!F200!DQ(8)!!!!
S!M_K_DQ<9>!J9M1!161!@baseboard_fab2_lib.baseboard_fab2(sch_1):page84_i14@mstr_sconn.sconn288_h44441003(chips)!SCONN288_H44441003_PIP-SCONN,HA!!!F200!DQ(9)!!!!
S!FM_DIMM_EVENT_COD_N!J9M1!78!@baseboard_fab2_lib.baseboard_fab2(sch_1):page84_i14@mstr_sconn.sconn288_h44441003(chips)!SCONN288_H44441003_PIP-SCONN,HA!!!F200!EVENT_N!!!!
S!M_K_ODT<2>!J9M1!87!@baseboard_fab2_lib.baseboard_fab2(sch_1):page84_i14@mstr_sconn.sconn288_h44441003(chips)!SCONN288_H44441003_PIP-SCONN,HA!!!F200!ODT(0)!!!!
S!M_K_ODT<3>!J9M1!91!@baseboard_fab2_lib.baseboard_fab2(sch_1):page84_i14@mstr_sconn.sconn288_h44441003(chips)!SCONN288_H44441003_PIP-SCONN,HA!!!F200!ODT(1)!!!!
S!M_K_PAR!J9M1!222!@baseboard_fab2_lib.baseboard_fab2(sch_1):page84_i14@mstr_sconn.sconn288_h44441003(chips)!SCONN288_H44441003_PIP-SCONN,HA!!!F200!PAR!!!!
S!M_KLM_RST_N!J9M1!58!@baseboard_fab2_lib.baseboard_fab2(sch_1):page84_i14@mstr_sconn.sconn288_h44441003(chips)!SCONN288_H44441003_PIP-SCONN,HA!!!F200!RESET_N!!!!
S!TP_CH_K_DIMM0_RFU_0!J9M1!205!@baseboard_fab2_lib.baseboard_fab2(sch_1):page84_i14@mstr_sconn.sconn288_h44441003(chips)!SCONN288_H44441003_PIP-SCONN,HA!!!F200!RFU(0)!!!!
S!TP_CH_K_DIMM0_RFU_1!J9M1!227!@baseboard_fab2_lib.baseboard_fab2(sch_1):page84_i14@mstr_sconn.sconn288_h44441003(chips)!SCONN288_H44441003_PIP-SCONN,HA!!!F200!RFU(1)!!!!
S!TP_CH_K_DIMM0_RFU_2!J9M1!144!@baseboard_fab2_lib.baseboard_fab2(sch_1):page84_i14@mstr_sconn.sconn288_h44441003(chips)!SCONN288_H44441003_PIP-SCONN,HA!!!F200!RFU(2)!!!!
S!M_K_CS_N<4>!J9M1!84!@baseboard_fab2_lib.baseboard_fab2(sch_1):page84_i14@mstr_sconn.sconn288_h44441003(chips)!SCONN288_H44441003_PIP-SCONN,HA!!!F200!S0_N!!!!
S!M_K_CS_N<5>!J9M1!89!@baseboard_fab2_lib.baseboard_fab2(sch_1):page84_i14@mstr_sconn.sconn288_h44441003(chips)!SCONN288_H44441003_PIP-SCONN,HA!!!F200!S1_N!!!!
S!M_K_CS_N<6>!J9M1!93!@baseboard_fab2_lib.baseboard_fab2(sch_1):page84_i14@mstr_sconn.sconn288_h44441003(chips)!SCONN288_H44441003_PIP-SCONN,HA!!!F200!S2_N_C(0)!!!!
S!M_K_CS_N<7>!J9M1!237!@baseboard_fab2_lib.baseboard_fab2(sch_1):page84_i14@mstr_sconn.sconn288_h44441003(chips)!SCONN288_H44441003_PIP-SCONN,HA!!!F200!S3_N_C(1)!!!!
S!PVPP_KLM!J9M1!139!@baseboard_fab2_lib.baseboard_fab2(sch_1):page84_i14@mstr_sconn.sconn288_h44441003(chips)!SCONN288_H44441003_PIP-SCONN,HA!!!F200!SA(0)!!!!
S!GND!J9M1!140!@baseboard_fab2_lib.baseboard_fab2(sch_1):page84_i14@mstr_sconn.sconn288_h44441003(chips)!SCONN288_H44441003_PIP-SCONN,HA!!!F200!SA(1)!!!!
S!GND!J9M1!238!@baseboard_fab2_lib.baseboard_fab2(sch_1):page84_i14@mstr_sconn.sconn288_h44441003(chips)!SCONN288_H44441003_PIP-SCONN,HA!!!F200!SA(2)!!!!
S!FM_ADR_COMPLETE_KLM_N!J9M1!230!@baseboard_fab2_lib.baseboard_fab2(sch_1):page84_i14@mstr_sconn.sconn288_h44441003(chips)!SCONN288_H44441003_PIP-SCONN,HA!!!F200!SAVE_N_NC!!!!
S!SMB_DDR_KLM_VPP_SCL!J9M1!141!@baseboard_fab2_lib.baseboard_fab2(sch_1):page84_i14@mstr_sconn.sconn288_h44441003(chips)!SCONN288_H44441003_PIP-SCONN,HA!!!F200!SCL!!!!
S!SMB_DDR_KLM_VPP_SDA!J9M1!285!@baseboard_fab2_lib.baseboard_fab2(sch_1):page84_i14@mstr_sconn.sconn288_h44441003(chips)!SCONN288_H44441003_PIP-SCONN,HA!!!F200!SDA!!!!
S!PVPP_KLM!J9M1!284!@baseboard_fab2_lib.baseboard_fab2(sch_1):page84_i14@mstr_sconn.sconn288_h44441003(chips)!SCONN288_H44441003_PIP-SCONN,HA!!!F200!VDDSPD!!!!
S!M_K_VREF!J9M1!146!@baseboard_fab2_lib.baseboard_fab2(sch_1):page84_i14@mstr_sconn.sconn288_h44441003(chips)!SCONN288_H44441003_PIP-SCONN,HA!!!F200!VREFCA!!!!
S!M_K_DQS_DN<0>!J9M1!152!@baseboard_fab2_lib.baseboard_fab2(sch_1):page84_i102@mstr_sconn.sconn288_h44441003(chips)!SCONN288_H44441003_PIP-SCONN,HA!!!F199!DQS0N!!!!
S!M_K_DQS_DP<0>!J9M1!153!@baseboard_fab2_lib.baseboard_fab2(sch_1):page84_i102@mstr_sconn.sconn288_h44441003(chips)!SCONN288_H44441003_PIP-SCONN,HA!!!F199!DQS0P!!!!
S!M_K_DQS_DN<10>!J9M1!19!@baseboard_fab2_lib.baseboard_fab2(sch_1):page84_i102@mstr_sconn.sconn288_h44441003(chips)!SCONN288_H44441003_PIP-SCONN,HA!!!F199!DQS10N!!!!
S!M_K_DQS_DP<10>!J9M1!18!@baseboard_fab2_lib.baseboard_fab2(sch_1):page84_i102@mstr_sconn.sconn288_h44441003(chips)!SCONN288_H44441003_PIP-SCONN,HA!!!F199!DQS10P!!!!
S!M_K_DQS_DN<11>!J9M1!30!@baseboard_fab2_lib.baseboard_fab2(sch_1):page84_i102@mstr_sconn.sconn288_h44441003(chips)!SCONN288_H44441003_PIP-SCONN,HA!!!F199!DQS11N!!!!
S!M_K_DQS_DP<11>!J9M1!29!@baseboard_fab2_lib.baseboard_fab2(sch_1):page84_i102@mstr_sconn.sconn288_h44441003(chips)!SCONN288_H44441003_PIP-SCONN,HA!!!F199!DQS11P!!!!
S!M_K_DQS_DN<12>!J9M1!41!@baseboard_fab2_lib.baseboard_fab2(sch_1):page84_i102@mstr_sconn.sconn288_h44441003(chips)!SCONN288_H44441003_PIP-SCONN,HA!!!F199!DQS12N!!!!
S!M_K_DQS_DP<12>!J9M1!40!@baseboard_fab2_lib.baseboard_fab2(sch_1):page84_i102@mstr_sconn.sconn288_h44441003(chips)!SCONN288_H44441003_PIP-SCONN,HA!!!F199!DQS12P!!!!
S!M_K_DQS_DN<13>!J9M1!100!@baseboard_fab2_lib.baseboard_fab2(sch_1):page84_i102@mstr_sconn.sconn288_h44441003(chips)!SCONN288_H44441003_PIP-SCONN,HA!!!F199!DQS13N!!!!
S!M_K_DQS_DP<13>!J9M1!99!@baseboard_fab2_lib.baseboard_fab2(sch_1):page84_i102@mstr_sconn.sconn288_h44441003(chips)!SCONN288_H44441003_PIP-SCONN,HA!!!F199!DQS13P!!!!
S!M_K_DQS_DN<14>!J9M1!111!@baseboard_fab2_lib.baseboard_fab2(sch_1):page84_i102@mstr_sconn.sconn288_h44441003(chips)!SCONN288_H44441003_PIP-SCONN,HA!!!F199!DQS14N!!!!
S!M_K_DQS_DP<14>!J9M1!110!@baseboard_fab2_lib.baseboard_fab2(sch_1):page84_i102@mstr_sconn.sconn288_h44441003(chips)!SCONN288_H44441003_PIP-SCONN,HA!!!F199!DQS14P!!!!
S!M_K_DQS_DN<15>!J9M1!122!@baseboard_fab2_lib.baseboard_fab2(sch_1):page84_i102@mstr_sconn.sconn288_h44441003(chips)!SCONN288_H44441003_PIP-SCONN,HA!!!F199!DQS15N!!!!
S!M_K_DQS_DP<15>!J9M1!121!@baseboard_fab2_lib.baseboard_fab2(sch_1):page84_i102@mstr_sconn.sconn288_h44441003(chips)!SCONN288_H44441003_PIP-SCONN,HA!!!F199!DQS15P!!!!
S!M_K_DQS_DN<16>!J9M1!133!@baseboard_fab2_lib.baseboard_fab2(sch_1):page84_i102@mstr_sconn.sconn288_h44441003(chips)!SCONN288_H44441003_PIP-SCONN,HA!!!F199!DQS16N!!!!
S!M_K_DQS_DP<16>!J9M1!132!@baseboard_fab2_lib.baseboard_fab2(sch_1):page84_i102@mstr_sconn.sconn288_h44441003(chips)!SCONN288_H44441003_PIP-SCONN,HA!!!F199!DQS16P!!!!
S!M_K_DQS_DN<17>!J9M1!52!@baseboard_fab2_lib.baseboard_fab2(sch_1):page84_i102@mstr_sconn.sconn288_h44441003(chips)!SCONN288_H44441003_PIP-SCONN,HA!!!F199!DQS17N!!!!
S!M_K_DQS_DP<17>!J9M1!51!@baseboard_fab2_lib.baseboard_fab2(sch_1):page84_i102@mstr_sconn.sconn288_h44441003(chips)!SCONN288_H44441003_PIP-SCONN,HA!!!F199!DQS17P!!!!
S!M_K_DQS_DN<1>!J9M1!163!@baseboard_fab2_lib.baseboard_fab2(sch_1):page84_i102@mstr_sconn.sconn288_h44441003(chips)!SCONN288_H44441003_PIP-SCONN,HA!!!F199!DQS1N!!!!
S!M_K_DQS_DP<1>!J9M1!164!@baseboard_fab2_lib.baseboard_fab2(sch_1):page84_i102@mstr_sconn.sconn288_h44441003(chips)!SCONN288_H44441003_PIP-SCONN,HA!!!F199!DQS1P!!!!
S!M_K_DQS_DN<2>!J9M1!174!@baseboard_fab2_lib.baseboard_fab2(sch_1):page84_i102@mstr_sconn.sconn288_h44441003(chips)!SCONN288_H44441003_PIP-SCONN,HA!!!F199!DQS2N!!!!
S!M_K_DQS_DP<2>!J9M1!175!@baseboard_fab2_lib.baseboard_fab2(sch_1):page84_i102@mstr_sconn.sconn288_h44441003(chips)!SCONN288_H44441003_PIP-SCONN,HA!!!F199!DQS2P!!!!
S!M_K_DQS_DN<3>!J9M1!185!@baseboard_fab2_lib.baseboard_fab2(sch_1):page84_i102@mstr_sconn.sconn288_h44441003(chips)!SCONN288_H44441003_PIP-SCONN,HA!!!F199!DQS3N!!!!
S!M_K_DQS_DP<3>!J9M1!186!@baseboard_fab2_lib.baseboard_fab2(sch_1):page84_i102@mstr_sconn.sconn288_h44441003(chips)!SCONN288_H44441003_PIP-SCONN,HA!!!F199!DQS3P!!!!
S!M_K_DQS_DN<4>!J9M1!244!@baseboard_fab2_lib.baseboard_fab2(sch_1):page84_i102@mstr_sconn.sconn288_h44441003(chips)!SCONN288_H44441003_PIP-SCONN,HA!!!F199!DQS4N!!!!
S!M_K_DQS_DP<4>!J9M1!245!@baseboard_fab2_lib.baseboard_fab2(sch_1):page84_i102@mstr_sconn.sconn288_h44441003(chips)!SCONN288_H44441003_PIP-SCONN,HA!!!F199!DQS4P!!!!
S!M_K_DQS_DN<5>!J9M1!255!@baseboard_fab2_lib.baseboard_fab2(sch_1):page84_i102@mstr_sconn.sconn288_h44441003(chips)!SCONN288_H44441003_PIP-SCONN,HA!!!F199!DQS5N!!!!
S!M_K_DQS_DP<5>!J9M1!256!@baseboard_fab2_lib.baseboard_fab2(sch_1):page84_i102@mstr_sconn.sconn288_h44441003(chips)!SCONN288_H44441003_PIP-SCONN,HA!!!F199!DQS5P!!!!
S!M_K_DQS_DN<6>!J9M1!266!@baseboard_fab2_lib.baseboard_fab2(sch_1):page84_i102@mstr_sconn.sconn288_h44441003(chips)!SCONN288_H44441003_PIP-SCONN,HA!!!F199!DQS6N!!!!
S!M_K_DQS_DP<6>!J9M1!267!@baseboard_fab2_lib.baseboard_fab2(sch_1):page84_i102@mstr_sconn.sconn288_h44441003(chips)!SCONN288_H44441003_PIP-SCONN,HA!!!F199!DQS6P!!!!
S!M_K_DQS_DN<7>!J9M1!277!@baseboard_fab2_lib.baseboard_fab2(sch_1):page84_i102@mstr_sconn.sconn288_h44441003(chips)!SCONN288_H44441003_PIP-SCONN,HA!!!F199!DQS7N!!!!
S!M_K_DQS_DP<7>!J9M1!278!@baseboard_fab2_lib.baseboard_fab2(sch_1):page84_i102@mstr_sconn.sconn288_h44441003(chips)!SCONN288_H44441003_PIP-SCONN,HA!!!F199!DQS7P!!!!
S!M_K_DQS_DN<8>!J9M1!196!@baseboard_fab2_lib.baseboard_fab2(sch_1):page84_i102@mstr_sconn.sconn288_h44441003(chips)!SCONN288_H44441003_PIP-SCONN,HA!!!F199!DQS8N!!!!
S!M_K_DQS_DP<8>!J9M1!197!@baseboard_fab2_lib.baseboard_fab2(sch_1):page84_i102@mstr_sconn.sconn288_h44441003(chips)!SCONN288_H44441003_PIP-SCONN,HA!!!F199!DQS8P!!!!
S!M_K_DQS_DN<9>!J9M1!8!@baseboard_fab2_lib.baseboard_fab2(sch_1):page84_i102@mstr_sconn.sconn288_h44441003(chips)!SCONN288_H44441003_PIP-SCONN,HA!!!F199!DQS9N!!!!
S!M_K_DQS_DP<9>!J9M1!7!@baseboard_fab2_lib.baseboard_fab2(sch_1):page84_i102@mstr_sconn.sconn288_h44441003(chips)!SCONN288_H44441003_PIP-SCONN,HA!!!F199!DQS9P!!!!
S!GND!J9M1!283!@baseboard_fab2_lib.baseboard_fab2(sch_1):page84_i138@mstr_sconn.sconn288_h44441003(chips)!SCONN288_H44441003_PIP-SCONN,HA!!!F198!VSS(0)!!!!
S!GND!J9M1!261!@baseboard_fab2_lib.baseboard_fab2(sch_1):page84_i138@mstr_sconn.sconn288_h44441003(chips)!SCONN288_H44441003_PIP-SCONN,HA!!!F198!VSS(10)!!!!
S!GND!J9M1!259!@baseboard_fab2_lib.baseboard_fab2(sch_1):page84_i138@mstr_sconn.sconn288_h44441003(chips)!SCONN288_H44441003_PIP-SCONN,HA!!!F198!VSS(11)!!!!
S!GND!J9M1!257!@baseboard_fab2_lib.baseboard_fab2(sch_1):page84_i138@mstr_sconn.sconn288_h44441003(chips)!SCONN288_H44441003_PIP-SCONN,HA!!!F198!VSS(12)!!!!
S!GND!J9M1!254!@baseboard_fab2_lib.baseboard_fab2(sch_1):page84_i138@mstr_sconn.sconn288_h44441003(chips)!SCONN288_H44441003_PIP-SCONN,HA!!!F198!VSS(13)!!!!
S!GND!J9M1!252!@baseboard_fab2_lib.baseboard_fab2(sch_1):page84_i138@mstr_sconn.sconn288_h44441003(chips)!SCONN288_H44441003_PIP-SCONN,HA!!!F198!VSS(14)!!!!
S!GND!J9M1!250!@baseboard_fab2_lib.baseboard_fab2(sch_1):page84_i138@mstr_sconn.sconn288_h44441003(chips)!SCONN288_H44441003_PIP-SCONN,HA!!!F198!VSS(15)!!!!
S!GND!J9M1!248!@baseboard_fab2_lib.baseboard_fab2(sch_1):page84_i138@mstr_sconn.sconn288_h44441003(chips)!SCONN288_H44441003_PIP-SCONN,HA!!!F198!VSS(16)!!!!
S!GND!J9M1!246!@baseboard_fab2_lib.baseboard_fab2(sch_1):page84_i138@mstr_sconn.sconn288_h44441003(chips)!SCONN288_H44441003_PIP-SCONN,HA!!!F198!VSS(17)!!!!
S!GND!J9M1!243!@baseboard_fab2_lib.baseboard_fab2(sch_1):page84_i138@mstr_sconn.sconn288_h44441003(chips)!SCONN288_H44441003_PIP-SCONN,HA!!!F198!VSS(18)!!!!
S!GND!J9M1!241!@baseboard_fab2_lib.baseboard_fab2(sch_1):page84_i138@mstr_sconn.sconn288_h44441003(chips)!SCONN288_H44441003_PIP-SCONN,HA!!!F198!VSS(19)!!!!
S!GND!J9M1!281!@baseboard_fab2_lib.baseboard_fab2(sch_1):page84_i138@mstr_sconn.sconn288_h44441003(chips)!SCONN288_H44441003_PIP-SCONN,HA!!!F198!VSS(1)!!!!
S!GND!J9M1!239!@baseboard_fab2_lib.baseboard_fab2(sch_1):page84_i138@mstr_sconn.sconn288_h44441003(chips)!SCONN288_H44441003_PIP-SCONN,HA!!!F198!VSS(20)!!!!
S!GND!J9M1!202!@baseboard_fab2_lib.baseboard_fab2(sch_1):page84_i138@mstr_sconn.sconn288_h44441003(chips)!SCONN288_H44441003_PIP-SCONN,HA!!!F198!VSS(21)!!!!
S!GND!J9M1!200!@baseboard_fab2_lib.baseboard_fab2(sch_1):page84_i138@mstr_sconn.sconn288_h44441003(chips)!SCONN288_H44441003_PIP-SCONN,HA!!!F198!VSS(22)!!!!
S!GND!J9M1!198!@baseboard_fab2_lib.baseboard_fab2(sch_1):page84_i138@mstr_sconn.sconn288_h44441003(chips)!SCONN288_H44441003_PIP-SCONN,HA!!!F198!VSS(23)!!!!
S!GND!J9M1!195!@baseboard_fab2_lib.baseboard_fab2(sch_1):page84_i138@mstr_sconn.sconn288_h44441003(chips)!SCONN288_H44441003_PIP-SCONN,HA!!!F198!VSS(24)!!!!
S!GND!J9M1!193!@baseboard_fab2_lib.baseboard_fab2(sch_1):page84_i138@mstr_sconn.sconn288_h44441003(chips)!SCONN288_H44441003_PIP-SCONN,HA!!!F198!VSS(25)!!!!
S!GND!J9M1!191!@baseboard_fab2_lib.baseboard_fab2(sch_1):page84_i138@mstr_sconn.sconn288_h44441003(chips)!SCONN288_H44441003_PIP-SCONN,HA!!!F198!VSS(26)!!!!
S!GND!J9M1!189!@baseboard_fab2_lib.baseboard_fab2(sch_1):page84_i138@mstr_sconn.sconn288_h44441003(chips)!SCONN288_H44441003_PIP-SCONN,HA!!!F198!VSS(27)!!!!
S!GND!J9M1!187!@baseboard_fab2_lib.baseboard_fab2(sch_1):page84_i138@mstr_sconn.sconn288_h44441003(chips)!SCONN288_H44441003_PIP-SCONN,HA!!!F198!VSS(28)!!!!
S!GND!J9M1!184!@baseboard_fab2_lib.baseboard_fab2(sch_1):page84_i138@mstr_sconn.sconn288_h44441003(chips)!SCONN288_H44441003_PIP-SCONN,HA!!!F198!VSS(29)!!!!
S!GND!J9M1!279!@baseboard_fab2_lib.baseboard_fab2(sch_1):page84_i138@mstr_sconn.sconn288_h44441003(chips)!SCONN288_H44441003_PIP-SCONN,HA!!!F198!VSS(2)!!!!
S!GND!J9M1!182!@baseboard_fab2_lib.baseboard_fab2(sch_1):page84_i138@mstr_sconn.sconn288_h44441003(chips)!SCONN288_H44441003_PIP-SCONN,HA!!!F198!VSS(30)!!!!
S!GND!J9M1!180!@baseboard_fab2_lib.baseboard_fab2(sch_1):page84_i138@mstr_sconn.sconn288_h44441003(chips)!SCONN288_H44441003_PIP-SCONN,HA!!!F198!VSS(31)!!!!
S!GND!J9M1!178!@baseboard_fab2_lib.baseboard_fab2(sch_1):page84_i138@mstr_sconn.sconn288_h44441003(chips)!SCONN288_H44441003_PIP-SCONN,HA!!!F198!VSS(32)!!!!
S!GND!J9M1!176!@baseboard_fab2_lib.baseboard_fab2(sch_1):page84_i138@mstr_sconn.sconn288_h44441003(chips)!SCONN288_H44441003_PIP-SCONN,HA!!!F198!VSS(33)!!!!
S!GND!J9M1!173!@baseboard_fab2_lib.baseboard_fab2(sch_1):page84_i138@mstr_sconn.sconn288_h44441003(chips)!SCONN288_H44441003_PIP-SCONN,HA!!!F198!VSS(34)!!!!
S!GND!J9M1!171!@baseboard_fab2_lib.baseboard_fab2(sch_1):page84_i138@mstr_sconn.sconn288_h44441003(chips)!SCONN288_H44441003_PIP-SCONN,HA!!!F198!VSS(35)!!!!
S!GND!J9M1!169!@baseboard_fab2_lib.baseboard_fab2(sch_1):page84_i138@mstr_sconn.sconn288_h44441003(chips)!SCONN288_H44441003_PIP-SCONN,HA!!!F198!VSS(36)!!!!
S!GND!J9M1!167!@baseboard_fab2_lib.baseboard_fab2(sch_1):page84_i138@mstr_sconn.sconn288_h44441003(chips)!SCONN288_H44441003_PIP-SCONN,HA!!!F198!VSS(37)!!!!
S!GND!J9M1!165!@baseboard_fab2_lib.baseboard_fab2(sch_1):page84_i138@mstr_sconn.sconn288_h44441003(chips)!SCONN288_H44441003_PIP-SCONN,HA!!!F198!VSS(38)!!!!
S!GND!J9M1!162!@baseboard_fab2_lib.baseboard_fab2(sch_1):page84_i138@mstr_sconn.sconn288_h44441003(chips)!SCONN288_H44441003_PIP-SCONN,HA!!!F198!VSS(39)!!!!
S!GND!J9M1!276!@baseboard_fab2_lib.baseboard_fab2(sch_1):page84_i138@mstr_sconn.sconn288_h44441003(chips)!SCONN288_H44441003_PIP-SCONN,HA!!!F198!VSS(3)!!!!
S!GND!J9M1!160!@baseboard_fab2_lib.baseboard_fab2(sch_1):page84_i138@mstr_sconn.sconn288_h44441003(chips)!SCONN288_H44441003_PIP-SCONN,HA!!!F198!VSS(40)!!!!
S!GND!J9M1!158!@baseboard_fab2_lib.baseboard_fab2(sch_1):page84_i138@mstr_sconn.sconn288_h44441003(chips)!SCONN288_H44441003_PIP-SCONN,HA!!!F198!VSS(41)!!!!
S!GND!J9M1!156!@baseboard_fab2_lib.baseboard_fab2(sch_1):page84_i138@mstr_sconn.sconn288_h44441003(chips)!SCONN288_H44441003_PIP-SCONN,HA!!!F198!VSS(42)!!!!
S!GND!J9M1!154!@baseboard_fab2_lib.baseboard_fab2(sch_1):page84_i138@mstr_sconn.sconn288_h44441003(chips)!SCONN288_H44441003_PIP-SCONN,HA!!!F198!VSS(43)!!!!
S!GND!J9M1!151!@baseboard_fab2_lib.baseboard_fab2(sch_1):page84_i138@mstr_sconn.sconn288_h44441003(chips)!SCONN288_H44441003_PIP-SCONN,HA!!!F198!VSS(44)!!!!
S!GND!J9M1!149!@baseboard_fab2_lib.baseboard_fab2(sch_1):page84_i138@mstr_sconn.sconn288_h44441003(chips)!SCONN288_H44441003_PIP-SCONN,HA!!!F198!VSS(45)!!!!
S!GND!J9M1!147!@baseboard_fab2_lib.baseboard_fab2(sch_1):page84_i138@mstr_sconn.sconn288_h44441003(chips)!SCONN288_H44441003_PIP-SCONN,HA!!!F198!VSS(46)!!!!
S!GND!J9M1!138!@baseboard_fab2_lib.baseboard_fab2(sch_1):page84_i138@mstr_sconn.sconn288_h44441003(chips)!SCONN288_H44441003_PIP-SCONN,HA!!!F198!VSS(47)!!!!
S!GND!J9M1!136!@baseboard_fab2_lib.baseboard_fab2(sch_1):page84_i138@mstr_sconn.sconn288_h44441003(chips)!SCONN288_H44441003_PIP-SCONN,HA!!!F198!VSS(48)!!!!
S!GND!J9M1!134!@baseboard_fab2_lib.baseboard_fab2(sch_1):page84_i138@mstr_sconn.sconn288_h44441003(chips)!SCONN288_H44441003_PIP-SCONN,HA!!!F198!VSS(49)!!!!
S!GND!J9M1!274!@baseboard_fab2_lib.baseboard_fab2(sch_1):page84_i138@mstr_sconn.sconn288_h44441003(chips)!SCONN288_H44441003_PIP-SCONN,HA!!!F198!VSS(4)!!!!
S!GND!J9M1!131!@baseboard_fab2_lib.baseboard_fab2(sch_1):page84_i138@mstr_sconn.sconn288_h44441003(chips)!SCONN288_H44441003_PIP-SCONN,HA!!!F198!VSS(50)!!!!
S!GND!J9M1!129!@baseboard_fab2_lib.baseboard_fab2(sch_1):page84_i138@mstr_sconn.sconn288_h44441003(chips)!SCONN288_H44441003_PIP-SCONN,HA!!!F198!VSS(51)!!!!
S!GND!J9M1!127!@baseboard_fab2_lib.baseboard_fab2(sch_1):page84_i138@mstr_sconn.sconn288_h44441003(chips)!SCONN288_H44441003_PIP-SCONN,HA!!!F198!VSS(52)!!!!
S!GND!J9M1!125!@baseboard_fab2_lib.baseboard_fab2(sch_1):page84_i138@mstr_sconn.sconn288_h44441003(chips)!SCONN288_H44441003_PIP-SCONN,HA!!!F198!VSS(53)!!!!
S!GND!J9M1!123!@baseboard_fab2_lib.baseboard_fab2(sch_1):page84_i138@mstr_sconn.sconn288_h44441003(chips)!SCONN288_H44441003_PIP-SCONN,HA!!!F198!VSS(54)!!!!
S!GND!J9M1!120!@baseboard_fab2_lib.baseboard_fab2(sch_1):page84_i138@mstr_sconn.sconn288_h44441003(chips)!SCONN288_H44441003_PIP-SCONN,HA!!!F198!VSS(55)!!!!
S!GND!J9M1!118!@baseboard_fab2_lib.baseboard_fab2(sch_1):page84_i138@mstr_sconn.sconn288_h44441003(chips)!SCONN288_H44441003_PIP-SCONN,HA!!!F198!VSS(56)!!!!
S!GND!J9M1!116!@baseboard_fab2_lib.baseboard_fab2(sch_1):page84_i138@mstr_sconn.sconn288_h44441003(chips)!SCONN288_H44441003_PIP-SCONN,HA!!!F198!VSS(57)!!!!
S!GND!J9M1!114!@baseboard_fab2_lib.baseboard_fab2(sch_1):page84_i138@mstr_sconn.sconn288_h44441003(chips)!SCONN288_H44441003_PIP-SCONN,HA!!!F198!VSS(58)!!!!
S!GND!J9M1!112!@baseboard_fab2_lib.baseboard_fab2(sch_1):page84_i138@mstr_sconn.sconn288_h44441003(chips)!SCONN288_H44441003_PIP-SCONN,HA!!!F198!VSS(59)!!!!
S!GND!J9M1!272!@baseboard_fab2_lib.baseboard_fab2(sch_1):page84_i138@mstr_sconn.sconn288_h44441003(chips)!SCONN288_H44441003_PIP-SCONN,HA!!!F198!VSS(5)!!!!
S!GND!J9M1!109!@baseboard_fab2_lib.baseboard_fab2(sch_1):page84_i138@mstr_sconn.sconn288_h44441003(chips)!SCONN288_H44441003_PIP-SCONN,HA!!!F198!VSS(60)!!!!
S!GND!J9M1!107!@baseboard_fab2_lib.baseboard_fab2(sch_1):page84_i138@mstr_sconn.sconn288_h44441003(chips)!SCONN288_H44441003_PIP-SCONN,HA!!!F198!VSS(61)!!!!
S!GND!J9M1!105!@baseboard_fab2_lib.baseboard_fab2(sch_1):page84_i138@mstr_sconn.sconn288_h44441003(chips)!SCONN288_H44441003_PIP-SCONN,HA!!!F198!VSS(62)!!!!
S!GND!J9M1!103!@baseboard_fab2_lib.baseboard_fab2(sch_1):page84_i138@mstr_sconn.sconn288_h44441003(chips)!SCONN288_H44441003_PIP-SCONN,HA!!!F198!VSS(63)!!!!
S!GND!J9M1!101!@baseboard_fab2_lib.baseboard_fab2(sch_1):page84_i138@mstr_sconn.sconn288_h44441003(chips)!SCONN288_H44441003_PIP-SCONN,HA!!!F198!VSS(64)!!!!
S!GND!J9M1!98!@baseboard_fab2_lib.baseboard_fab2(sch_1):page84_i138@mstr_sconn.sconn288_h44441003(chips)!SCONN288_H44441003_PIP-SCONN,HA!!!F198!VSS(65)!!!!
S!GND!J9M1!96!@baseboard_fab2_lib.baseboard_fab2(sch_1):page84_i138@mstr_sconn.sconn288_h44441003(chips)!SCONN288_H44441003_PIP-SCONN,HA!!!F198!VSS(66)!!!!
S!GND!J9M1!94!@baseboard_fab2_lib.baseboard_fab2(sch_1):page84_i138@mstr_sconn.sconn288_h44441003(chips)!SCONN288_H44441003_PIP-SCONN,HA!!!F198!VSS(67)!!!!
S!GND!J9M1!57!@baseboard_fab2_lib.baseboard_fab2(sch_1):page84_i138@mstr_sconn.sconn288_h44441003(chips)!SCONN288_H44441003_PIP-SCONN,HA!!!F198!VSS(68)!!!!
S!GND!J9M1!55!@baseboard_fab2_lib.baseboard_fab2(sch_1):page84_i138@mstr_sconn.sconn288_h44441003(chips)!SCONN288_H44441003_PIP-SCONN,HA!!!F198!VSS(69)!!!!
S!GND!J9M1!270!@baseboard_fab2_lib.baseboard_fab2(sch_1):page84_i138@mstr_sconn.sconn288_h44441003(chips)!SCONN288_H44441003_PIP-SCONN,HA!!!F198!VSS(6)!!!!
S!GND!J9M1!53!@baseboard_fab2_lib.baseboard_fab2(sch_1):page84_i138@mstr_sconn.sconn288_h44441003(chips)!SCONN288_H44441003_PIP-SCONN,HA!!!F198!VSS(70)!!!!
S!GND!J9M1!50!@baseboard_fab2_lib.baseboard_fab2(sch_1):page84_i138@mstr_sconn.sconn288_h44441003(chips)!SCONN288_H44441003_PIP-SCONN,HA!!!F198!VSS(71)!!!!
S!GND!J9M1!48!@baseboard_fab2_lib.baseboard_fab2(sch_1):page84_i138@mstr_sconn.sconn288_h44441003(chips)!SCONN288_H44441003_PIP-SCONN,HA!!!F198!VSS(72)!!!!
S!GND!J9M1!46!@baseboard_fab2_lib.baseboard_fab2(sch_1):page84_i138@mstr_sconn.sconn288_h44441003(chips)!SCONN288_H44441003_PIP-SCONN,HA!!!F198!VSS(73)!!!!
S!GND!J9M1!44!@baseboard_fab2_lib.baseboard_fab2(sch_1):page84_i138@mstr_sconn.sconn288_h44441003(chips)!SCONN288_H44441003_PIP-SCONN,HA!!!F198!VSS(74)!!!!
S!GND!J9M1!42!@baseboard_fab2_lib.baseboard_fab2(sch_1):page84_i138@mstr_sconn.sconn288_h44441003(chips)!SCONN288_H44441003_PIP-SCONN,HA!!!F198!VSS(75)!!!!
S!GND!J9M1!39!@baseboard_fab2_lib.baseboard_fab2(sch_1):page84_i138@mstr_sconn.sconn288_h44441003(chips)!SCONN288_H44441003_PIP-SCONN,HA!!!F198!VSS(76)!!!!
S!GND!J9M1!37!@baseboard_fab2_lib.baseboard_fab2(sch_1):page84_i138@mstr_sconn.sconn288_h44441003(chips)!SCONN288_H44441003_PIP-SCONN,HA!!!F198!VSS(77)!!!!
S!GND!J9M1!35!@baseboard_fab2_lib.baseboard_fab2(sch_1):page84_i138@mstr_sconn.sconn288_h44441003(chips)!SCONN288_H44441003_PIP-SCONN,HA!!!F198!VSS(78)!!!!
S!GND!J9M1!33!@baseboard_fab2_lib.baseboard_fab2(sch_1):page84_i138@mstr_sconn.sconn288_h44441003(chips)!SCONN288_H44441003_PIP-SCONN,HA!!!F198!VSS(79)!!!!
S!GND!J9M1!268!@baseboard_fab2_lib.baseboard_fab2(sch_1):page84_i138@mstr_sconn.sconn288_h44441003(chips)!SCONN288_H44441003_PIP-SCONN,HA!!!F198!VSS(7)!!!!
S!GND!J9M1!31!@baseboard_fab2_lib.baseboard_fab2(sch_1):page84_i138@mstr_sconn.sconn288_h44441003(chips)!SCONN288_H44441003_PIP-SCONN,HA!!!F198!VSS(80)!!!!
S!GND!J9M1!28!@baseboard_fab2_lib.baseboard_fab2(sch_1):page84_i138@mstr_sconn.sconn288_h44441003(chips)!SCONN288_H44441003_PIP-SCONN,HA!!!F198!VSS(81)!!!!
S!GND!J9M1!26!@baseboard_fab2_lib.baseboard_fab2(sch_1):page84_i138@mstr_sconn.sconn288_h44441003(chips)!SCONN288_H44441003_PIP-SCONN,HA!!!F198!VSS(82)!!!!
S!GND!J9M1!24!@baseboard_fab2_lib.baseboard_fab2(sch_1):page84_i138@mstr_sconn.sconn288_h44441003(chips)!SCONN288_H44441003_PIP-SCONN,HA!!!F198!VSS(83)!!!!
S!GND!J9M1!22!@baseboard_fab2_lib.baseboard_fab2(sch_1):page84_i138@mstr_sconn.sconn288_h44441003(chips)!SCONN288_H44441003_PIP-SCONN,HA!!!F198!VSS(84)!!!!
S!GND!J9M1!20!@baseboard_fab2_lib.baseboard_fab2(sch_1):page84_i138@mstr_sconn.sconn288_h44441003(chips)!SCONN288_H44441003_PIP-SCONN,HA!!!F198!VSS(85)!!!!
S!GND!J9M1!17!@baseboard_fab2_lib.baseboard_fab2(sch_1):page84_i138@mstr_sconn.sconn288_h44441003(chips)!SCONN288_H44441003_PIP-SCONN,HA!!!F198!VSS(86)!!!!
S!GND!J9M1!15!@baseboard_fab2_lib.baseboard_fab2(sch_1):page84_i138@mstr_sconn.sconn288_h44441003(chips)!SCONN288_H44441003_PIP-SCONN,HA!!!F198!VSS(87)!!!!
S!GND!J9M1!13!@baseboard_fab2_lib.baseboard_fab2(sch_1):page84_i138@mstr_sconn.sconn288_h44441003(chips)!SCONN288_H44441003_PIP-SCONN,HA!!!F198!VSS(88)!!!!
S!GND!J9M1!11!@baseboard_fab2_lib.baseboard_fab2(sch_1):page84_i138@mstr_sconn.sconn288_h44441003(chips)!SCONN288_H44441003_PIP-SCONN,HA!!!F198!VSS(89)!!!!
S!GND!J9M1!265!@baseboard_fab2_lib.baseboard_fab2(sch_1):page84_i138@mstr_sconn.sconn288_h44441003(chips)!SCONN288_H44441003_PIP-SCONN,HA!!!F198!VSS(8)!!!!
S!GND!J9M1!9!@baseboard_fab2_lib.baseboard_fab2(sch_1):page84_i138@mstr_sconn.sconn288_h44441003(chips)!SCONN288_H44441003_PIP-SCONN,HA!!!F198!VSS(90)!!!!
S!GND!J9M1!6!@baseboard_fab2_lib.baseboard_fab2(sch_1):page84_i138@mstr_sconn.sconn288_h44441003(chips)!SCONN288_H44441003_PIP-SCONN,HA!!!F198!VSS(91)!!!!
S!GND!J9M1!4!@baseboard_fab2_lib.baseboard_fab2(sch_1):page84_i138@mstr_sconn.sconn288_h44441003(chips)!SCONN288_H44441003_PIP-SCONN,HA!!!F198!VSS(92)!!!!
S!GND!J9M1!2!@baseboard_fab2_lib.baseboard_fab2(sch_1):page84_i138@mstr_sconn.sconn288_h44441003(chips)!SCONN288_H44441003_PIP-SCONN,HA!!!F198!VSS(93)!!!!
S!GND!J9M1!263!@baseboard_fab2_lib.baseboard_fab2(sch_1):page84_i138@mstr_sconn.sconn288_h44441003(chips)!SCONN288_H44441003_PIP-SCONN,HA!!!F198!VSS(9)!!!!
S!P12V_NVDIMM_KLM!J9M1!145!@baseboard_fab2_lib.baseboard_fab2(sch_1):page84_i57@mstr_sconn.sconn288_h44441003(chips)!SCONN288_H44441003_PIP-SCONN,HA!!!F197!\12v\(0)!!!!
S!P12V_NVDIMM_KLM!J9M1!1!@baseboard_fab2_lib.baseboard_fab2(sch_1):page84_i57@mstr_sconn.sconn288_h44441003(chips)!SCONN288_H44441003_PIP-SCONN,HA!!!F197!\12v\(1)!!!!
S!PVDDQ_KLM!J9M1!236!@baseboard_fab2_lib.baseboard_fab2(sch_1):page84_i57@mstr_sconn.sconn288_h44441003(chips)!SCONN288_H44441003_PIP-SCONN,HA!!!F197!VDD(0)!!!!
S!PVDDQ_KLM!J9M1!209!@baseboard_fab2_lib.baseboard_fab2(sch_1):page84_i57@mstr_sconn.sconn288_h44441003(chips)!SCONN288_H44441003_PIP-SCONN,HA!!!F197!VDD(10)!!!!
S!PVDDQ_KLM!J9M1!206!@baseboard_fab2_lib.baseboard_fab2(sch_1):page84_i57@mstr_sconn.sconn288_h44441003(chips)!SCONN288_H44441003_PIP-SCONN,HA!!!F197!VDD(11)!!!!
S!PVDDQ_KLM!J9M1!204!@baseboard_fab2_lib.baseboard_fab2(sch_1):page84_i57@mstr_sconn.sconn288_h44441003(chips)!SCONN288_H44441003_PIP-SCONN,HA!!!F197!VDD(12)!!!!
S!PVDDQ_KLM!J9M1!92!@baseboard_fab2_lib.baseboard_fab2(sch_1):page84_i57@mstr_sconn.sconn288_h44441003(chips)!SCONN288_H44441003_PIP-SCONN,HA!!!F197!VDD(13)!!!!
S!PVDDQ_KLM!J9M1!90!@baseboard_fab2_lib.baseboard_fab2(sch_1):page84_i57@mstr_sconn.sconn288_h44441003(chips)!SCONN288_H44441003_PIP-SCONN,HA!!!F197!VDD(14)!!!!
S!PVDDQ_KLM!J9M1!88!@baseboard_fab2_lib.baseboard_fab2(sch_1):page84_i57@mstr_sconn.sconn288_h44441003(chips)!SCONN288_H44441003_PIP-SCONN,HA!!!F197!VDD(15)!!!!
S!PVDDQ_KLM!J9M1!85!@baseboard_fab2_lib.baseboard_fab2(sch_1):page84_i57@mstr_sconn.sconn288_h44441003(chips)!SCONN288_H44441003_PIP-SCONN,HA!!!F197!VDD(16)!!!!
S!PVDDQ_KLM!J9M1!83!@baseboard_fab2_lib.baseboard_fab2(sch_1):page84_i57@mstr_sconn.sconn288_h44441003(chips)!SCONN288_H44441003_PIP-SCONN,HA!!!F197!VDD(17)!!!!
S!PVDDQ_KLM!J9M1!80!@baseboard_fab2_lib.baseboard_fab2(sch_1):page84_i57@mstr_sconn.sconn288_h44441003(chips)!SCONN288_H44441003_PIP-SCONN,HA!!!F197!VDD(18)!!!!
S!PVDDQ_KLM!J9M1!76!@baseboard_fab2_lib.baseboard_fab2(sch_1):page84_i57@mstr_sconn.sconn288_h44441003(chips)!SCONN288_H44441003_PIP-SCONN,HA!!!F197!VDD(19)!!!!
S!PVDDQ_KLM!J9M1!233!@baseboard_fab2_lib.baseboard_fab2(sch_1):page84_i57@mstr_sconn.sconn288_h44441003(chips)!SCONN288_H44441003_PIP-SCONN,HA!!!F197!VDD(1)!!!!
S!PVDDQ_KLM!J9M1!73!@baseboard_fab2_lib.baseboard_fab2(sch_1):page84_i57@mstr_sconn.sconn288_h44441003(chips)!SCONN288_H44441003_PIP-SCONN,HA!!!F197!VDD(20)!!!!
S!PVDDQ_KLM!J9M1!70!@baseboard_fab2_lib.baseboard_fab2(sch_1):page84_i57@mstr_sconn.sconn288_h44441003(chips)!SCONN288_H44441003_PIP-SCONN,HA!!!F197!VDD(21)!!!!
S!PVDDQ_KLM!J9M1!67!@baseboard_fab2_lib.baseboard_fab2(sch_1):page84_i57@mstr_sconn.sconn288_h44441003(chips)!SCONN288_H44441003_PIP-SCONN,HA!!!F197!VDD(22)!!!!
S!PVDDQ_KLM!J9M1!64!@baseboard_fab2_lib.baseboard_fab2(sch_1):page84_i57@mstr_sconn.sconn288_h44441003(chips)!SCONN288_H44441003_PIP-SCONN,HA!!!F197!VDD(23)!!!!
S!PVDDQ_KLM!J9M1!61!@baseboard_fab2_lib.baseboard_fab2(sch_1):page84_i57@mstr_sconn.sconn288_h44441003(chips)!SCONN288_H44441003_PIP-SCONN,HA!!!F197!VDD(24)!!!!
S!PVDDQ_KLM!J9M1!59!@baseboard_fab2_lib.baseboard_fab2(sch_1):page84_i57@mstr_sconn.sconn288_h44441003(chips)!SCONN288_H44441003_PIP-SCONN,HA!!!F197!VDD(25)!!!!
S!PVDDQ_KLM!J9M1!231!@baseboard_fab2_lib.baseboard_fab2(sch_1):page84_i57@mstr_sconn.sconn288_h44441003(chips)!SCONN288_H44441003_PIP-SCONN,HA!!!F197!VDD(2)!!!!
S!PVDDQ_KLM!J9M1!229!@baseboard_fab2_lib.baseboard_fab2(sch_1):page84_i57@mstr_sconn.sconn288_h44441003(chips)!SCONN288_H44441003_PIP-SCONN,HA!!!F197!VDD(3)!!!!
S!PVDDQ_KLM!J9M1!226!@baseboard_fab2_lib.baseboard_fab2(sch_1):page84_i57@mstr_sconn.sconn288_h44441003(chips)!SCONN288_H44441003_PIP-SCONN,HA!!!F197!VDD(4)!!!!
S!PVDDQ_KLM!J9M1!223!@baseboard_fab2_lib.baseboard_fab2(sch_1):page84_i57@mstr_sconn.sconn288_h44441003(chips)!SCONN288_H44441003_PIP-SCONN,HA!!!F197!VDD(5)!!!!
S!PVDDQ_KLM!J9M1!220!@baseboard_fab2_lib.baseboard_fab2(sch_1):page84_i57@mstr_sconn.sconn288_h44441003(chips)!SCONN288_H44441003_PIP-SCONN,HA!!!F197!VDD(6)!!!!
S!PVDDQ_KLM!J9M1!217!@baseboard_fab2_lib.baseboard_fab2(sch_1):page84_i57@mstr_sconn.sconn288_h44441003(chips)!SCONN288_H44441003_PIP-SCONN,HA!!!F197!VDD(7)!!!!
S!PVDDQ_KLM!J9M1!215!@baseboard_fab2_lib.baseboard_fab2(sch_1):page84_i57@mstr_sconn.sconn288_h44441003(chips)!SCONN288_H44441003_PIP-SCONN,HA!!!F197!VDD(8)!!!!
S!PVDDQ_KLM!J9M1!212!@baseboard_fab2_lib.baseboard_fab2(sch_1):page84_i57@mstr_sconn.sconn288_h44441003(chips)!SCONN288_H44441003_PIP-SCONN,HA!!!F197!VDD(9)!!!!
S!PVPP_KLM!J9M1!287!@baseboard_fab2_lib.baseboard_fab2(sch_1):page84_i57@mstr_sconn.sconn288_h44441003(chips)!SCONN288_H44441003_PIP-SCONN,HA!!!F197!VPP(0)!!!!
S!PVPP_KLM!J9M1!286!@baseboard_fab2_lib.baseboard_fab2(sch_1):page84_i57@mstr_sconn.sconn288_h44441003(chips)!SCONN288_H44441003_PIP-SCONN,HA!!!F197!VPP(1)!!!!
S!PVPP_KLM!J9M1!288!@baseboard_fab2_lib.baseboard_fab2(sch_1):page84_i57@mstr_sconn.sconn288_h44441003(chips)!SCONN288_H44441003_PIP-SCONN,HA!!!F197!VPP(2)!!!!
S!PVPP_KLM!J9M1!143!@baseboard_fab2_lib.baseboard_fab2(sch_1):page84_i57@mstr_sconn.sconn288_h44441003(chips)!SCONN288_H44441003_PIP-SCONN,HA!!!F197!VPP(3)!!!!
S!PVPP_KLM!J9M1!142!@baseboard_fab2_lib.baseboard_fab2(sch_1):page84_i57@mstr_sconn.sconn288_h44441003(chips)!SCONN288_H44441003_PIP-SCONN,HA!!!F197!VPP(4)!!!!
S!PVTT_KLM!J9M1!221!@baseboard_fab2_lib.baseboard_fab2(sch_1):page84_i57@mstr_sconn.sconn288_h44441003(chips)!SCONN288_H44441003_PIP-SCONN,HA!!!F197!VTT(0)!!!!
S!PVTT_KLM!J9M1!77!@baseboard_fab2_lib.baseboard_fab2(sch_1):page84_i57@mstr_sconn.sconn288_h44441003(chips)!SCONN288_H44441003_PIP-SCONN,HA!!!F197!VTT(1)!!!!
S!M_L_MA<0>!J9L2!79!@baseboard_fab2_lib.baseboard_fab2(sch_1):page86_i12@mstr_sconn.sconn288_h44441003(chips)!SCONN288_H44441003_PIP-SCONN,HA!!!F204!A0!!!!
S!M_L_MA<1>!J9L2!72!@baseboard_fab2_lib.baseboard_fab2(sch_1):page86_i12@mstr_sconn.sconn288_h44441003(chips)!SCONN288_H44441003_PIP-SCONN,HA!!!F204!A1!!!!
S!M_L_MA<10>!J9L2!225!@baseboard_fab2_lib.baseboard_fab2(sch_1):page86_i12@mstr_sconn.sconn288_h44441003(chips)!SCONN288_H44441003_PIP-SCONN,HA!!!F204!A10!!!!
S!M_L_MA<11>!J9L2!210!@baseboard_fab2_lib.baseboard_fab2(sch_1):page86_i12@mstr_sconn.sconn288_h44441003(chips)!SCONN288_H44441003_PIP-SCONN,HA!!!F204!A11!!!!
S!M_L_MA<12>!J9L2!65!@baseboard_fab2_lib.baseboard_fab2(sch_1):page86_i12@mstr_sconn.sconn288_h44441003(chips)!SCONN288_H44441003_PIP-SCONN,HA!!!F204!A12!!!!
S!M_L_MA<13>!J9L2!232!@baseboard_fab2_lib.baseboard_fab2(sch_1):page86_i12@mstr_sconn.sconn288_h44441003(chips)!SCONN288_H44441003_PIP-SCONN,HA!!!F204!A13!!!!
S!M_L_MA<14>!J9L2!228!@baseboard_fab2_lib.baseboard_fab2(sch_1):page86_i12@mstr_sconn.sconn288_h44441003(chips)!SCONN288_H44441003_PIP-SCONN,HA!!!F204!A14_WE_N!!!!
S!M_L_MA<15>!J9L2!86!@baseboard_fab2_lib.baseboard_fab2(sch_1):page86_i12@mstr_sconn.sconn288_h44441003(chips)!SCONN288_H44441003_PIP-SCONN,HA!!!F204!A15_CAS_N!!!!
S!M_L_MA<16>!J9L2!82!@baseboard_fab2_lib.baseboard_fab2(sch_1):page86_i12@mstr_sconn.sconn288_h44441003(chips)!SCONN288_H44441003_PIP-SCONN,HA!!!F204!A16_RAS_N!!!!
S!M_L_MA<17>!J9L2!234!@baseboard_fab2_lib.baseboard_fab2(sch_1):page86_i12@mstr_sconn.sconn288_h44441003(chips)!SCONN288_H44441003_PIP-SCONN,HA!!!F204!A17!!!!
S!M_L_MA<2>!J9L2!216!@baseboard_fab2_lib.baseboard_fab2(sch_1):page86_i12@mstr_sconn.sconn288_h44441003(chips)!SCONN288_H44441003_PIP-SCONN,HA!!!F204!A2!!!!
S!M_L_MA<3>!J9L2!71!@baseboard_fab2_lib.baseboard_fab2(sch_1):page86_i12@mstr_sconn.sconn288_h44441003(chips)!SCONN288_H44441003_PIP-SCONN,HA!!!F204!A3!!!!
S!M_L_MA<4>!J9L2!214!@baseboard_fab2_lib.baseboard_fab2(sch_1):page86_i12@mstr_sconn.sconn288_h44441003(chips)!SCONN288_H44441003_PIP-SCONN,HA!!!F204!A4!!!!
S!M_L_MA<5>!J9L2!213!@baseboard_fab2_lib.baseboard_fab2(sch_1):page86_i12@mstr_sconn.sconn288_h44441003(chips)!SCONN288_H44441003_PIP-SCONN,HA!!!F204!A5!!!!
S!M_L_MA<6>!J9L2!69!@baseboard_fab2_lib.baseboard_fab2(sch_1):page86_i12@mstr_sconn.sconn288_h44441003(chips)!SCONN288_H44441003_PIP-SCONN,HA!!!F204!A6!!!!
S!M_L_MA<7>!J9L2!211!@baseboard_fab2_lib.baseboard_fab2(sch_1):page86_i12@mstr_sconn.sconn288_h44441003(chips)!SCONN288_H44441003_PIP-SCONN,HA!!!F204!A7!!!!
S!M_L_MA<8>!J9L2!68!@baseboard_fab2_lib.baseboard_fab2(sch_1):page86_i12@mstr_sconn.sconn288_h44441003(chips)!SCONN288_H44441003_PIP-SCONN,HA!!!F204!A8!!!!
S!M_L_MA<9>!J9L2!66!@baseboard_fab2_lib.baseboard_fab2(sch_1):page86_i12@mstr_sconn.sconn288_h44441003(chips)!SCONN288_H44441003_PIP-SCONN,HA!!!F204!A9!!!!
S!M_L_ACT_N!J9L2!62!@baseboard_fab2_lib.baseboard_fab2(sch_1):page86_i12@mstr_sconn.sconn288_h44441003(chips)!SCONN288_H44441003_PIP-SCONN,HA!!!F204!ACT_N!!!!
S!M_L_ALERT_N!J9L2!208!@baseboard_fab2_lib.baseboard_fab2(sch_1):page86_i12@mstr_sconn.sconn288_h44441003(chips)!SCONN288_H44441003_PIP-SCONN,HA!!!F204!ALERT_N!!!!
S!M_L_BA<0>!J9L2!81!@baseboard_fab2_lib.baseboard_fab2(sch_1):page86_i12@mstr_sconn.sconn288_h44441003(chips)!SCONN288_H44441003_PIP-SCONN,HA!!!F204!BA(0)!!!!
S!M_L_BA<1>!J9L2!224!@baseboard_fab2_lib.baseboard_fab2(sch_1):page86_i12@mstr_sconn.sconn288_h44441003(chips)!SCONN288_H44441003_PIP-SCONN,HA!!!F204!BA(1)!!!!
S!M_L_BG<0>!J9L2!63!@baseboard_fab2_lib.baseboard_fab2(sch_1):page86_i12@mstr_sconn.sconn288_h44441003(chips)!SCONN288_H44441003_PIP-SCONN,HA!!!F204!BG(0)!!!!
S!M_L_BG<1>!J9L2!207!@baseboard_fab2_lib.baseboard_fab2(sch_1):page86_i12@mstr_sconn.sconn288_h44441003(chips)!SCONN288_H44441003_PIP-SCONN,HA!!!F204!BG(1)!!!!
S!M_L_C<2>!J9L2!235!@baseboard_fab2_lib.baseboard_fab2(sch_1):page86_i12@mstr_sconn.sconn288_h44441003(chips)!SCONN288_H44441003_PIP-SCONN,HA!!!F204!C(2)!!!!
S!M_L_ECC<0>!J9L2!49!@baseboard_fab2_lib.baseboard_fab2(sch_1):page86_i12@mstr_sconn.sconn288_h44441003(chips)!SCONN288_H44441003_PIP-SCONN,HA!!!F204!CB(0)!!!!
S!M_L_ECC<1>!J9L2!194!@baseboard_fab2_lib.baseboard_fab2(sch_1):page86_i12@mstr_sconn.sconn288_h44441003(chips)!SCONN288_H44441003_PIP-SCONN,HA!!!F204!CB(1)!!!!
S!M_L_ECC<2>!J9L2!56!@baseboard_fab2_lib.baseboard_fab2(sch_1):page86_i12@mstr_sconn.sconn288_h44441003(chips)!SCONN288_H44441003_PIP-SCONN,HA!!!F204!CB(2)!!!!
S!M_L_ECC<3>!J9L2!201!@baseboard_fab2_lib.baseboard_fab2(sch_1):page86_i12@mstr_sconn.sconn288_h44441003(chips)!SCONN288_H44441003_PIP-SCONN,HA!!!F204!CB(3)!!!!
S!M_L_ECC<4>!J9L2!47!@baseboard_fab2_lib.baseboard_fab2(sch_1):page86_i12@mstr_sconn.sconn288_h44441003(chips)!SCONN288_H44441003_PIP-SCONN,HA!!!F204!CB(4)!!!!
S!M_L_ECC<5>!J9L2!192!@baseboard_fab2_lib.baseboard_fab2(sch_1):page86_i12@mstr_sconn.sconn288_h44441003(chips)!SCONN288_H44441003_PIP-SCONN,HA!!!F204!CB(5)!!!!
S!M_L_ECC<6>!J9L2!54!@baseboard_fab2_lib.baseboard_fab2(sch_1):page86_i12@mstr_sconn.sconn288_h44441003(chips)!SCONN288_H44441003_PIP-SCONN,HA!!!F204!CB(6)!!!!
S!M_L_ECC<7>!J9L2!199!@baseboard_fab2_lib.baseboard_fab2(sch_1):page86_i12@mstr_sconn.sconn288_h44441003(chips)!SCONN288_H44441003_PIP-SCONN,HA!!!F204!CB(7)!!!!
S!M_L_CLK_DN<2>!J9L2!75!@baseboard_fab2_lib.baseboard_fab2(sch_1):page86_i12@mstr_sconn.sconn288_h44441003(chips)!SCONN288_H44441003_PIP-SCONN,HA!!!F204!CK0N!!!!
S!M_L_CLK_DP<2>!J9L2!74!@baseboard_fab2_lib.baseboard_fab2(sch_1):page86_i12@mstr_sconn.sconn288_h44441003(chips)!SCONN288_H44441003_PIP-SCONN,HA!!!F204!CK0P!!!!
S!M_L_CLK_DN<3>!J9L2!219!@baseboard_fab2_lib.baseboard_fab2(sch_1):page86_i12@mstr_sconn.sconn288_h44441003(chips)!SCONN288_H44441003_PIP-SCONN,HA!!!F204!CK1N!!!!
S!M_L_CLK_DP<3>!J9L2!218!@baseboard_fab2_lib.baseboard_fab2(sch_1):page86_i12@mstr_sconn.sconn288_h44441003(chips)!SCONN288_H44441003_PIP-SCONN,HA!!!F204!CK1P!!!!
S!M_L_CKE<2>!J9L2!60!@baseboard_fab2_lib.baseboard_fab2(sch_1):page86_i12@mstr_sconn.sconn288_h44441003(chips)!SCONN288_H44441003_PIP-SCONN,HA!!!F204!CKE(0)!!!!
S!M_L_CKE<3>!J9L2!203!@baseboard_fab2_lib.baseboard_fab2(sch_1):page86_i12@mstr_sconn.sconn288_h44441003(chips)!SCONN288_H44441003_PIP-SCONN,HA!!!F204!CKE(1)!!!!
S!M_L_DQ<0>!J9L2!5!@baseboard_fab2_lib.baseboard_fab2(sch_1):page86_i12@mstr_sconn.sconn288_h44441003(chips)!SCONN288_H44441003_PIP-SCONN,HA!!!F204!DQ(0)!!!!
S!M_L_DQ<10>!J9L2!23!@baseboard_fab2_lib.baseboard_fab2(sch_1):page86_i12@mstr_sconn.sconn288_h44441003(chips)!SCONN288_H44441003_PIP-SCONN,HA!!!F204!DQ(10)!!!!
S!M_L_DQ<11>!J9L2!168!@baseboard_fab2_lib.baseboard_fab2(sch_1):page86_i12@mstr_sconn.sconn288_h44441003(chips)!SCONN288_H44441003_PIP-SCONN,HA!!!F204!DQ(11)!!!!
S!M_L_DQ<12>!J9L2!14!@baseboard_fab2_lib.baseboard_fab2(sch_1):page86_i12@mstr_sconn.sconn288_h44441003(chips)!SCONN288_H44441003_PIP-SCONN,HA!!!F204!DQ(12)!!!!
S!M_L_DQ<13>!J9L2!159!@baseboard_fab2_lib.baseboard_fab2(sch_1):page86_i12@mstr_sconn.sconn288_h44441003(chips)!SCONN288_H44441003_PIP-SCONN,HA!!!F204!DQ(13)!!!!
S!M_L_DQ<14>!J9L2!21!@baseboard_fab2_lib.baseboard_fab2(sch_1):page86_i12@mstr_sconn.sconn288_h44441003(chips)!SCONN288_H44441003_PIP-SCONN,HA!!!F204!DQ(14)!!!!
S!M_L_DQ<15>!J9L2!166!@baseboard_fab2_lib.baseboard_fab2(sch_1):page86_i12@mstr_sconn.sconn288_h44441003(chips)!SCONN288_H44441003_PIP-SCONN,HA!!!F204!DQ(15)!!!!
S!M_L_DQ<16>!J9L2!27!@baseboard_fab2_lib.baseboard_fab2(sch_1):page86_i12@mstr_sconn.sconn288_h44441003(chips)!SCONN288_H44441003_PIP-SCONN,HA!!!F204!DQ(16)!!!!
S!M_L_DQ<17>!J9L2!172!@baseboard_fab2_lib.baseboard_fab2(sch_1):page86_i12@mstr_sconn.sconn288_h44441003(chips)!SCONN288_H44441003_PIP-SCONN,HA!!!F204!DQ(17)!!!!
S!M_L_DQ<18>!J9L2!34!@baseboard_fab2_lib.baseboard_fab2(sch_1):page86_i12@mstr_sconn.sconn288_h44441003(chips)!SCONN288_H44441003_PIP-SCONN,HA!!!F204!DQ(18)!!!!
S!M_L_DQ<19>!J9L2!179!@baseboard_fab2_lib.baseboard_fab2(sch_1):page86_i12@mstr_sconn.sconn288_h44441003(chips)!SCONN288_H44441003_PIP-SCONN,HA!!!F204!DQ(19)!!!!
S!M_L_DQ<1>!J9L2!150!@baseboard_fab2_lib.baseboard_fab2(sch_1):page86_i12@mstr_sconn.sconn288_h44441003(chips)!SCONN288_H44441003_PIP-SCONN,HA!!!F204!DQ(1)!!!!
S!M_L_DQ<20>!J9L2!25!@baseboard_fab2_lib.baseboard_fab2(sch_1):page86_i12@mstr_sconn.sconn288_h44441003(chips)!SCONN288_H44441003_PIP-SCONN,HA!!!F204!DQ(20)!!!!
S!M_L_DQ<21>!J9L2!170!@baseboard_fab2_lib.baseboard_fab2(sch_1):page86_i12@mstr_sconn.sconn288_h44441003(chips)!SCONN288_H44441003_PIP-SCONN,HA!!!F204!DQ(21)!!!!
S!M_L_DQ<22>!J9L2!32!@baseboard_fab2_lib.baseboard_fab2(sch_1):page86_i12@mstr_sconn.sconn288_h44441003(chips)!SCONN288_H44441003_PIP-SCONN,HA!!!F204!DQ(22)!!!!
S!M_L_DQ<23>!J9L2!177!@baseboard_fab2_lib.baseboard_fab2(sch_1):page86_i12@mstr_sconn.sconn288_h44441003(chips)!SCONN288_H44441003_PIP-SCONN,HA!!!F204!DQ(23)!!!!
S!M_L_DQ<24>!J9L2!38!@baseboard_fab2_lib.baseboard_fab2(sch_1):page86_i12@mstr_sconn.sconn288_h44441003(chips)!SCONN288_H44441003_PIP-SCONN,HA!!!F204!DQ(24)!!!!
S!M_L_DQ<25>!J9L2!183!@baseboard_fab2_lib.baseboard_fab2(sch_1):page86_i12@mstr_sconn.sconn288_h44441003(chips)!SCONN288_H44441003_PIP-SCONN,HA!!!F204!DQ(25)!!!!
S!M_L_DQ<26>!J9L2!45!@baseboard_fab2_lib.baseboard_fab2(sch_1):page86_i12@mstr_sconn.sconn288_h44441003(chips)!SCONN288_H44441003_PIP-SCONN,HA!!!F204!DQ(26)!!!!
S!M_L_DQ<27>!J9L2!190!@baseboard_fab2_lib.baseboard_fab2(sch_1):page86_i12@mstr_sconn.sconn288_h44441003(chips)!SCONN288_H44441003_PIP-SCONN,HA!!!F204!DQ(27)!!!!
S!M_L_DQ<28>!J9L2!36!@baseboard_fab2_lib.baseboard_fab2(sch_1):page86_i12@mstr_sconn.sconn288_h44441003(chips)!SCONN288_H44441003_PIP-SCONN,HA!!!F204!DQ(28)!!!!
S!M_L_DQ<29>!J9L2!181!@baseboard_fab2_lib.baseboard_fab2(sch_1):page86_i12@mstr_sconn.sconn288_h44441003(chips)!SCONN288_H44441003_PIP-SCONN,HA!!!F204!DQ(29)!!!!
S!M_L_DQ<2>!J9L2!12!@baseboard_fab2_lib.baseboard_fab2(sch_1):page86_i12@mstr_sconn.sconn288_h44441003(chips)!SCONN288_H44441003_PIP-SCONN,HA!!!F204!DQ(2)!!!!
S!M_L_DQ<30>!J9L2!43!@baseboard_fab2_lib.baseboard_fab2(sch_1):page86_i12@mstr_sconn.sconn288_h44441003(chips)!SCONN288_H44441003_PIP-SCONN,HA!!!F204!DQ(30)!!!!
S!M_L_DQ<31>!J9L2!188!@baseboard_fab2_lib.baseboard_fab2(sch_1):page86_i12@mstr_sconn.sconn288_h44441003(chips)!SCONN288_H44441003_PIP-SCONN,HA!!!F204!DQ(31)!!!!
S!M_L_DQ<32>!J9L2!97!@baseboard_fab2_lib.baseboard_fab2(sch_1):page86_i12@mstr_sconn.sconn288_h44441003(chips)!SCONN288_H44441003_PIP-SCONN,HA!!!F204!DQ(32)!!!!
S!M_L_DQ<33>!J9L2!242!@baseboard_fab2_lib.baseboard_fab2(sch_1):page86_i12@mstr_sconn.sconn288_h44441003(chips)!SCONN288_H44441003_PIP-SCONN,HA!!!F204!DQ(33)!!!!
S!M_L_DQ<34>!J9L2!104!@baseboard_fab2_lib.baseboard_fab2(sch_1):page86_i12@mstr_sconn.sconn288_h44441003(chips)!SCONN288_H44441003_PIP-SCONN,HA!!!F204!DQ(34)!!!!
S!M_L_DQ<35>!J9L2!249!@baseboard_fab2_lib.baseboard_fab2(sch_1):page86_i12@mstr_sconn.sconn288_h44441003(chips)!SCONN288_H44441003_PIP-SCONN,HA!!!F204!DQ(35)!!!!
S!M_L_DQ<36>!J9L2!95!@baseboard_fab2_lib.baseboard_fab2(sch_1):page86_i12@mstr_sconn.sconn288_h44441003(chips)!SCONN288_H44441003_PIP-SCONN,HA!!!F204!DQ(36)!!!!
S!M_L_DQ<37>!J9L2!240!@baseboard_fab2_lib.baseboard_fab2(sch_1):page86_i12@mstr_sconn.sconn288_h44441003(chips)!SCONN288_H44441003_PIP-SCONN,HA!!!F204!DQ(37)!!!!
S!M_L_DQ<38>!J9L2!102!@baseboard_fab2_lib.baseboard_fab2(sch_1):page86_i12@mstr_sconn.sconn288_h44441003(chips)!SCONN288_H44441003_PIP-SCONN,HA!!!F204!DQ(38)!!!!
S!M_L_DQ<39>!J9L2!247!@baseboard_fab2_lib.baseboard_fab2(sch_1):page86_i12@mstr_sconn.sconn288_h44441003(chips)!SCONN288_H44441003_PIP-SCONN,HA!!!F204!DQ(39)!!!!
S!M_L_DQ<3>!J9L2!157!@baseboard_fab2_lib.baseboard_fab2(sch_1):page86_i12@mstr_sconn.sconn288_h44441003(chips)!SCONN288_H44441003_PIP-SCONN,HA!!!F204!DQ(3)!!!!
S!M_L_DQ<40>!J9L2!108!@baseboard_fab2_lib.baseboard_fab2(sch_1):page86_i12@mstr_sconn.sconn288_h44441003(chips)!SCONN288_H44441003_PIP-SCONN,HA!!!F204!DQ(40)!!!!
S!M_L_DQ<41>!J9L2!253!@baseboard_fab2_lib.baseboard_fab2(sch_1):page86_i12@mstr_sconn.sconn288_h44441003(chips)!SCONN288_H44441003_PIP-SCONN,HA!!!F204!DQ(41)!!!!
S!M_L_DQ<42>!J9L2!115!@baseboard_fab2_lib.baseboard_fab2(sch_1):page86_i12@mstr_sconn.sconn288_h44441003(chips)!SCONN288_H44441003_PIP-SCONN,HA!!!F204!DQ(42)!!!!
S!M_L_DQ<43>!J9L2!260!@baseboard_fab2_lib.baseboard_fab2(sch_1):page86_i12@mstr_sconn.sconn288_h44441003(chips)!SCONN288_H44441003_PIP-SCONN,HA!!!F204!DQ(43)!!!!
S!M_L_DQ<44>!J9L2!106!@baseboard_fab2_lib.baseboard_fab2(sch_1):page86_i12@mstr_sconn.sconn288_h44441003(chips)!SCONN288_H44441003_PIP-SCONN,HA!!!F204!DQ(44)!!!!
S!M_L_DQ<45>!J9L2!251!@baseboard_fab2_lib.baseboard_fab2(sch_1):page86_i12@mstr_sconn.sconn288_h44441003(chips)!SCONN288_H44441003_PIP-SCONN,HA!!!F204!DQ(45)!!!!
S!M_L_DQ<46>!J9L2!113!@baseboard_fab2_lib.baseboard_fab2(sch_1):page86_i12@mstr_sconn.sconn288_h44441003(chips)!SCONN288_H44441003_PIP-SCONN,HA!!!F204!DQ(46)!!!!
S!M_L_DQ<47>!J9L2!258!@baseboard_fab2_lib.baseboard_fab2(sch_1):page86_i12@mstr_sconn.sconn288_h44441003(chips)!SCONN288_H44441003_PIP-SCONN,HA!!!F204!DQ(47)!!!!
S!M_L_DQ<48>!J9L2!119!@baseboard_fab2_lib.baseboard_fab2(sch_1):page86_i12@mstr_sconn.sconn288_h44441003(chips)!SCONN288_H44441003_PIP-SCONN,HA!!!F204!DQ(48)!!!!
S!M_L_DQ<49>!J9L2!264!@baseboard_fab2_lib.baseboard_fab2(sch_1):page86_i12@mstr_sconn.sconn288_h44441003(chips)!SCONN288_H44441003_PIP-SCONN,HA!!!F204!DQ(49)!!!!
S!M_L_DQ<4>!J9L2!3!@baseboard_fab2_lib.baseboard_fab2(sch_1):page86_i12@mstr_sconn.sconn288_h44441003(chips)!SCONN288_H44441003_PIP-SCONN,HA!!!F204!DQ(4)!!!!
S!M_L_DQ<50>!J9L2!126!@baseboard_fab2_lib.baseboard_fab2(sch_1):page86_i12@mstr_sconn.sconn288_h44441003(chips)!SCONN288_H44441003_PIP-SCONN,HA!!!F204!DQ(50)!!!!
S!M_L_DQ<51>!J9L2!271!@baseboard_fab2_lib.baseboard_fab2(sch_1):page86_i12@mstr_sconn.sconn288_h44441003(chips)!SCONN288_H44441003_PIP-SCONN,HA!!!F204!DQ(51)!!!!
S!M_L_DQ<52>!J9L2!117!@baseboard_fab2_lib.baseboard_fab2(sch_1):page86_i12@mstr_sconn.sconn288_h44441003(chips)!SCONN288_H44441003_PIP-SCONN,HA!!!F204!DQ(52)!!!!
S!M_L_DQ<53>!J9L2!262!@baseboard_fab2_lib.baseboard_fab2(sch_1):page86_i12@mstr_sconn.sconn288_h44441003(chips)!SCONN288_H44441003_PIP-SCONN,HA!!!F204!DQ(53)!!!!
S!M_L_DQ<54>!J9L2!124!@baseboard_fab2_lib.baseboard_fab2(sch_1):page86_i12@mstr_sconn.sconn288_h44441003(chips)!SCONN288_H44441003_PIP-SCONN,HA!!!F204!DQ(54)!!!!
S!M_L_DQ<55>!J9L2!269!@baseboard_fab2_lib.baseboard_fab2(sch_1):page86_i12@mstr_sconn.sconn288_h44441003(chips)!SCONN288_H44441003_PIP-SCONN,HA!!!F204!DQ(55)!!!!
S!M_L_DQ<56>!J9L2!130!@baseboard_fab2_lib.baseboard_fab2(sch_1):page86_i12@mstr_sconn.sconn288_h44441003(chips)!SCONN288_H44441003_PIP-SCONN,HA!!!F204!DQ(56)!!!!
S!M_L_DQ<57>!J9L2!275!@baseboard_fab2_lib.baseboard_fab2(sch_1):page86_i12@mstr_sconn.sconn288_h44441003(chips)!SCONN288_H44441003_PIP-SCONN,HA!!!F204!DQ(57)!!!!
S!M_L_DQ<58>!J9L2!137!@baseboard_fab2_lib.baseboard_fab2(sch_1):page86_i12@mstr_sconn.sconn288_h44441003(chips)!SCONN288_H44441003_PIP-SCONN,HA!!!F204!DQ(58)!!!!
S!M_L_DQ<59>!J9L2!282!@baseboard_fab2_lib.baseboard_fab2(sch_1):page86_i12@mstr_sconn.sconn288_h44441003(chips)!SCONN288_H44441003_PIP-SCONN,HA!!!F204!DQ(59)!!!!
S!M_L_DQ<5>!J9L2!148!@baseboard_fab2_lib.baseboard_fab2(sch_1):page86_i12@mstr_sconn.sconn288_h44441003(chips)!SCONN288_H44441003_PIP-SCONN,HA!!!F204!DQ(5)!!!!
S!M_L_DQ<60>!J9L2!128!@baseboard_fab2_lib.baseboard_fab2(sch_1):page86_i12@mstr_sconn.sconn288_h44441003(chips)!SCONN288_H44441003_PIP-SCONN,HA!!!F204!DQ(60)!!!!
S!M_L_DQ<61>!J9L2!273!@baseboard_fab2_lib.baseboard_fab2(sch_1):page86_i12@mstr_sconn.sconn288_h44441003(chips)!SCONN288_H44441003_PIP-SCONN,HA!!!F204!DQ(61)!!!!
S!M_L_DQ<62>!J9L2!135!@baseboard_fab2_lib.baseboard_fab2(sch_1):page86_i12@mstr_sconn.sconn288_h44441003(chips)!SCONN288_H44441003_PIP-SCONN,HA!!!F204!DQ(62)!!!!
S!M_L_DQ<63>!J9L2!280!@baseboard_fab2_lib.baseboard_fab2(sch_1):page86_i12@mstr_sconn.sconn288_h44441003(chips)!SCONN288_H44441003_PIP-SCONN,HA!!!F204!DQ(63)!!!!
S!M_L_DQ<6>!J9L2!10!@baseboard_fab2_lib.baseboard_fab2(sch_1):page86_i12@mstr_sconn.sconn288_h44441003(chips)!SCONN288_H44441003_PIP-SCONN,HA!!!F204!DQ(6)!!!!
S!M_L_DQ<7>!J9L2!155!@baseboard_fab2_lib.baseboard_fab2(sch_1):page86_i12@mstr_sconn.sconn288_h44441003(chips)!SCONN288_H44441003_PIP-SCONN,HA!!!F204!DQ(7)!!!!
S!M_L_DQ<8>!J9L2!16!@baseboard_fab2_lib.baseboard_fab2(sch_1):page86_i12@mstr_sconn.sconn288_h44441003(chips)!SCONN288_H44441003_PIP-SCONN,HA!!!F204!DQ(8)!!!!
S!M_L_DQ<9>!J9L2!161!@baseboard_fab2_lib.baseboard_fab2(sch_1):page86_i12@mstr_sconn.sconn288_h44441003(chips)!SCONN288_H44441003_PIP-SCONN,HA!!!F204!DQ(9)!!!!
S!FM_DIMM_EVENT_COD_N!J9L2!78!@baseboard_fab2_lib.baseboard_fab2(sch_1):page86_i12@mstr_sconn.sconn288_h44441003(chips)!SCONN288_H44441003_PIP-SCONN,HA!!!F204!EVENT_N!!!!
S!M_L_ODT<2>!J9L2!87!@baseboard_fab2_lib.baseboard_fab2(sch_1):page86_i12@mstr_sconn.sconn288_h44441003(chips)!SCONN288_H44441003_PIP-SCONN,HA!!!F204!ODT(0)!!!!
S!M_L_ODT<3>!J9L2!91!@baseboard_fab2_lib.baseboard_fab2(sch_1):page86_i12@mstr_sconn.sconn288_h44441003(chips)!SCONN288_H44441003_PIP-SCONN,HA!!!F204!ODT(1)!!!!
S!M_L_PAR!J9L2!222!@baseboard_fab2_lib.baseboard_fab2(sch_1):page86_i12@mstr_sconn.sconn288_h44441003(chips)!SCONN288_H44441003_PIP-SCONN,HA!!!F204!PAR!!!!
S!M_KLM_RST_N!J9L2!58!@baseboard_fab2_lib.baseboard_fab2(sch_1):page86_i12@mstr_sconn.sconn288_h44441003(chips)!SCONN288_H44441003_PIP-SCONN,HA!!!F204!RESET_N!!!!
S!TP_CH_L_DIMM0_RFU_0!J9L2!205!@baseboard_fab2_lib.baseboard_fab2(sch_1):page86_i12@mstr_sconn.sconn288_h44441003(chips)!SCONN288_H44441003_PIP-SCONN,HA!!!F204!RFU(0)!!!!
S!TP_CH_L_DIMM0_RFU_1!J9L2!227!@baseboard_fab2_lib.baseboard_fab2(sch_1):page86_i12@mstr_sconn.sconn288_h44441003(chips)!SCONN288_H44441003_PIP-SCONN,HA!!!F204!RFU(1)!!!!
S!TP_CH_L_DIMM0_RFU_2!J9L2!144!@baseboard_fab2_lib.baseboard_fab2(sch_1):page86_i12@mstr_sconn.sconn288_h44441003(chips)!SCONN288_H44441003_PIP-SCONN,HA!!!F204!RFU(2)!!!!
S!M_L_CS_N<4>!J9L2!84!@baseboard_fab2_lib.baseboard_fab2(sch_1):page86_i12@mstr_sconn.sconn288_h44441003(chips)!SCONN288_H44441003_PIP-SCONN,HA!!!F204!S0_N!!!!
S!M_L_CS_N<5>!J9L2!89!@baseboard_fab2_lib.baseboard_fab2(sch_1):page86_i12@mstr_sconn.sconn288_h44441003(chips)!SCONN288_H44441003_PIP-SCONN,HA!!!F204!S1_N!!!!
S!M_L_CS_N<6>!J9L2!93!@baseboard_fab2_lib.baseboard_fab2(sch_1):page86_i12@mstr_sconn.sconn288_h44441003(chips)!SCONN288_H44441003_PIP-SCONN,HA!!!F204!S2_N_C(0)!!!!
S!M_L_CS_N<7>!J9L2!237!@baseboard_fab2_lib.baseboard_fab2(sch_1):page86_i12@mstr_sconn.sconn288_h44441003(chips)!SCONN288_H44441003_PIP-SCONN,HA!!!F204!S3_N_C(1)!!!!
S!PVPP_KLM!J9L2!139!@baseboard_fab2_lib.baseboard_fab2(sch_1):page86_i12@mstr_sconn.sconn288_h44441003(chips)!SCONN288_H44441003_PIP-SCONN,HA!!!F204!SA(0)!!!!
S!PVPP_KLM!J9L2!140!@baseboard_fab2_lib.baseboard_fab2(sch_1):page86_i12@mstr_sconn.sconn288_h44441003(chips)!SCONN288_H44441003_PIP-SCONN,HA!!!F204!SA(1)!!!!
S!GND!J9L2!238!@baseboard_fab2_lib.baseboard_fab2(sch_1):page86_i12@mstr_sconn.sconn288_h44441003(chips)!SCONN288_H44441003_PIP-SCONN,HA!!!F204!SA(2)!!!!
S!FM_ADR_COMPLETE_KLM_N!J9L2!230!@baseboard_fab2_lib.baseboard_fab2(sch_1):page86_i12@mstr_sconn.sconn288_h44441003(chips)!SCONN288_H44441003_PIP-SCONN,HA!!!F204!SAVE_N_NC!!!!
S!SMB_DDR_KLM_VPP_SCL!J9L2!141!@baseboard_fab2_lib.baseboard_fab2(sch_1):page86_i12@mstr_sconn.sconn288_h44441003(chips)!SCONN288_H44441003_PIP-SCONN,HA!!!F204!SCL!!!!
S!SMB_DDR_KLM_VPP_SDA!J9L2!285!@baseboard_fab2_lib.baseboard_fab2(sch_1):page86_i12@mstr_sconn.sconn288_h44441003(chips)!SCONN288_H44441003_PIP-SCONN,HA!!!F204!SDA!!!!
S!PVPP_KLM!J9L2!284!@baseboard_fab2_lib.baseboard_fab2(sch_1):page86_i12@mstr_sconn.sconn288_h44441003(chips)!SCONN288_H44441003_PIP-SCONN,HA!!!F204!VDDSPD!!!!
S!M_L_VREF!J9L2!146!@baseboard_fab2_lib.baseboard_fab2(sch_1):page86_i12@mstr_sconn.sconn288_h44441003(chips)!SCONN288_H44441003_PIP-SCONN,HA!!!F204!VREFCA!!!!
S!M_L_DQS_DN<0>!J9L2!152!@baseboard_fab2_lib.baseboard_fab2(sch_1):page86_i100@mstr_sconn.sconn288_h44441003(chips)!SCONN288_H44441003_PIP-SCONN,HA!!!F203!DQS0N!!!!
S!M_L_DQS_DP<0>!J9L2!153!@baseboard_fab2_lib.baseboard_fab2(sch_1):page86_i100@mstr_sconn.sconn288_h44441003(chips)!SCONN288_H44441003_PIP-SCONN,HA!!!F203!DQS0P!!!!
S!M_L_DQS_DN<10>!J9L2!19!@baseboard_fab2_lib.baseboard_fab2(sch_1):page86_i100@mstr_sconn.sconn288_h44441003(chips)!SCONN288_H44441003_PIP-SCONN,HA!!!F203!DQS10N!!!!
S!M_L_DQS_DP<10>!J9L2!18!@baseboard_fab2_lib.baseboard_fab2(sch_1):page86_i100@mstr_sconn.sconn288_h44441003(chips)!SCONN288_H44441003_PIP-SCONN,HA!!!F203!DQS10P!!!!
S!M_L_DQS_DN<11>!J9L2!30!@baseboard_fab2_lib.baseboard_fab2(sch_1):page86_i100@mstr_sconn.sconn288_h44441003(chips)!SCONN288_H44441003_PIP-SCONN,HA!!!F203!DQS11N!!!!
S!M_L_DQS_DP<11>!J9L2!29!@baseboard_fab2_lib.baseboard_fab2(sch_1):page86_i100@mstr_sconn.sconn288_h44441003(chips)!SCONN288_H44441003_PIP-SCONN,HA!!!F203!DQS11P!!!!
S!M_L_DQS_DN<12>!J9L2!41!@baseboard_fab2_lib.baseboard_fab2(sch_1):page86_i100@mstr_sconn.sconn288_h44441003(chips)!SCONN288_H44441003_PIP-SCONN,HA!!!F203!DQS12N!!!!
S!M_L_DQS_DP<12>!J9L2!40!@baseboard_fab2_lib.baseboard_fab2(sch_1):page86_i100@mstr_sconn.sconn288_h44441003(chips)!SCONN288_H44441003_PIP-SCONN,HA!!!F203!DQS12P!!!!
S!M_L_DQS_DN<13>!J9L2!100!@baseboard_fab2_lib.baseboard_fab2(sch_1):page86_i100@mstr_sconn.sconn288_h44441003(chips)!SCONN288_H44441003_PIP-SCONN,HA!!!F203!DQS13N!!!!
S!M_L_DQS_DP<13>!J9L2!99!@baseboard_fab2_lib.baseboard_fab2(sch_1):page86_i100@mstr_sconn.sconn288_h44441003(chips)!SCONN288_H44441003_PIP-SCONN,HA!!!F203!DQS13P!!!!
S!M_L_DQS_DN<14>!J9L2!111!@baseboard_fab2_lib.baseboard_fab2(sch_1):page86_i100@mstr_sconn.sconn288_h44441003(chips)!SCONN288_H44441003_PIP-SCONN,HA!!!F203!DQS14N!!!!
S!M_L_DQS_DP<14>!J9L2!110!@baseboard_fab2_lib.baseboard_fab2(sch_1):page86_i100@mstr_sconn.sconn288_h44441003(chips)!SCONN288_H44441003_PIP-SCONN,HA!!!F203!DQS14P!!!!
S!M_L_DQS_DN<15>!J9L2!122!@baseboard_fab2_lib.baseboard_fab2(sch_1):page86_i100@mstr_sconn.sconn288_h44441003(chips)!SCONN288_H44441003_PIP-SCONN,HA!!!F203!DQS15N!!!!
S!M_L_DQS_DP<15>!J9L2!121!@baseboard_fab2_lib.baseboard_fab2(sch_1):page86_i100@mstr_sconn.sconn288_h44441003(chips)!SCONN288_H44441003_PIP-SCONN,HA!!!F203!DQS15P!!!!
S!M_L_DQS_DN<16>!J9L2!133!@baseboard_fab2_lib.baseboard_fab2(sch_1):page86_i100@mstr_sconn.sconn288_h44441003(chips)!SCONN288_H44441003_PIP-SCONN,HA!!!F203!DQS16N!!!!
S!M_L_DQS_DP<16>!J9L2!132!@baseboard_fab2_lib.baseboard_fab2(sch_1):page86_i100@mstr_sconn.sconn288_h44441003(chips)!SCONN288_H44441003_PIP-SCONN,HA!!!F203!DQS16P!!!!
S!M_L_DQS_DN<17>!J9L2!52!@baseboard_fab2_lib.baseboard_fab2(sch_1):page86_i100@mstr_sconn.sconn288_h44441003(chips)!SCONN288_H44441003_PIP-SCONN,HA!!!F203!DQS17N!!!!
S!M_L_DQS_DP<17>!J9L2!51!@baseboard_fab2_lib.baseboard_fab2(sch_1):page86_i100@mstr_sconn.sconn288_h44441003(chips)!SCONN288_H44441003_PIP-SCONN,HA!!!F203!DQS17P!!!!
S!M_L_DQS_DN<1>!J9L2!163!@baseboard_fab2_lib.baseboard_fab2(sch_1):page86_i100@mstr_sconn.sconn288_h44441003(chips)!SCONN288_H44441003_PIP-SCONN,HA!!!F203!DQS1N!!!!
S!M_L_DQS_DP<1>!J9L2!164!@baseboard_fab2_lib.baseboard_fab2(sch_1):page86_i100@mstr_sconn.sconn288_h44441003(chips)!SCONN288_H44441003_PIP-SCONN,HA!!!F203!DQS1P!!!!
S!M_L_DQS_DN<2>!J9L2!174!@baseboard_fab2_lib.baseboard_fab2(sch_1):page86_i100@mstr_sconn.sconn288_h44441003(chips)!SCONN288_H44441003_PIP-SCONN,HA!!!F203!DQS2N!!!!
S!M_L_DQS_DP<2>!J9L2!175!@baseboard_fab2_lib.baseboard_fab2(sch_1):page86_i100@mstr_sconn.sconn288_h44441003(chips)!SCONN288_H44441003_PIP-SCONN,HA!!!F203!DQS2P!!!!
S!M_L_DQS_DN<3>!J9L2!185!@baseboard_fab2_lib.baseboard_fab2(sch_1):page86_i100@mstr_sconn.sconn288_h44441003(chips)!SCONN288_H44441003_PIP-SCONN,HA!!!F203!DQS3N!!!!
S!M_L_DQS_DP<3>!J9L2!186!@baseboard_fab2_lib.baseboard_fab2(sch_1):page86_i100@mstr_sconn.sconn288_h44441003(chips)!SCONN288_H44441003_PIP-SCONN,HA!!!F203!DQS3P!!!!
S!M_L_DQS_DN<4>!J9L2!244!@baseboard_fab2_lib.baseboard_fab2(sch_1):page86_i100@mstr_sconn.sconn288_h44441003(chips)!SCONN288_H44441003_PIP-SCONN,HA!!!F203!DQS4N!!!!
S!M_L_DQS_DP<4>!J9L2!245!@baseboard_fab2_lib.baseboard_fab2(sch_1):page86_i100@mstr_sconn.sconn288_h44441003(chips)!SCONN288_H44441003_PIP-SCONN,HA!!!F203!DQS4P!!!!
S!M_L_DQS_DN<5>!J9L2!255!@baseboard_fab2_lib.baseboard_fab2(sch_1):page86_i100@mstr_sconn.sconn288_h44441003(chips)!SCONN288_H44441003_PIP-SCONN,HA!!!F203!DQS5N!!!!
S!M_L_DQS_DP<5>!J9L2!256!@baseboard_fab2_lib.baseboard_fab2(sch_1):page86_i100@mstr_sconn.sconn288_h44441003(chips)!SCONN288_H44441003_PIP-SCONN,HA!!!F203!DQS5P!!!!
S!M_L_DQS_DN<6>!J9L2!266!@baseboard_fab2_lib.baseboard_fab2(sch_1):page86_i100@mstr_sconn.sconn288_h44441003(chips)!SCONN288_H44441003_PIP-SCONN,HA!!!F203!DQS6N!!!!
S!M_L_DQS_DP<6>!J9L2!267!@baseboard_fab2_lib.baseboard_fab2(sch_1):page86_i100@mstr_sconn.sconn288_h44441003(chips)!SCONN288_H44441003_PIP-SCONN,HA!!!F203!DQS6P!!!!
S!M_L_DQS_DN<7>!J9L2!277!@baseboard_fab2_lib.baseboard_fab2(sch_1):page86_i100@mstr_sconn.sconn288_h44441003(chips)!SCONN288_H44441003_PIP-SCONN,HA!!!F203!DQS7N!!!!
S!M_L_DQS_DP<7>!J9L2!278!@baseboard_fab2_lib.baseboard_fab2(sch_1):page86_i100@mstr_sconn.sconn288_h44441003(chips)!SCONN288_H44441003_PIP-SCONN,HA!!!F203!DQS7P!!!!
S!M_L_DQS_DN<8>!J9L2!196!@baseboard_fab2_lib.baseboard_fab2(sch_1):page86_i100@mstr_sconn.sconn288_h44441003(chips)!SCONN288_H44441003_PIP-SCONN,HA!!!F203!DQS8N!!!!
S!M_L_DQS_DP<8>!J9L2!197!@baseboard_fab2_lib.baseboard_fab2(sch_1):page86_i100@mstr_sconn.sconn288_h44441003(chips)!SCONN288_H44441003_PIP-SCONN,HA!!!F203!DQS8P!!!!
S!M_L_DQS_DN<9>!J9L2!8!@baseboard_fab2_lib.baseboard_fab2(sch_1):page86_i100@mstr_sconn.sconn288_h44441003(chips)!SCONN288_H44441003_PIP-SCONN,HA!!!F203!DQS9N!!!!
S!M_L_DQS_DP<9>!J9L2!7!@baseboard_fab2_lib.baseboard_fab2(sch_1):page86_i100@mstr_sconn.sconn288_h44441003(chips)!SCONN288_H44441003_PIP-SCONN,HA!!!F203!DQS9P!!!!
S!GND!J9L2!283!@baseboard_fab2_lib.baseboard_fab2(sch_1):page86_i138@mstr_sconn.sconn288_h44441003(chips)!SCONN288_H44441003_PIP-SCONN,HA!!!F202!VSS(0)!!!!
S!GND!J9L2!261!@baseboard_fab2_lib.baseboard_fab2(sch_1):page86_i138@mstr_sconn.sconn288_h44441003(chips)!SCONN288_H44441003_PIP-SCONN,HA!!!F202!VSS(10)!!!!
S!GND!J9L2!259!@baseboard_fab2_lib.baseboard_fab2(sch_1):page86_i138@mstr_sconn.sconn288_h44441003(chips)!SCONN288_H44441003_PIP-SCONN,HA!!!F202!VSS(11)!!!!
S!GND!J9L2!257!@baseboard_fab2_lib.baseboard_fab2(sch_1):page86_i138@mstr_sconn.sconn288_h44441003(chips)!SCONN288_H44441003_PIP-SCONN,HA!!!F202!VSS(12)!!!!
S!GND!J9L2!254!@baseboard_fab2_lib.baseboard_fab2(sch_1):page86_i138@mstr_sconn.sconn288_h44441003(chips)!SCONN288_H44441003_PIP-SCONN,HA!!!F202!VSS(13)!!!!
S!GND!J9L2!252!@baseboard_fab2_lib.baseboard_fab2(sch_1):page86_i138@mstr_sconn.sconn288_h44441003(chips)!SCONN288_H44441003_PIP-SCONN,HA!!!F202!VSS(14)!!!!
S!GND!J9L2!250!@baseboard_fab2_lib.baseboard_fab2(sch_1):page86_i138@mstr_sconn.sconn288_h44441003(chips)!SCONN288_H44441003_PIP-SCONN,HA!!!F202!VSS(15)!!!!
S!GND!J9L2!248!@baseboard_fab2_lib.baseboard_fab2(sch_1):page86_i138@mstr_sconn.sconn288_h44441003(chips)!SCONN288_H44441003_PIP-SCONN,HA!!!F202!VSS(16)!!!!
S!GND!J9L2!246!@baseboard_fab2_lib.baseboard_fab2(sch_1):page86_i138@mstr_sconn.sconn288_h44441003(chips)!SCONN288_H44441003_PIP-SCONN,HA!!!F202!VSS(17)!!!!
S!GND!J9L2!243!@baseboard_fab2_lib.baseboard_fab2(sch_1):page86_i138@mstr_sconn.sconn288_h44441003(chips)!SCONN288_H44441003_PIP-SCONN,HA!!!F202!VSS(18)!!!!
S!GND!J9L2!241!@baseboard_fab2_lib.baseboard_fab2(sch_1):page86_i138@mstr_sconn.sconn288_h44441003(chips)!SCONN288_H44441003_PIP-SCONN,HA!!!F202!VSS(19)!!!!
S!GND!J9L2!281!@baseboard_fab2_lib.baseboard_fab2(sch_1):page86_i138@mstr_sconn.sconn288_h44441003(chips)!SCONN288_H44441003_PIP-SCONN,HA!!!F202!VSS(1)!!!!
S!GND!J9L2!239!@baseboard_fab2_lib.baseboard_fab2(sch_1):page86_i138@mstr_sconn.sconn288_h44441003(chips)!SCONN288_H44441003_PIP-SCONN,HA!!!F202!VSS(20)!!!!
S!GND!J9L2!202!@baseboard_fab2_lib.baseboard_fab2(sch_1):page86_i138@mstr_sconn.sconn288_h44441003(chips)!SCONN288_H44441003_PIP-SCONN,HA!!!F202!VSS(21)!!!!
S!GND!J9L2!200!@baseboard_fab2_lib.baseboard_fab2(sch_1):page86_i138@mstr_sconn.sconn288_h44441003(chips)!SCONN288_H44441003_PIP-SCONN,HA!!!F202!VSS(22)!!!!
S!GND!J9L2!198!@baseboard_fab2_lib.baseboard_fab2(sch_1):page86_i138@mstr_sconn.sconn288_h44441003(chips)!SCONN288_H44441003_PIP-SCONN,HA!!!F202!VSS(23)!!!!
S!GND!J9L2!195!@baseboard_fab2_lib.baseboard_fab2(sch_1):page86_i138@mstr_sconn.sconn288_h44441003(chips)!SCONN288_H44441003_PIP-SCONN,HA!!!F202!VSS(24)!!!!
S!GND!J9L2!193!@baseboard_fab2_lib.baseboard_fab2(sch_1):page86_i138@mstr_sconn.sconn288_h44441003(chips)!SCONN288_H44441003_PIP-SCONN,HA!!!F202!VSS(25)!!!!
S!GND!J9L2!191!@baseboard_fab2_lib.baseboard_fab2(sch_1):page86_i138@mstr_sconn.sconn288_h44441003(chips)!SCONN288_H44441003_PIP-SCONN,HA!!!F202!VSS(26)!!!!
S!GND!J9L2!189!@baseboard_fab2_lib.baseboard_fab2(sch_1):page86_i138@mstr_sconn.sconn288_h44441003(chips)!SCONN288_H44441003_PIP-SCONN,HA!!!F202!VSS(27)!!!!
S!GND!J9L2!187!@baseboard_fab2_lib.baseboard_fab2(sch_1):page86_i138@mstr_sconn.sconn288_h44441003(chips)!SCONN288_H44441003_PIP-SCONN,HA!!!F202!VSS(28)!!!!
S!GND!J9L2!184!@baseboard_fab2_lib.baseboard_fab2(sch_1):page86_i138@mstr_sconn.sconn288_h44441003(chips)!SCONN288_H44441003_PIP-SCONN,HA!!!F202!VSS(29)!!!!
S!GND!J9L2!279!@baseboard_fab2_lib.baseboard_fab2(sch_1):page86_i138@mstr_sconn.sconn288_h44441003(chips)!SCONN288_H44441003_PIP-SCONN,HA!!!F202!VSS(2)!!!!
S!GND!J9L2!182!@baseboard_fab2_lib.baseboard_fab2(sch_1):page86_i138@mstr_sconn.sconn288_h44441003(chips)!SCONN288_H44441003_PIP-SCONN,HA!!!F202!VSS(30)!!!!
S!GND!J9L2!180!@baseboard_fab2_lib.baseboard_fab2(sch_1):page86_i138@mstr_sconn.sconn288_h44441003(chips)!SCONN288_H44441003_PIP-SCONN,HA!!!F202!VSS(31)!!!!
S!GND!J9L2!178!@baseboard_fab2_lib.baseboard_fab2(sch_1):page86_i138@mstr_sconn.sconn288_h44441003(chips)!SCONN288_H44441003_PIP-SCONN,HA!!!F202!VSS(32)!!!!
S!GND!J9L2!176!@baseboard_fab2_lib.baseboard_fab2(sch_1):page86_i138@mstr_sconn.sconn288_h44441003(chips)!SCONN288_H44441003_PIP-SCONN,HA!!!F202!VSS(33)!!!!
S!GND!J9L2!173!@baseboard_fab2_lib.baseboard_fab2(sch_1):page86_i138@mstr_sconn.sconn288_h44441003(chips)!SCONN288_H44441003_PIP-SCONN,HA!!!F202!VSS(34)!!!!
S!GND!J9L2!171!@baseboard_fab2_lib.baseboard_fab2(sch_1):page86_i138@mstr_sconn.sconn288_h44441003(chips)!SCONN288_H44441003_PIP-SCONN,HA!!!F202!VSS(35)!!!!
S!GND!J9L2!169!@baseboard_fab2_lib.baseboard_fab2(sch_1):page86_i138@mstr_sconn.sconn288_h44441003(chips)!SCONN288_H44441003_PIP-SCONN,HA!!!F202!VSS(36)!!!!
S!GND!J9L2!167!@baseboard_fab2_lib.baseboard_fab2(sch_1):page86_i138@mstr_sconn.sconn288_h44441003(chips)!SCONN288_H44441003_PIP-SCONN,HA!!!F202!VSS(37)!!!!
S!GND!J9L2!165!@baseboard_fab2_lib.baseboard_fab2(sch_1):page86_i138@mstr_sconn.sconn288_h44441003(chips)!SCONN288_H44441003_PIP-SCONN,HA!!!F202!VSS(38)!!!!
S!GND!J9L2!162!@baseboard_fab2_lib.baseboard_fab2(sch_1):page86_i138@mstr_sconn.sconn288_h44441003(chips)!SCONN288_H44441003_PIP-SCONN,HA!!!F202!VSS(39)!!!!
S!GND!J9L2!276!@baseboard_fab2_lib.baseboard_fab2(sch_1):page86_i138@mstr_sconn.sconn288_h44441003(chips)!SCONN288_H44441003_PIP-SCONN,HA!!!F202!VSS(3)!!!!
S!GND!J9L2!160!@baseboard_fab2_lib.baseboard_fab2(sch_1):page86_i138@mstr_sconn.sconn288_h44441003(chips)!SCONN288_H44441003_PIP-SCONN,HA!!!F202!VSS(40)!!!!
S!GND!J9L2!158!@baseboard_fab2_lib.baseboard_fab2(sch_1):page86_i138@mstr_sconn.sconn288_h44441003(chips)!SCONN288_H44441003_PIP-SCONN,HA!!!F202!VSS(41)!!!!
S!GND!J9L2!156!@baseboard_fab2_lib.baseboard_fab2(sch_1):page86_i138@mstr_sconn.sconn288_h44441003(chips)!SCONN288_H44441003_PIP-SCONN,HA!!!F202!VSS(42)!!!!
S!GND!J9L2!154!@baseboard_fab2_lib.baseboard_fab2(sch_1):page86_i138@mstr_sconn.sconn288_h44441003(chips)!SCONN288_H44441003_PIP-SCONN,HA!!!F202!VSS(43)!!!!
S!GND!J9L2!151!@baseboard_fab2_lib.baseboard_fab2(sch_1):page86_i138@mstr_sconn.sconn288_h44441003(chips)!SCONN288_H44441003_PIP-SCONN,HA!!!F202!VSS(44)!!!!
S!GND!J9L2!149!@baseboard_fab2_lib.baseboard_fab2(sch_1):page86_i138@mstr_sconn.sconn288_h44441003(chips)!SCONN288_H44441003_PIP-SCONN,HA!!!F202!VSS(45)!!!!
S!GND!J9L2!147!@baseboard_fab2_lib.baseboard_fab2(sch_1):page86_i138@mstr_sconn.sconn288_h44441003(chips)!SCONN288_H44441003_PIP-SCONN,HA!!!F202!VSS(46)!!!!
S!GND!J9L2!138!@baseboard_fab2_lib.baseboard_fab2(sch_1):page86_i138@mstr_sconn.sconn288_h44441003(chips)!SCONN288_H44441003_PIP-SCONN,HA!!!F202!VSS(47)!!!!
S!GND!J9L2!136!@baseboard_fab2_lib.baseboard_fab2(sch_1):page86_i138@mstr_sconn.sconn288_h44441003(chips)!SCONN288_H44441003_PIP-SCONN,HA!!!F202!VSS(48)!!!!
S!GND!J9L2!134!@baseboard_fab2_lib.baseboard_fab2(sch_1):page86_i138@mstr_sconn.sconn288_h44441003(chips)!SCONN288_H44441003_PIP-SCONN,HA!!!F202!VSS(49)!!!!
S!GND!J9L2!274!@baseboard_fab2_lib.baseboard_fab2(sch_1):page86_i138@mstr_sconn.sconn288_h44441003(chips)!SCONN288_H44441003_PIP-SCONN,HA!!!F202!VSS(4)!!!!
S!GND!J9L2!131!@baseboard_fab2_lib.baseboard_fab2(sch_1):page86_i138@mstr_sconn.sconn288_h44441003(chips)!SCONN288_H44441003_PIP-SCONN,HA!!!F202!VSS(50)!!!!
S!GND!J9L2!129!@baseboard_fab2_lib.baseboard_fab2(sch_1):page86_i138@mstr_sconn.sconn288_h44441003(chips)!SCONN288_H44441003_PIP-SCONN,HA!!!F202!VSS(51)!!!!
S!GND!J9L2!127!@baseboard_fab2_lib.baseboard_fab2(sch_1):page86_i138@mstr_sconn.sconn288_h44441003(chips)!SCONN288_H44441003_PIP-SCONN,HA!!!F202!VSS(52)!!!!
S!GND!J9L2!125!@baseboard_fab2_lib.baseboard_fab2(sch_1):page86_i138@mstr_sconn.sconn288_h44441003(chips)!SCONN288_H44441003_PIP-SCONN,HA!!!F202!VSS(53)!!!!
S!GND!J9L2!123!@baseboard_fab2_lib.baseboard_fab2(sch_1):page86_i138@mstr_sconn.sconn288_h44441003(chips)!SCONN288_H44441003_PIP-SCONN,HA!!!F202!VSS(54)!!!!
S!GND!J9L2!120!@baseboard_fab2_lib.baseboard_fab2(sch_1):page86_i138@mstr_sconn.sconn288_h44441003(chips)!SCONN288_H44441003_PIP-SCONN,HA!!!F202!VSS(55)!!!!
S!GND!J9L2!118!@baseboard_fab2_lib.baseboard_fab2(sch_1):page86_i138@mstr_sconn.sconn288_h44441003(chips)!SCONN288_H44441003_PIP-SCONN,HA!!!F202!VSS(56)!!!!
S!GND!J9L2!116!@baseboard_fab2_lib.baseboard_fab2(sch_1):page86_i138@mstr_sconn.sconn288_h44441003(chips)!SCONN288_H44441003_PIP-SCONN,HA!!!F202!VSS(57)!!!!
S!GND!J9L2!114!@baseboard_fab2_lib.baseboard_fab2(sch_1):page86_i138@mstr_sconn.sconn288_h44441003(chips)!SCONN288_H44441003_PIP-SCONN,HA!!!F202!VSS(58)!!!!
S!GND!J9L2!112!@baseboard_fab2_lib.baseboard_fab2(sch_1):page86_i138@mstr_sconn.sconn288_h44441003(chips)!SCONN288_H44441003_PIP-SCONN,HA!!!F202!VSS(59)!!!!
S!GND!J9L2!272!@baseboard_fab2_lib.baseboard_fab2(sch_1):page86_i138@mstr_sconn.sconn288_h44441003(chips)!SCONN288_H44441003_PIP-SCONN,HA!!!F202!VSS(5)!!!!
S!GND!J9L2!109!@baseboard_fab2_lib.baseboard_fab2(sch_1):page86_i138@mstr_sconn.sconn288_h44441003(chips)!SCONN288_H44441003_PIP-SCONN,HA!!!F202!VSS(60)!!!!
S!GND!J9L2!107!@baseboard_fab2_lib.baseboard_fab2(sch_1):page86_i138@mstr_sconn.sconn288_h44441003(chips)!SCONN288_H44441003_PIP-SCONN,HA!!!F202!VSS(61)!!!!
S!GND!J9L2!105!@baseboard_fab2_lib.baseboard_fab2(sch_1):page86_i138@mstr_sconn.sconn288_h44441003(chips)!SCONN288_H44441003_PIP-SCONN,HA!!!F202!VSS(62)!!!!
S!GND!J9L2!103!@baseboard_fab2_lib.baseboard_fab2(sch_1):page86_i138@mstr_sconn.sconn288_h44441003(chips)!SCONN288_H44441003_PIP-SCONN,HA!!!F202!VSS(63)!!!!
S!GND!J9L2!101!@baseboard_fab2_lib.baseboard_fab2(sch_1):page86_i138@mstr_sconn.sconn288_h44441003(chips)!SCONN288_H44441003_PIP-SCONN,HA!!!F202!VSS(64)!!!!
S!GND!J9L2!98!@baseboard_fab2_lib.baseboard_fab2(sch_1):page86_i138@mstr_sconn.sconn288_h44441003(chips)!SCONN288_H44441003_PIP-SCONN,HA!!!F202!VSS(65)!!!!
S!GND!J9L2!96!@baseboard_fab2_lib.baseboard_fab2(sch_1):page86_i138@mstr_sconn.sconn288_h44441003(chips)!SCONN288_H44441003_PIP-SCONN,HA!!!F202!VSS(66)!!!!
S!GND!J9L2!94!@baseboard_fab2_lib.baseboard_fab2(sch_1):page86_i138@mstr_sconn.sconn288_h44441003(chips)!SCONN288_H44441003_PIP-SCONN,HA!!!F202!VSS(67)!!!!
S!GND!J9L2!57!@baseboard_fab2_lib.baseboard_fab2(sch_1):page86_i138@mstr_sconn.sconn288_h44441003(chips)!SCONN288_H44441003_PIP-SCONN,HA!!!F202!VSS(68)!!!!
S!GND!J9L2!55!@baseboard_fab2_lib.baseboard_fab2(sch_1):page86_i138@mstr_sconn.sconn288_h44441003(chips)!SCONN288_H44441003_PIP-SCONN,HA!!!F202!VSS(69)!!!!
S!GND!J9L2!270!@baseboard_fab2_lib.baseboard_fab2(sch_1):page86_i138@mstr_sconn.sconn288_h44441003(chips)!SCONN288_H44441003_PIP-SCONN,HA!!!F202!VSS(6)!!!!
S!GND!J9L2!53!@baseboard_fab2_lib.baseboard_fab2(sch_1):page86_i138@mstr_sconn.sconn288_h44441003(chips)!SCONN288_H44441003_PIP-SCONN,HA!!!F202!VSS(70)!!!!
S!GND!J9L2!50!@baseboard_fab2_lib.baseboard_fab2(sch_1):page86_i138@mstr_sconn.sconn288_h44441003(chips)!SCONN288_H44441003_PIP-SCONN,HA!!!F202!VSS(71)!!!!
S!GND!J9L2!48!@baseboard_fab2_lib.baseboard_fab2(sch_1):page86_i138@mstr_sconn.sconn288_h44441003(chips)!SCONN288_H44441003_PIP-SCONN,HA!!!F202!VSS(72)!!!!
S!GND!J9L2!46!@baseboard_fab2_lib.baseboard_fab2(sch_1):page86_i138@mstr_sconn.sconn288_h44441003(chips)!SCONN288_H44441003_PIP-SCONN,HA!!!F202!VSS(73)!!!!
S!GND!J9L2!44!@baseboard_fab2_lib.baseboard_fab2(sch_1):page86_i138@mstr_sconn.sconn288_h44441003(chips)!SCONN288_H44441003_PIP-SCONN,HA!!!F202!VSS(74)!!!!
S!GND!J9L2!42!@baseboard_fab2_lib.baseboard_fab2(sch_1):page86_i138@mstr_sconn.sconn288_h44441003(chips)!SCONN288_H44441003_PIP-SCONN,HA!!!F202!VSS(75)!!!!
S!GND!J9L2!39!@baseboard_fab2_lib.baseboard_fab2(sch_1):page86_i138@mstr_sconn.sconn288_h44441003(chips)!SCONN288_H44441003_PIP-SCONN,HA!!!F202!VSS(76)!!!!
S!GND!J9L2!37!@baseboard_fab2_lib.baseboard_fab2(sch_1):page86_i138@mstr_sconn.sconn288_h44441003(chips)!SCONN288_H44441003_PIP-SCONN,HA!!!F202!VSS(77)!!!!
S!GND!J9L2!35!@baseboard_fab2_lib.baseboard_fab2(sch_1):page86_i138@mstr_sconn.sconn288_h44441003(chips)!SCONN288_H44441003_PIP-SCONN,HA!!!F202!VSS(78)!!!!
S!GND!J9L2!33!@baseboard_fab2_lib.baseboard_fab2(sch_1):page86_i138@mstr_sconn.sconn288_h44441003(chips)!SCONN288_H44441003_PIP-SCONN,HA!!!F202!VSS(79)!!!!
S!GND!J9L2!268!@baseboard_fab2_lib.baseboard_fab2(sch_1):page86_i138@mstr_sconn.sconn288_h44441003(chips)!SCONN288_H44441003_PIP-SCONN,HA!!!F202!VSS(7)!!!!
S!GND!J9L2!31!@baseboard_fab2_lib.baseboard_fab2(sch_1):page86_i138@mstr_sconn.sconn288_h44441003(chips)!SCONN288_H44441003_PIP-SCONN,HA!!!F202!VSS(80)!!!!
S!GND!J9L2!28!@baseboard_fab2_lib.baseboard_fab2(sch_1):page86_i138@mstr_sconn.sconn288_h44441003(chips)!SCONN288_H44441003_PIP-SCONN,HA!!!F202!VSS(81)!!!!
S!GND!J9L2!26!@baseboard_fab2_lib.baseboard_fab2(sch_1):page86_i138@mstr_sconn.sconn288_h44441003(chips)!SCONN288_H44441003_PIP-SCONN,HA!!!F202!VSS(82)!!!!
S!GND!J9L2!24!@baseboard_fab2_lib.baseboard_fab2(sch_1):page86_i138@mstr_sconn.sconn288_h44441003(chips)!SCONN288_H44441003_PIP-SCONN,HA!!!F202!VSS(83)!!!!
S!GND!J9L2!22!@baseboard_fab2_lib.baseboard_fab2(sch_1):page86_i138@mstr_sconn.sconn288_h44441003(chips)!SCONN288_H44441003_PIP-SCONN,HA!!!F202!VSS(84)!!!!
S!GND!J9L2!20!@baseboard_fab2_lib.baseboard_fab2(sch_1):page86_i138@mstr_sconn.sconn288_h44441003(chips)!SCONN288_H44441003_PIP-SCONN,HA!!!F202!VSS(85)!!!!
S!GND!J9L2!17!@baseboard_fab2_lib.baseboard_fab2(sch_1):page86_i138@mstr_sconn.sconn288_h44441003(chips)!SCONN288_H44441003_PIP-SCONN,HA!!!F202!VSS(86)!!!!
S!GND!J9L2!15!@baseboard_fab2_lib.baseboard_fab2(sch_1):page86_i138@mstr_sconn.sconn288_h44441003(chips)!SCONN288_H44441003_PIP-SCONN,HA!!!F202!VSS(87)!!!!
S!GND!J9L2!13!@baseboard_fab2_lib.baseboard_fab2(sch_1):page86_i138@mstr_sconn.sconn288_h44441003(chips)!SCONN288_H44441003_PIP-SCONN,HA!!!F202!VSS(88)!!!!
S!GND!J9L2!11!@baseboard_fab2_lib.baseboard_fab2(sch_1):page86_i138@mstr_sconn.sconn288_h44441003(chips)!SCONN288_H44441003_PIP-SCONN,HA!!!F202!VSS(89)!!!!
S!GND!J9L2!265!@baseboard_fab2_lib.baseboard_fab2(sch_1):page86_i138@mstr_sconn.sconn288_h44441003(chips)!SCONN288_H44441003_PIP-SCONN,HA!!!F202!VSS(8)!!!!
S!GND!J9L2!9!@baseboard_fab2_lib.baseboard_fab2(sch_1):page86_i138@mstr_sconn.sconn288_h44441003(chips)!SCONN288_H44441003_PIP-SCONN,HA!!!F202!VSS(90)!!!!
S!GND!J9L2!6!@baseboard_fab2_lib.baseboard_fab2(sch_1):page86_i138@mstr_sconn.sconn288_h44441003(chips)!SCONN288_H44441003_PIP-SCONN,HA!!!F202!VSS(91)!!!!
S!GND!J9L2!4!@baseboard_fab2_lib.baseboard_fab2(sch_1):page86_i138@mstr_sconn.sconn288_h44441003(chips)!SCONN288_H44441003_PIP-SCONN,HA!!!F202!VSS(92)!!!!
S!GND!J9L2!2!@baseboard_fab2_lib.baseboard_fab2(sch_1):page86_i138@mstr_sconn.sconn288_h44441003(chips)!SCONN288_H44441003_PIP-SCONN,HA!!!F202!VSS(93)!!!!
S!GND!J9L2!263!@baseboard_fab2_lib.baseboard_fab2(sch_1):page86_i138@mstr_sconn.sconn288_h44441003(chips)!SCONN288_H44441003_PIP-SCONN,HA!!!F202!VSS(9)!!!!
S!P12V_NVDIMM_KLM!J9L2!145!@baseboard_fab2_lib.baseboard_fab2(sch_1):page86_i55@mstr_sconn.sconn288_h44441003(chips)!SCONN288_H44441003_PIP-SCONN,HA!!!F201!\12v\(0)!!!!
S!P12V_NVDIMM_KLM!J9L2!1!@baseboard_fab2_lib.baseboard_fab2(sch_1):page86_i55@mstr_sconn.sconn288_h44441003(chips)!SCONN288_H44441003_PIP-SCONN,HA!!!F201!\12v\(1)!!!!
S!PVDDQ_KLM!J9L2!236!@baseboard_fab2_lib.baseboard_fab2(sch_1):page86_i55@mstr_sconn.sconn288_h44441003(chips)!SCONN288_H44441003_PIP-SCONN,HA!!!F201!VDD(0)!!!!
S!PVDDQ_KLM!J9L2!209!@baseboard_fab2_lib.baseboard_fab2(sch_1):page86_i55@mstr_sconn.sconn288_h44441003(chips)!SCONN288_H44441003_PIP-SCONN,HA!!!F201!VDD(10)!!!!
S!PVDDQ_KLM!J9L2!206!@baseboard_fab2_lib.baseboard_fab2(sch_1):page86_i55@mstr_sconn.sconn288_h44441003(chips)!SCONN288_H44441003_PIP-SCONN,HA!!!F201!VDD(11)!!!!
S!PVDDQ_KLM!J9L2!204!@baseboard_fab2_lib.baseboard_fab2(sch_1):page86_i55@mstr_sconn.sconn288_h44441003(chips)!SCONN288_H44441003_PIP-SCONN,HA!!!F201!VDD(12)!!!!
S!PVDDQ_KLM!J9L2!92!@baseboard_fab2_lib.baseboard_fab2(sch_1):page86_i55@mstr_sconn.sconn288_h44441003(chips)!SCONN288_H44441003_PIP-SCONN,HA!!!F201!VDD(13)!!!!
S!PVDDQ_KLM!J9L2!90!@baseboard_fab2_lib.baseboard_fab2(sch_1):page86_i55@mstr_sconn.sconn288_h44441003(chips)!SCONN288_H44441003_PIP-SCONN,HA!!!F201!VDD(14)!!!!
S!PVDDQ_KLM!J9L2!88!@baseboard_fab2_lib.baseboard_fab2(sch_1):page86_i55@mstr_sconn.sconn288_h44441003(chips)!SCONN288_H44441003_PIP-SCONN,HA!!!F201!VDD(15)!!!!
S!PVDDQ_KLM!J9L2!85!@baseboard_fab2_lib.baseboard_fab2(sch_1):page86_i55@mstr_sconn.sconn288_h44441003(chips)!SCONN288_H44441003_PIP-SCONN,HA!!!F201!VDD(16)!!!!
S!PVDDQ_KLM!J9L2!83!@baseboard_fab2_lib.baseboard_fab2(sch_1):page86_i55@mstr_sconn.sconn288_h44441003(chips)!SCONN288_H44441003_PIP-SCONN,HA!!!F201!VDD(17)!!!!
S!PVDDQ_KLM!J9L2!80!@baseboard_fab2_lib.baseboard_fab2(sch_1):page86_i55@mstr_sconn.sconn288_h44441003(chips)!SCONN288_H44441003_PIP-SCONN,HA!!!F201!VDD(18)!!!!
S!PVDDQ_KLM!J9L2!76!@baseboard_fab2_lib.baseboard_fab2(sch_1):page86_i55@mstr_sconn.sconn288_h44441003(chips)!SCONN288_H44441003_PIP-SCONN,HA!!!F201!VDD(19)!!!!
S!PVDDQ_KLM!J9L2!233!@baseboard_fab2_lib.baseboard_fab2(sch_1):page86_i55@mstr_sconn.sconn288_h44441003(chips)!SCONN288_H44441003_PIP-SCONN,HA!!!F201!VDD(1)!!!!
S!PVDDQ_KLM!J9L2!73!@baseboard_fab2_lib.baseboard_fab2(sch_1):page86_i55@mstr_sconn.sconn288_h44441003(chips)!SCONN288_H44441003_PIP-SCONN,HA!!!F201!VDD(20)!!!!
S!PVDDQ_KLM!J9L2!70!@baseboard_fab2_lib.baseboard_fab2(sch_1):page86_i55@mstr_sconn.sconn288_h44441003(chips)!SCONN288_H44441003_PIP-SCONN,HA!!!F201!VDD(21)!!!!
S!PVDDQ_KLM!J9L2!67!@baseboard_fab2_lib.baseboard_fab2(sch_1):page86_i55@mstr_sconn.sconn288_h44441003(chips)!SCONN288_H44441003_PIP-SCONN,HA!!!F201!VDD(22)!!!!
S!PVDDQ_KLM!J9L2!64!@baseboard_fab2_lib.baseboard_fab2(sch_1):page86_i55@mstr_sconn.sconn288_h44441003(chips)!SCONN288_H44441003_PIP-SCONN,HA!!!F201!VDD(23)!!!!
S!PVDDQ_KLM!J9L2!61!@baseboard_fab2_lib.baseboard_fab2(sch_1):page86_i55@mstr_sconn.sconn288_h44441003(chips)!SCONN288_H44441003_PIP-SCONN,HA!!!F201!VDD(24)!!!!
S!PVDDQ_KLM!J9L2!59!@baseboard_fab2_lib.baseboard_fab2(sch_1):page86_i55@mstr_sconn.sconn288_h44441003(chips)!SCONN288_H44441003_PIP-SCONN,HA!!!F201!VDD(25)!!!!
S!PVDDQ_KLM!J9L2!231!@baseboard_fab2_lib.baseboard_fab2(sch_1):page86_i55@mstr_sconn.sconn288_h44441003(chips)!SCONN288_H44441003_PIP-SCONN,HA!!!F201!VDD(2)!!!!
S!PVDDQ_KLM!J9L2!229!@baseboard_fab2_lib.baseboard_fab2(sch_1):page86_i55@mstr_sconn.sconn288_h44441003(chips)!SCONN288_H44441003_PIP-SCONN,HA!!!F201!VDD(3)!!!!
S!PVDDQ_KLM!J9L2!226!@baseboard_fab2_lib.baseboard_fab2(sch_1):page86_i55@mstr_sconn.sconn288_h44441003(chips)!SCONN288_H44441003_PIP-SCONN,HA!!!F201!VDD(4)!!!!
S!PVDDQ_KLM!J9L2!223!@baseboard_fab2_lib.baseboard_fab2(sch_1):page86_i55@mstr_sconn.sconn288_h44441003(chips)!SCONN288_H44441003_PIP-SCONN,HA!!!F201!VDD(5)!!!!
S!PVDDQ_KLM!J9L2!220!@baseboard_fab2_lib.baseboard_fab2(sch_1):page86_i55@mstr_sconn.sconn288_h44441003(chips)!SCONN288_H44441003_PIP-SCONN,HA!!!F201!VDD(6)!!!!
S!PVDDQ_KLM!J9L2!217!@baseboard_fab2_lib.baseboard_fab2(sch_1):page86_i55@mstr_sconn.sconn288_h44441003(chips)!SCONN288_H44441003_PIP-SCONN,HA!!!F201!VDD(7)!!!!
S!PVDDQ_KLM!J9L2!215!@baseboard_fab2_lib.baseboard_fab2(sch_1):page86_i55@mstr_sconn.sconn288_h44441003(chips)!SCONN288_H44441003_PIP-SCONN,HA!!!F201!VDD(8)!!!!
S!PVDDQ_KLM!J9L2!212!@baseboard_fab2_lib.baseboard_fab2(sch_1):page86_i55@mstr_sconn.sconn288_h44441003(chips)!SCONN288_H44441003_PIP-SCONN,HA!!!F201!VDD(9)!!!!
S!PVPP_KLM!J9L2!287!@baseboard_fab2_lib.baseboard_fab2(sch_1):page86_i55@mstr_sconn.sconn288_h44441003(chips)!SCONN288_H44441003_PIP-SCONN,HA!!!F201!VPP(0)!!!!
S!PVPP_KLM!J9L2!286!@baseboard_fab2_lib.baseboard_fab2(sch_1):page86_i55@mstr_sconn.sconn288_h44441003(chips)!SCONN288_H44441003_PIP-SCONN,HA!!!F201!VPP(1)!!!!
S!PVPP_KLM!J9L2!288!@baseboard_fab2_lib.baseboard_fab2(sch_1):page86_i55@mstr_sconn.sconn288_h44441003(chips)!SCONN288_H44441003_PIP-SCONN,HA!!!F201!VPP(2)!!!!
S!PVPP_KLM!J9L2!143!@baseboard_fab2_lib.baseboard_fab2(sch_1):page86_i55@mstr_sconn.sconn288_h44441003(chips)!SCONN288_H44441003_PIP-SCONN,HA!!!F201!VPP(3)!!!!
S!PVPP_KLM!J9L2!142!@baseboard_fab2_lib.baseboard_fab2(sch_1):page86_i55@mstr_sconn.sconn288_h44441003(chips)!SCONN288_H44441003_PIP-SCONN,HA!!!F201!VPP(4)!!!!
S!PVTT_KLM!J9L2!221!@baseboard_fab2_lib.baseboard_fab2(sch_1):page86_i55@mstr_sconn.sconn288_h44441003(chips)!SCONN288_H44441003_PIP-SCONN,HA!!!F201!VTT(0)!!!!
S!PVTT_KLM!J9L2!77!@baseboard_fab2_lib.baseboard_fab2(sch_1):page86_i55@mstr_sconn.sconn288_h44441003(chips)!SCONN288_H44441003_PIP-SCONN,HA!!!F201!VTT(1)!!!!
S!M_M_MA<0>!J9L1!79!@baseboard_fab2_lib.baseboard_fab2(sch_1):page88_i111@mstr_sconn.sconn288_h44441003(chips)!SCONN288_H44441003_PIP-SCONN,HA!!!F208!A0!!!!
S!M_M_MA<1>!J9L1!72!@baseboard_fab2_lib.baseboard_fab2(sch_1):page88_i111@mstr_sconn.sconn288_h44441003(chips)!SCONN288_H44441003_PIP-SCONN,HA!!!F208!A1!!!!
S!M_M_MA<10>!J9L1!225!@baseboard_fab2_lib.baseboard_fab2(sch_1):page88_i111@mstr_sconn.sconn288_h44441003(chips)!SCONN288_H44441003_PIP-SCONN,HA!!!F208!A10!!!!
S!M_M_MA<11>!J9L1!210!@baseboard_fab2_lib.baseboard_fab2(sch_1):page88_i111@mstr_sconn.sconn288_h44441003(chips)!SCONN288_H44441003_PIP-SCONN,HA!!!F208!A11!!!!
S!M_M_MA<12>!J9L1!65!@baseboard_fab2_lib.baseboard_fab2(sch_1):page88_i111@mstr_sconn.sconn288_h44441003(chips)!SCONN288_H44441003_PIP-SCONN,HA!!!F208!A12!!!!
S!M_M_MA<13>!J9L1!232!@baseboard_fab2_lib.baseboard_fab2(sch_1):page88_i111@mstr_sconn.sconn288_h44441003(chips)!SCONN288_H44441003_PIP-SCONN,HA!!!F208!A13!!!!
S!M_M_MA<14>!J9L1!228!@baseboard_fab2_lib.baseboard_fab2(sch_1):page88_i111@mstr_sconn.sconn288_h44441003(chips)!SCONN288_H44441003_PIP-SCONN,HA!!!F208!A14_WE_N!!!!
S!M_M_MA<15>!J9L1!86!@baseboard_fab2_lib.baseboard_fab2(sch_1):page88_i111@mstr_sconn.sconn288_h44441003(chips)!SCONN288_H44441003_PIP-SCONN,HA!!!F208!A15_CAS_N!!!!
S!M_M_MA<16>!J9L1!82!@baseboard_fab2_lib.baseboard_fab2(sch_1):page88_i111@mstr_sconn.sconn288_h44441003(chips)!SCONN288_H44441003_PIP-SCONN,HA!!!F208!A16_RAS_N!!!!
S!M_M_MA<17>!J9L1!234!@baseboard_fab2_lib.baseboard_fab2(sch_1):page88_i111@mstr_sconn.sconn288_h44441003(chips)!SCONN288_H44441003_PIP-SCONN,HA!!!F208!A17!!!!
S!M_M_MA<2>!J9L1!216!@baseboard_fab2_lib.baseboard_fab2(sch_1):page88_i111@mstr_sconn.sconn288_h44441003(chips)!SCONN288_H44441003_PIP-SCONN,HA!!!F208!A2!!!!
S!M_M_MA<3>!J9L1!71!@baseboard_fab2_lib.baseboard_fab2(sch_1):page88_i111@mstr_sconn.sconn288_h44441003(chips)!SCONN288_H44441003_PIP-SCONN,HA!!!F208!A3!!!!
S!M_M_MA<4>!J9L1!214!@baseboard_fab2_lib.baseboard_fab2(sch_1):page88_i111@mstr_sconn.sconn288_h44441003(chips)!SCONN288_H44441003_PIP-SCONN,HA!!!F208!A4!!!!
S!M_M_MA<5>!J9L1!213!@baseboard_fab2_lib.baseboard_fab2(sch_1):page88_i111@mstr_sconn.sconn288_h44441003(chips)!SCONN288_H44441003_PIP-SCONN,HA!!!F208!A5!!!!
S!M_M_MA<6>!J9L1!69!@baseboard_fab2_lib.baseboard_fab2(sch_1):page88_i111@mstr_sconn.sconn288_h44441003(chips)!SCONN288_H44441003_PIP-SCONN,HA!!!F208!A6!!!!
S!M_M_MA<7>!J9L1!211!@baseboard_fab2_lib.baseboard_fab2(sch_1):page88_i111@mstr_sconn.sconn288_h44441003(chips)!SCONN288_H44441003_PIP-SCONN,HA!!!F208!A7!!!!
S!M_M_MA<8>!J9L1!68!@baseboard_fab2_lib.baseboard_fab2(sch_1):page88_i111@mstr_sconn.sconn288_h44441003(chips)!SCONN288_H44441003_PIP-SCONN,HA!!!F208!A8!!!!
S!M_M_MA<9>!J9L1!66!@baseboard_fab2_lib.baseboard_fab2(sch_1):page88_i111@mstr_sconn.sconn288_h44441003(chips)!SCONN288_H44441003_PIP-SCONN,HA!!!F208!A9!!!!
S!M_M_ACT_N!J9L1!62!@baseboard_fab2_lib.baseboard_fab2(sch_1):page88_i111@mstr_sconn.sconn288_h44441003(chips)!SCONN288_H44441003_PIP-SCONN,HA!!!F208!ACT_N!!!!
S!M_M_ALERT_N!J9L1!208!@baseboard_fab2_lib.baseboard_fab2(sch_1):page88_i111@mstr_sconn.sconn288_h44441003(chips)!SCONN288_H44441003_PIP-SCONN,HA!!!F208!ALERT_N!!!!
S!M_M_BA<0>!J9L1!81!@baseboard_fab2_lib.baseboard_fab2(sch_1):page88_i111@mstr_sconn.sconn288_h44441003(chips)!SCONN288_H44441003_PIP-SCONN,HA!!!F208!BA(0)!!!!
S!M_M_BA<1>!J9L1!224!@baseboard_fab2_lib.baseboard_fab2(sch_1):page88_i111@mstr_sconn.sconn288_h44441003(chips)!SCONN288_H44441003_PIP-SCONN,HA!!!F208!BA(1)!!!!
S!M_M_BG<0>!J9L1!63!@baseboard_fab2_lib.baseboard_fab2(sch_1):page88_i111@mstr_sconn.sconn288_h44441003(chips)!SCONN288_H44441003_PIP-SCONN,HA!!!F208!BG(0)!!!!
S!M_M_BG<1>!J9L1!207!@baseboard_fab2_lib.baseboard_fab2(sch_1):page88_i111@mstr_sconn.sconn288_h44441003(chips)!SCONN288_H44441003_PIP-SCONN,HA!!!F208!BG(1)!!!!
S!M_M_C<2>!J9L1!235!@baseboard_fab2_lib.baseboard_fab2(sch_1):page88_i111@mstr_sconn.sconn288_h44441003(chips)!SCONN288_H44441003_PIP-SCONN,HA!!!F208!C(2)!!!!
S!M_M_ECC<0>!J9L1!49!@baseboard_fab2_lib.baseboard_fab2(sch_1):page88_i111@mstr_sconn.sconn288_h44441003(chips)!SCONN288_H44441003_PIP-SCONN,HA!!!F208!CB(0)!!!!
S!M_M_ECC<1>!J9L1!194!@baseboard_fab2_lib.baseboard_fab2(sch_1):page88_i111@mstr_sconn.sconn288_h44441003(chips)!SCONN288_H44441003_PIP-SCONN,HA!!!F208!CB(1)!!!!
S!M_M_ECC<2>!J9L1!56!@baseboard_fab2_lib.baseboard_fab2(sch_1):page88_i111@mstr_sconn.sconn288_h44441003(chips)!SCONN288_H44441003_PIP-SCONN,HA!!!F208!CB(2)!!!!
S!M_M_ECC<3>!J9L1!201!@baseboard_fab2_lib.baseboard_fab2(sch_1):page88_i111@mstr_sconn.sconn288_h44441003(chips)!SCONN288_H44441003_PIP-SCONN,HA!!!F208!CB(3)!!!!
S!M_M_ECC<4>!J9L1!47!@baseboard_fab2_lib.baseboard_fab2(sch_1):page88_i111@mstr_sconn.sconn288_h44441003(chips)!SCONN288_H44441003_PIP-SCONN,HA!!!F208!CB(4)!!!!
S!M_M_ECC<5>!J9L1!192!@baseboard_fab2_lib.baseboard_fab2(sch_1):page88_i111@mstr_sconn.sconn288_h44441003(chips)!SCONN288_H44441003_PIP-SCONN,HA!!!F208!CB(5)!!!!
S!M_M_ECC<6>!J9L1!54!@baseboard_fab2_lib.baseboard_fab2(sch_1):page88_i111@mstr_sconn.sconn288_h44441003(chips)!SCONN288_H44441003_PIP-SCONN,HA!!!F208!CB(6)!!!!
S!M_M_ECC<7>!J9L1!199!@baseboard_fab2_lib.baseboard_fab2(sch_1):page88_i111@mstr_sconn.sconn288_h44441003(chips)!SCONN288_H44441003_PIP-SCONN,HA!!!F208!CB(7)!!!!
S!M_M_CLK_DN<2>!J9L1!75!@baseboard_fab2_lib.baseboard_fab2(sch_1):page88_i111@mstr_sconn.sconn288_h44441003(chips)!SCONN288_H44441003_PIP-SCONN,HA!!!F208!CK0N!!!!
S!M_M_CLK_DP<2>!J9L1!74!@baseboard_fab2_lib.baseboard_fab2(sch_1):page88_i111@mstr_sconn.sconn288_h44441003(chips)!SCONN288_H44441003_PIP-SCONN,HA!!!F208!CK0P!!!!
S!M_M_CLK_DN<3>!J9L1!219!@baseboard_fab2_lib.baseboard_fab2(sch_1):page88_i111@mstr_sconn.sconn288_h44441003(chips)!SCONN288_H44441003_PIP-SCONN,HA!!!F208!CK1N!!!!
S!M_M_CLK_DP<3>!J9L1!218!@baseboard_fab2_lib.baseboard_fab2(sch_1):page88_i111@mstr_sconn.sconn288_h44441003(chips)!SCONN288_H44441003_PIP-SCONN,HA!!!F208!CK1P!!!!
S!M_M_CKE<2>!J9L1!60!@baseboard_fab2_lib.baseboard_fab2(sch_1):page88_i111@mstr_sconn.sconn288_h44441003(chips)!SCONN288_H44441003_PIP-SCONN,HA!!!F208!CKE(0)!!!!
S!M_M_CKE<3>!J9L1!203!@baseboard_fab2_lib.baseboard_fab2(sch_1):page88_i111@mstr_sconn.sconn288_h44441003(chips)!SCONN288_H44441003_PIP-SCONN,HA!!!F208!CKE(1)!!!!
S!M_M_DQ<0>!J9L1!5!@baseboard_fab2_lib.baseboard_fab2(sch_1):page88_i111@mstr_sconn.sconn288_h44441003(chips)!SCONN288_H44441003_PIP-SCONN,HA!!!F208!DQ(0)!!!!
S!M_M_DQ<10>!J9L1!23!@baseboard_fab2_lib.baseboard_fab2(sch_1):page88_i111@mstr_sconn.sconn288_h44441003(chips)!SCONN288_H44441003_PIP-SCONN,HA!!!F208!DQ(10)!!!!
S!M_M_DQ<11>!J9L1!168!@baseboard_fab2_lib.baseboard_fab2(sch_1):page88_i111@mstr_sconn.sconn288_h44441003(chips)!SCONN288_H44441003_PIP-SCONN,HA!!!F208!DQ(11)!!!!
S!M_M_DQ<12>!J9L1!14!@baseboard_fab2_lib.baseboard_fab2(sch_1):page88_i111@mstr_sconn.sconn288_h44441003(chips)!SCONN288_H44441003_PIP-SCONN,HA!!!F208!DQ(12)!!!!
S!M_M_DQ<13>!J9L1!159!@baseboard_fab2_lib.baseboard_fab2(sch_1):page88_i111@mstr_sconn.sconn288_h44441003(chips)!SCONN288_H44441003_PIP-SCONN,HA!!!F208!DQ(13)!!!!
S!M_M_DQ<14>!J9L1!21!@baseboard_fab2_lib.baseboard_fab2(sch_1):page88_i111@mstr_sconn.sconn288_h44441003(chips)!SCONN288_H44441003_PIP-SCONN,HA!!!F208!DQ(14)!!!!
S!M_M_DQ<15>!J9L1!166!@baseboard_fab2_lib.baseboard_fab2(sch_1):page88_i111@mstr_sconn.sconn288_h44441003(chips)!SCONN288_H44441003_PIP-SCONN,HA!!!F208!DQ(15)!!!!
S!M_M_DQ<16>!J9L1!27!@baseboard_fab2_lib.baseboard_fab2(sch_1):page88_i111@mstr_sconn.sconn288_h44441003(chips)!SCONN288_H44441003_PIP-SCONN,HA!!!F208!DQ(16)!!!!
S!M_M_DQ<17>!J9L1!172!@baseboard_fab2_lib.baseboard_fab2(sch_1):page88_i111@mstr_sconn.sconn288_h44441003(chips)!SCONN288_H44441003_PIP-SCONN,HA!!!F208!DQ(17)!!!!
S!M_M_DQ<18>!J9L1!34!@baseboard_fab2_lib.baseboard_fab2(sch_1):page88_i111@mstr_sconn.sconn288_h44441003(chips)!SCONN288_H44441003_PIP-SCONN,HA!!!F208!DQ(18)!!!!
S!M_M_DQ<19>!J9L1!179!@baseboard_fab2_lib.baseboard_fab2(sch_1):page88_i111@mstr_sconn.sconn288_h44441003(chips)!SCONN288_H44441003_PIP-SCONN,HA!!!F208!DQ(19)!!!!
S!M_M_DQ<1>!J9L1!150!@baseboard_fab2_lib.baseboard_fab2(sch_1):page88_i111@mstr_sconn.sconn288_h44441003(chips)!SCONN288_H44441003_PIP-SCONN,HA!!!F208!DQ(1)!!!!
S!M_M_DQ<20>!J9L1!25!@baseboard_fab2_lib.baseboard_fab2(sch_1):page88_i111@mstr_sconn.sconn288_h44441003(chips)!SCONN288_H44441003_PIP-SCONN,HA!!!F208!DQ(20)!!!!
S!M_M_DQ<21>!J9L1!170!@baseboard_fab2_lib.baseboard_fab2(sch_1):page88_i111@mstr_sconn.sconn288_h44441003(chips)!SCONN288_H44441003_PIP-SCONN,HA!!!F208!DQ(21)!!!!
S!M_M_DQ<22>!J9L1!32!@baseboard_fab2_lib.baseboard_fab2(sch_1):page88_i111@mstr_sconn.sconn288_h44441003(chips)!SCONN288_H44441003_PIP-SCONN,HA!!!F208!DQ(22)!!!!
S!M_M_DQ<23>!J9L1!177!@baseboard_fab2_lib.baseboard_fab2(sch_1):page88_i111@mstr_sconn.sconn288_h44441003(chips)!SCONN288_H44441003_PIP-SCONN,HA!!!F208!DQ(23)!!!!
S!M_M_DQ<24>!J9L1!38!@baseboard_fab2_lib.baseboard_fab2(sch_1):page88_i111@mstr_sconn.sconn288_h44441003(chips)!SCONN288_H44441003_PIP-SCONN,HA!!!F208!DQ(24)!!!!
S!M_M_DQ<25>!J9L1!183!@baseboard_fab2_lib.baseboard_fab2(sch_1):page88_i111@mstr_sconn.sconn288_h44441003(chips)!SCONN288_H44441003_PIP-SCONN,HA!!!F208!DQ(25)!!!!
S!M_M_DQ<26>!J9L1!45!@baseboard_fab2_lib.baseboard_fab2(sch_1):page88_i111@mstr_sconn.sconn288_h44441003(chips)!SCONN288_H44441003_PIP-SCONN,HA!!!F208!DQ(26)!!!!
S!M_M_DQ<27>!J9L1!190!@baseboard_fab2_lib.baseboard_fab2(sch_1):page88_i111@mstr_sconn.sconn288_h44441003(chips)!SCONN288_H44441003_PIP-SCONN,HA!!!F208!DQ(27)!!!!
S!M_M_DQ<28>!J9L1!36!@baseboard_fab2_lib.baseboard_fab2(sch_1):page88_i111@mstr_sconn.sconn288_h44441003(chips)!SCONN288_H44441003_PIP-SCONN,HA!!!F208!DQ(28)!!!!
S!M_M_DQ<29>!J9L1!181!@baseboard_fab2_lib.baseboard_fab2(sch_1):page88_i111@mstr_sconn.sconn288_h44441003(chips)!SCONN288_H44441003_PIP-SCONN,HA!!!F208!DQ(29)!!!!
S!M_M_DQ<2>!J9L1!12!@baseboard_fab2_lib.baseboard_fab2(sch_1):page88_i111@mstr_sconn.sconn288_h44441003(chips)!SCONN288_H44441003_PIP-SCONN,HA!!!F208!DQ(2)!!!!
S!M_M_DQ<30>!J9L1!43!@baseboard_fab2_lib.baseboard_fab2(sch_1):page88_i111@mstr_sconn.sconn288_h44441003(chips)!SCONN288_H44441003_PIP-SCONN,HA!!!F208!DQ(30)!!!!
S!M_M_DQ<31>!J9L1!188!@baseboard_fab2_lib.baseboard_fab2(sch_1):page88_i111@mstr_sconn.sconn288_h44441003(chips)!SCONN288_H44441003_PIP-SCONN,HA!!!F208!DQ(31)!!!!
S!M_M_DQ<32>!J9L1!97!@baseboard_fab2_lib.baseboard_fab2(sch_1):page88_i111@mstr_sconn.sconn288_h44441003(chips)!SCONN288_H44441003_PIP-SCONN,HA!!!F208!DQ(32)!!!!
S!M_M_DQ<33>!J9L1!242!@baseboard_fab2_lib.baseboard_fab2(sch_1):page88_i111@mstr_sconn.sconn288_h44441003(chips)!SCONN288_H44441003_PIP-SCONN,HA!!!F208!DQ(33)!!!!
S!M_M_DQ<34>!J9L1!104!@baseboard_fab2_lib.baseboard_fab2(sch_1):page88_i111@mstr_sconn.sconn288_h44441003(chips)!SCONN288_H44441003_PIP-SCONN,HA!!!F208!DQ(34)!!!!
S!M_M_DQ<35>!J9L1!249!@baseboard_fab2_lib.baseboard_fab2(sch_1):page88_i111@mstr_sconn.sconn288_h44441003(chips)!SCONN288_H44441003_PIP-SCONN,HA!!!F208!DQ(35)!!!!
S!M_M_DQ<36>!J9L1!95!@baseboard_fab2_lib.baseboard_fab2(sch_1):page88_i111@mstr_sconn.sconn288_h44441003(chips)!SCONN288_H44441003_PIP-SCONN,HA!!!F208!DQ(36)!!!!
S!M_M_DQ<37>!J9L1!240!@baseboard_fab2_lib.baseboard_fab2(sch_1):page88_i111@mstr_sconn.sconn288_h44441003(chips)!SCONN288_H44441003_PIP-SCONN,HA!!!F208!DQ(37)!!!!
S!M_M_DQ<38>!J9L1!102!@baseboard_fab2_lib.baseboard_fab2(sch_1):page88_i111@mstr_sconn.sconn288_h44441003(chips)!SCONN288_H44441003_PIP-SCONN,HA!!!F208!DQ(38)!!!!
S!M_M_DQ<39>!J9L1!247!@baseboard_fab2_lib.baseboard_fab2(sch_1):page88_i111@mstr_sconn.sconn288_h44441003(chips)!SCONN288_H44441003_PIP-SCONN,HA!!!F208!DQ(39)!!!!
S!M_M_DQ<3>!J9L1!157!@baseboard_fab2_lib.baseboard_fab2(sch_1):page88_i111@mstr_sconn.sconn288_h44441003(chips)!SCONN288_H44441003_PIP-SCONN,HA!!!F208!DQ(3)!!!!
S!M_M_DQ<40>!J9L1!108!@baseboard_fab2_lib.baseboard_fab2(sch_1):page88_i111@mstr_sconn.sconn288_h44441003(chips)!SCONN288_H44441003_PIP-SCONN,HA!!!F208!DQ(40)!!!!
S!M_M_DQ<41>!J9L1!253!@baseboard_fab2_lib.baseboard_fab2(sch_1):page88_i111@mstr_sconn.sconn288_h44441003(chips)!SCONN288_H44441003_PIP-SCONN,HA!!!F208!DQ(41)!!!!
S!M_M_DQ<42>!J9L1!115!@baseboard_fab2_lib.baseboard_fab2(sch_1):page88_i111@mstr_sconn.sconn288_h44441003(chips)!SCONN288_H44441003_PIP-SCONN,HA!!!F208!DQ(42)!!!!
S!M_M_DQ<43>!J9L1!260!@baseboard_fab2_lib.baseboard_fab2(sch_1):page88_i111@mstr_sconn.sconn288_h44441003(chips)!SCONN288_H44441003_PIP-SCONN,HA!!!F208!DQ(43)!!!!
S!M_M_DQ<44>!J9L1!106!@baseboard_fab2_lib.baseboard_fab2(sch_1):page88_i111@mstr_sconn.sconn288_h44441003(chips)!SCONN288_H44441003_PIP-SCONN,HA!!!F208!DQ(44)!!!!
S!M_M_DQ<45>!J9L1!251!@baseboard_fab2_lib.baseboard_fab2(sch_1):page88_i111@mstr_sconn.sconn288_h44441003(chips)!SCONN288_H44441003_PIP-SCONN,HA!!!F208!DQ(45)!!!!
S!M_M_DQ<46>!J9L1!113!@baseboard_fab2_lib.baseboard_fab2(sch_1):page88_i111@mstr_sconn.sconn288_h44441003(chips)!SCONN288_H44441003_PIP-SCONN,HA!!!F208!DQ(46)!!!!
S!M_M_DQ<47>!J9L1!258!@baseboard_fab2_lib.baseboard_fab2(sch_1):page88_i111@mstr_sconn.sconn288_h44441003(chips)!SCONN288_H44441003_PIP-SCONN,HA!!!F208!DQ(47)!!!!
S!M_M_DQ<48>!J9L1!119!@baseboard_fab2_lib.baseboard_fab2(sch_1):page88_i111@mstr_sconn.sconn288_h44441003(chips)!SCONN288_H44441003_PIP-SCONN,HA!!!F208!DQ(48)!!!!
S!M_M_DQ<49>!J9L1!264!@baseboard_fab2_lib.baseboard_fab2(sch_1):page88_i111@mstr_sconn.sconn288_h44441003(chips)!SCONN288_H44441003_PIP-SCONN,HA!!!F208!DQ(49)!!!!
S!M_M_DQ<4>!J9L1!3!@baseboard_fab2_lib.baseboard_fab2(sch_1):page88_i111@mstr_sconn.sconn288_h44441003(chips)!SCONN288_H44441003_PIP-SCONN,HA!!!F208!DQ(4)!!!!
S!M_M_DQ<50>!J9L1!126!@baseboard_fab2_lib.baseboard_fab2(sch_1):page88_i111@mstr_sconn.sconn288_h44441003(chips)!SCONN288_H44441003_PIP-SCONN,HA!!!F208!DQ(50)!!!!
S!M_M_DQ<51>!J9L1!271!@baseboard_fab2_lib.baseboard_fab2(sch_1):page88_i111@mstr_sconn.sconn288_h44441003(chips)!SCONN288_H44441003_PIP-SCONN,HA!!!F208!DQ(51)!!!!
S!M_M_DQ<52>!J9L1!117!@baseboard_fab2_lib.baseboard_fab2(sch_1):page88_i111@mstr_sconn.sconn288_h44441003(chips)!SCONN288_H44441003_PIP-SCONN,HA!!!F208!DQ(52)!!!!
S!M_M_DQ<53>!J9L1!262!@baseboard_fab2_lib.baseboard_fab2(sch_1):page88_i111@mstr_sconn.sconn288_h44441003(chips)!SCONN288_H44441003_PIP-SCONN,HA!!!F208!DQ(53)!!!!
S!M_M_DQ<54>!J9L1!124!@baseboard_fab2_lib.baseboard_fab2(sch_1):page88_i111@mstr_sconn.sconn288_h44441003(chips)!SCONN288_H44441003_PIP-SCONN,HA!!!F208!DQ(54)!!!!
S!M_M_DQ<55>!J9L1!269!@baseboard_fab2_lib.baseboard_fab2(sch_1):page88_i111@mstr_sconn.sconn288_h44441003(chips)!SCONN288_H44441003_PIP-SCONN,HA!!!F208!DQ(55)!!!!
S!M_M_DQ<56>!J9L1!130!@baseboard_fab2_lib.baseboard_fab2(sch_1):page88_i111@mstr_sconn.sconn288_h44441003(chips)!SCONN288_H44441003_PIP-SCONN,HA!!!F208!DQ(56)!!!!
S!M_M_DQ<57>!J9L1!275!@baseboard_fab2_lib.baseboard_fab2(sch_1):page88_i111@mstr_sconn.sconn288_h44441003(chips)!SCONN288_H44441003_PIP-SCONN,HA!!!F208!DQ(57)!!!!
S!M_M_DQ<58>!J9L1!137!@baseboard_fab2_lib.baseboard_fab2(sch_1):page88_i111@mstr_sconn.sconn288_h44441003(chips)!SCONN288_H44441003_PIP-SCONN,HA!!!F208!DQ(58)!!!!
S!M_M_DQ<59>!J9L1!282!@baseboard_fab2_lib.baseboard_fab2(sch_1):page88_i111@mstr_sconn.sconn288_h44441003(chips)!SCONN288_H44441003_PIP-SCONN,HA!!!F208!DQ(59)!!!!
S!M_M_DQ<5>!J9L1!148!@baseboard_fab2_lib.baseboard_fab2(sch_1):page88_i111@mstr_sconn.sconn288_h44441003(chips)!SCONN288_H44441003_PIP-SCONN,HA!!!F208!DQ(5)!!!!
S!M_M_DQ<60>!J9L1!128!@baseboard_fab2_lib.baseboard_fab2(sch_1):page88_i111@mstr_sconn.sconn288_h44441003(chips)!SCONN288_H44441003_PIP-SCONN,HA!!!F208!DQ(60)!!!!
S!M_M_DQ<61>!J9L1!273!@baseboard_fab2_lib.baseboard_fab2(sch_1):page88_i111@mstr_sconn.sconn288_h44441003(chips)!SCONN288_H44441003_PIP-SCONN,HA!!!F208!DQ(61)!!!!
S!M_M_DQ<62>!J9L1!135!@baseboard_fab2_lib.baseboard_fab2(sch_1):page88_i111@mstr_sconn.sconn288_h44441003(chips)!SCONN288_H44441003_PIP-SCONN,HA!!!F208!DQ(62)!!!!
S!M_M_DQ<63>!J9L1!280!@baseboard_fab2_lib.baseboard_fab2(sch_1):page88_i111@mstr_sconn.sconn288_h44441003(chips)!SCONN288_H44441003_PIP-SCONN,HA!!!F208!DQ(63)!!!!
S!M_M_DQ<6>!J9L1!10!@baseboard_fab2_lib.baseboard_fab2(sch_1):page88_i111@mstr_sconn.sconn288_h44441003(chips)!SCONN288_H44441003_PIP-SCONN,HA!!!F208!DQ(6)!!!!
S!M_M_DQ<7>!J9L1!155!@baseboard_fab2_lib.baseboard_fab2(sch_1):page88_i111@mstr_sconn.sconn288_h44441003(chips)!SCONN288_H44441003_PIP-SCONN,HA!!!F208!DQ(7)!!!!
S!M_M_DQ<8>!J9L1!16!@baseboard_fab2_lib.baseboard_fab2(sch_1):page88_i111@mstr_sconn.sconn288_h44441003(chips)!SCONN288_H44441003_PIP-SCONN,HA!!!F208!DQ(8)!!!!
S!M_M_DQ<9>!J9L1!161!@baseboard_fab2_lib.baseboard_fab2(sch_1):page88_i111@mstr_sconn.sconn288_h44441003(chips)!SCONN288_H44441003_PIP-SCONN,HA!!!F208!DQ(9)!!!!
S!FM_DIMM_EVENT_COD_N!J9L1!78!@baseboard_fab2_lib.baseboard_fab2(sch_1):page88_i111@mstr_sconn.sconn288_h44441003(chips)!SCONN288_H44441003_PIP-SCONN,HA!!!F208!EVENT_N!!!!
S!M_M_ODT<2>!J9L1!87!@baseboard_fab2_lib.baseboard_fab2(sch_1):page88_i111@mstr_sconn.sconn288_h44441003(chips)!SCONN288_H44441003_PIP-SCONN,HA!!!F208!ODT(0)!!!!
S!M_M_ODT<3>!J9L1!91!@baseboard_fab2_lib.baseboard_fab2(sch_1):page88_i111@mstr_sconn.sconn288_h44441003(chips)!SCONN288_H44441003_PIP-SCONN,HA!!!F208!ODT(1)!!!!
S!M_M_PAR!J9L1!222!@baseboard_fab2_lib.baseboard_fab2(sch_1):page88_i111@mstr_sconn.sconn288_h44441003(chips)!SCONN288_H44441003_PIP-SCONN,HA!!!F208!PAR!!!!
S!M_KLM_RST_N!J9L1!58!@baseboard_fab2_lib.baseboard_fab2(sch_1):page88_i111@mstr_sconn.sconn288_h44441003(chips)!SCONN288_H44441003_PIP-SCONN,HA!!!F208!RESET_N!!!!
S!TP_CH_M_DIMM_M1_RFU_0!J9L1!205!@baseboard_fab2_lib.baseboard_fab2(sch_1):page88_i111@mstr_sconn.sconn288_h44441003(chips)!SCONN288_H44441003_PIP-SCONN,HA!!!F208!RFU(0)!!!!
S!TP_CH_M_DIMM_M1_RFU_1!J9L1!227!@baseboard_fab2_lib.baseboard_fab2(sch_1):page88_i111@mstr_sconn.sconn288_h44441003(chips)!SCONN288_H44441003_PIP-SCONN,HA!!!F208!RFU(1)!!!!
S!TP_CH_M_DIMM_M1_RFU_2!J9L1!144!@baseboard_fab2_lib.baseboard_fab2(sch_1):page88_i111@mstr_sconn.sconn288_h44441003(chips)!SCONN288_H44441003_PIP-SCONN,HA!!!F208!RFU(2)!!!!
S!M_M_CS_N<4>!J9L1!84!@baseboard_fab2_lib.baseboard_fab2(sch_1):page88_i111@mstr_sconn.sconn288_h44441003(chips)!SCONN288_H44441003_PIP-SCONN,HA!!!F208!S0_N!!!!
S!M_M_CS_N<5>!J9L1!89!@baseboard_fab2_lib.baseboard_fab2(sch_1):page88_i111@mstr_sconn.sconn288_h44441003(chips)!SCONN288_H44441003_PIP-SCONN,HA!!!F208!S1_N!!!!
S!M_M_CS_N<6>!J9L1!93!@baseboard_fab2_lib.baseboard_fab2(sch_1):page88_i111@mstr_sconn.sconn288_h44441003(chips)!SCONN288_H44441003_PIP-SCONN,HA!!!F208!S2_N_C(0)!!!!
S!M_M_CS_N<7>!J9L1!237!@baseboard_fab2_lib.baseboard_fab2(sch_1):page88_i111@mstr_sconn.sconn288_h44441003(chips)!SCONN288_H44441003_PIP-SCONN,HA!!!F208!S3_N_C(1)!!!!
S!PVPP_KLM!J9L1!139!@baseboard_fab2_lib.baseboard_fab2(sch_1):page88_i111@mstr_sconn.sconn288_h44441003(chips)!SCONN288_H44441003_PIP-SCONN,HA!!!F208!SA(0)!!!!
S!GND!J9L1!140!@baseboard_fab2_lib.baseboard_fab2(sch_1):page88_i111@mstr_sconn.sconn288_h44441003(chips)!SCONN288_H44441003_PIP-SCONN,HA!!!F208!SA(1)!!!!
S!PVPP_KLM!J9L1!238!@baseboard_fab2_lib.baseboard_fab2(sch_1):page88_i111@mstr_sconn.sconn288_h44441003(chips)!SCONN288_H44441003_PIP-SCONN,HA!!!F208!SA(2)!!!!
S!FM_ADR_COMPLETE_KLM_N!J9L1!230!@baseboard_fab2_lib.baseboard_fab2(sch_1):page88_i111@mstr_sconn.sconn288_h44441003(chips)!SCONN288_H44441003_PIP-SCONN,HA!!!F208!SAVE_N_NC!!!!
S!SMB_DDR_KLM_VPP_SCL!J9L1!141!@baseboard_fab2_lib.baseboard_fab2(sch_1):page88_i111@mstr_sconn.sconn288_h44441003(chips)!SCONN288_H44441003_PIP-SCONN,HA!!!F208!SCL!!!!
S!SMB_DDR_KLM_VPP_SDA!J9L1!285!@baseboard_fab2_lib.baseboard_fab2(sch_1):page88_i111@mstr_sconn.sconn288_h44441003(chips)!SCONN288_H44441003_PIP-SCONN,HA!!!F208!SDA!!!!
S!PVPP_KLM!J9L1!284!@baseboard_fab2_lib.baseboard_fab2(sch_1):page88_i111@mstr_sconn.sconn288_h44441003(chips)!SCONN288_H44441003_PIP-SCONN,HA!!!F208!VDDSPD!!!!
S!M_M_VREF!J9L1!146!@baseboard_fab2_lib.baseboard_fab2(sch_1):page88_i111@mstr_sconn.sconn288_h44441003(chips)!SCONN288_H44441003_PIP-SCONN,HA!!!F208!VREFCA!!!!
S!M_M_DQS_DN<0>!J9L1!152!@baseboard_fab2_lib.baseboard_fab2(sch_1):page88_i87@mstr_sconn.sconn288_h44441003(chips)!SCONN288_H44441003_PIP-SCONN,HA!!!F207!DQS0N!!!!
S!M_M_DQS_DP<0>!J9L1!153!@baseboard_fab2_lib.baseboard_fab2(sch_1):page88_i87@mstr_sconn.sconn288_h44441003(chips)!SCONN288_H44441003_PIP-SCONN,HA!!!F207!DQS0P!!!!
S!M_M_DQS_DN<10>!J9L1!19!@baseboard_fab2_lib.baseboard_fab2(sch_1):page88_i87@mstr_sconn.sconn288_h44441003(chips)!SCONN288_H44441003_PIP-SCONN,HA!!!F207!DQS10N!!!!
S!M_M_DQS_DP<10>!J9L1!18!@baseboard_fab2_lib.baseboard_fab2(sch_1):page88_i87@mstr_sconn.sconn288_h44441003(chips)!SCONN288_H44441003_PIP-SCONN,HA!!!F207!DQS10P!!!!
S!M_M_DQS_DN<11>!J9L1!30!@baseboard_fab2_lib.baseboard_fab2(sch_1):page88_i87@mstr_sconn.sconn288_h44441003(chips)!SCONN288_H44441003_PIP-SCONN,HA!!!F207!DQS11N!!!!
S!M_M_DQS_DP<11>!J9L1!29!@baseboard_fab2_lib.baseboard_fab2(sch_1):page88_i87@mstr_sconn.sconn288_h44441003(chips)!SCONN288_H44441003_PIP-SCONN,HA!!!F207!DQS11P!!!!
S!M_M_DQS_DN<12>!J9L1!41!@baseboard_fab2_lib.baseboard_fab2(sch_1):page88_i87@mstr_sconn.sconn288_h44441003(chips)!SCONN288_H44441003_PIP-SCONN,HA!!!F207!DQS12N!!!!
S!M_M_DQS_DP<12>!J9L1!40!@baseboard_fab2_lib.baseboard_fab2(sch_1):page88_i87@mstr_sconn.sconn288_h44441003(chips)!SCONN288_H44441003_PIP-SCONN,HA!!!F207!DQS12P!!!!
S!M_M_DQS_DN<13>!J9L1!100!@baseboard_fab2_lib.baseboard_fab2(sch_1):page88_i87@mstr_sconn.sconn288_h44441003(chips)!SCONN288_H44441003_PIP-SCONN,HA!!!F207!DQS13N!!!!
S!M_M_DQS_DP<13>!J9L1!99!@baseboard_fab2_lib.baseboard_fab2(sch_1):page88_i87@mstr_sconn.sconn288_h44441003(chips)!SCONN288_H44441003_PIP-SCONN,HA!!!F207!DQS13P!!!!
S!M_M_DQS_DN<14>!J9L1!111!@baseboard_fab2_lib.baseboard_fab2(sch_1):page88_i87@mstr_sconn.sconn288_h44441003(chips)!SCONN288_H44441003_PIP-SCONN,HA!!!F207!DQS14N!!!!
S!M_M_DQS_DP<14>!J9L1!110!@baseboard_fab2_lib.baseboard_fab2(sch_1):page88_i87@mstr_sconn.sconn288_h44441003(chips)!SCONN288_H44441003_PIP-SCONN,HA!!!F207!DQS14P!!!!
S!M_M_DQS_DN<15>!J9L1!122!@baseboard_fab2_lib.baseboard_fab2(sch_1):page88_i87@mstr_sconn.sconn288_h44441003(chips)!SCONN288_H44441003_PIP-SCONN,HA!!!F207!DQS15N!!!!
S!M_M_DQS_DP<15>!J9L1!121!@baseboard_fab2_lib.baseboard_fab2(sch_1):page88_i87@mstr_sconn.sconn288_h44441003(chips)!SCONN288_H44441003_PIP-SCONN,HA!!!F207!DQS15P!!!!
S!M_M_DQS_DN<16>!J9L1!133!@baseboard_fab2_lib.baseboard_fab2(sch_1):page88_i87@mstr_sconn.sconn288_h44441003(chips)!SCONN288_H44441003_PIP-SCONN,HA!!!F207!DQS16N!!!!
S!M_M_DQS_DP<16>!J9L1!132!@baseboard_fab2_lib.baseboard_fab2(sch_1):page88_i87@mstr_sconn.sconn288_h44441003(chips)!SCONN288_H44441003_PIP-SCONN,HA!!!F207!DQS16P!!!!
S!M_M_DQS_DN<17>!J9L1!52!@baseboard_fab2_lib.baseboard_fab2(sch_1):page88_i87@mstr_sconn.sconn288_h44441003(chips)!SCONN288_H44441003_PIP-SCONN,HA!!!F207!DQS17N!!!!
S!M_M_DQS_DP<17>!J9L1!51!@baseboard_fab2_lib.baseboard_fab2(sch_1):page88_i87@mstr_sconn.sconn288_h44441003(chips)!SCONN288_H44441003_PIP-SCONN,HA!!!F207!DQS17P!!!!
S!M_M_DQS_DN<1>!J9L1!163!@baseboard_fab2_lib.baseboard_fab2(sch_1):page88_i87@mstr_sconn.sconn288_h44441003(chips)!SCONN288_H44441003_PIP-SCONN,HA!!!F207!DQS1N!!!!
S!M_M_DQS_DP<1>!J9L1!164!@baseboard_fab2_lib.baseboard_fab2(sch_1):page88_i87@mstr_sconn.sconn288_h44441003(chips)!SCONN288_H44441003_PIP-SCONN,HA!!!F207!DQS1P!!!!
S!M_M_DQS_DN<2>!J9L1!174!@baseboard_fab2_lib.baseboard_fab2(sch_1):page88_i87@mstr_sconn.sconn288_h44441003(chips)!SCONN288_H44441003_PIP-SCONN,HA!!!F207!DQS2N!!!!
S!M_M_DQS_DP<2>!J9L1!175!@baseboard_fab2_lib.baseboard_fab2(sch_1):page88_i87@mstr_sconn.sconn288_h44441003(chips)!SCONN288_H44441003_PIP-SCONN,HA!!!F207!DQS2P!!!!
S!M_M_DQS_DN<3>!J9L1!185!@baseboard_fab2_lib.baseboard_fab2(sch_1):page88_i87@mstr_sconn.sconn288_h44441003(chips)!SCONN288_H44441003_PIP-SCONN,HA!!!F207!DQS3N!!!!
S!M_M_DQS_DP<3>!J9L1!186!@baseboard_fab2_lib.baseboard_fab2(sch_1):page88_i87@mstr_sconn.sconn288_h44441003(chips)!SCONN288_H44441003_PIP-SCONN,HA!!!F207!DQS3P!!!!
S!M_M_DQS_DN<4>!J9L1!244!@baseboard_fab2_lib.baseboard_fab2(sch_1):page88_i87@mstr_sconn.sconn288_h44441003(chips)!SCONN288_H44441003_PIP-SCONN,HA!!!F207!DQS4N!!!!
S!M_M_DQS_DP<4>!J9L1!245!@baseboard_fab2_lib.baseboard_fab2(sch_1):page88_i87@mstr_sconn.sconn288_h44441003(chips)!SCONN288_H44441003_PIP-SCONN,HA!!!F207!DQS4P!!!!
S!M_M_DQS_DN<5>!J9L1!255!@baseboard_fab2_lib.baseboard_fab2(sch_1):page88_i87@mstr_sconn.sconn288_h44441003(chips)!SCONN288_H44441003_PIP-SCONN,HA!!!F207!DQS5N!!!!
S!M_M_DQS_DP<5>!J9L1!256!@baseboard_fab2_lib.baseboard_fab2(sch_1):page88_i87@mstr_sconn.sconn288_h44441003(chips)!SCONN288_H44441003_PIP-SCONN,HA!!!F207!DQS5P!!!!
S!M_M_DQS_DN<6>!J9L1!266!@baseboard_fab2_lib.baseboard_fab2(sch_1):page88_i87@mstr_sconn.sconn288_h44441003(chips)!SCONN288_H44441003_PIP-SCONN,HA!!!F207!DQS6N!!!!
S!M_M_DQS_DP<6>!J9L1!267!@baseboard_fab2_lib.baseboard_fab2(sch_1):page88_i87@mstr_sconn.sconn288_h44441003(chips)!SCONN288_H44441003_PIP-SCONN,HA!!!F207!DQS6P!!!!
S!M_M_DQS_DN<7>!J9L1!277!@baseboard_fab2_lib.baseboard_fab2(sch_1):page88_i87@mstr_sconn.sconn288_h44441003(chips)!SCONN288_H44441003_PIP-SCONN,HA!!!F207!DQS7N!!!!
S!M_M_DQS_DP<7>!J9L1!278!@baseboard_fab2_lib.baseboard_fab2(sch_1):page88_i87@mstr_sconn.sconn288_h44441003(chips)!SCONN288_H44441003_PIP-SCONN,HA!!!F207!DQS7P!!!!
S!M_M_DQS_DN<8>!J9L1!196!@baseboard_fab2_lib.baseboard_fab2(sch_1):page88_i87@mstr_sconn.sconn288_h44441003(chips)!SCONN288_H44441003_PIP-SCONN,HA!!!F207!DQS8N!!!!
S!M_M_DQS_DP<8>!J9L1!197!@baseboard_fab2_lib.baseboard_fab2(sch_1):page88_i87@mstr_sconn.sconn288_h44441003(chips)!SCONN288_H44441003_PIP-SCONN,HA!!!F207!DQS8P!!!!
S!M_M_DQS_DN<9>!J9L1!8!@baseboard_fab2_lib.baseboard_fab2(sch_1):page88_i87@mstr_sconn.sconn288_h44441003(chips)!SCONN288_H44441003_PIP-SCONN,HA!!!F207!DQS9N!!!!
S!M_M_DQS_DP<9>!J9L1!7!@baseboard_fab2_lib.baseboard_fab2(sch_1):page88_i87@mstr_sconn.sconn288_h44441003(chips)!SCONN288_H44441003_PIP-SCONN,HA!!!F207!DQS9P!!!!
S!GND!J9L1!283!@baseboard_fab2_lib.baseboard_fab2(sch_1):page88_i25@mstr_sconn.sconn288_h44441003(chips)!SCONN288_H44441003_PIP-SCONN,HA!!!F206!VSS(0)!!!!
S!GND!J9L1!261!@baseboard_fab2_lib.baseboard_fab2(sch_1):page88_i25@mstr_sconn.sconn288_h44441003(chips)!SCONN288_H44441003_PIP-SCONN,HA!!!F206!VSS(10)!!!!
S!GND!J9L1!259!@baseboard_fab2_lib.baseboard_fab2(sch_1):page88_i25@mstr_sconn.sconn288_h44441003(chips)!SCONN288_H44441003_PIP-SCONN,HA!!!F206!VSS(11)!!!!
S!GND!J9L1!257!@baseboard_fab2_lib.baseboard_fab2(sch_1):page88_i25@mstr_sconn.sconn288_h44441003(chips)!SCONN288_H44441003_PIP-SCONN,HA!!!F206!VSS(12)!!!!
S!GND!J9L1!254!@baseboard_fab2_lib.baseboard_fab2(sch_1):page88_i25@mstr_sconn.sconn288_h44441003(chips)!SCONN288_H44441003_PIP-SCONN,HA!!!F206!VSS(13)!!!!
S!GND!J9L1!252!@baseboard_fab2_lib.baseboard_fab2(sch_1):page88_i25@mstr_sconn.sconn288_h44441003(chips)!SCONN288_H44441003_PIP-SCONN,HA!!!F206!VSS(14)!!!!
S!GND!J9L1!250!@baseboard_fab2_lib.baseboard_fab2(sch_1):page88_i25@mstr_sconn.sconn288_h44441003(chips)!SCONN288_H44441003_PIP-SCONN,HA!!!F206!VSS(15)!!!!
S!GND!J9L1!248!@baseboard_fab2_lib.baseboard_fab2(sch_1):page88_i25@mstr_sconn.sconn288_h44441003(chips)!SCONN288_H44441003_PIP-SCONN,HA!!!F206!VSS(16)!!!!
S!GND!J9L1!246!@baseboard_fab2_lib.baseboard_fab2(sch_1):page88_i25@mstr_sconn.sconn288_h44441003(chips)!SCONN288_H44441003_PIP-SCONN,HA!!!F206!VSS(17)!!!!
S!GND!J9L1!243!@baseboard_fab2_lib.baseboard_fab2(sch_1):page88_i25@mstr_sconn.sconn288_h44441003(chips)!SCONN288_H44441003_PIP-SCONN,HA!!!F206!VSS(18)!!!!
S!GND!J9L1!241!@baseboard_fab2_lib.baseboard_fab2(sch_1):page88_i25@mstr_sconn.sconn288_h44441003(chips)!SCONN288_H44441003_PIP-SCONN,HA!!!F206!VSS(19)!!!!
S!GND!J9L1!281!@baseboard_fab2_lib.baseboard_fab2(sch_1):page88_i25@mstr_sconn.sconn288_h44441003(chips)!SCONN288_H44441003_PIP-SCONN,HA!!!F206!VSS(1)!!!!
S!GND!J9L1!239!@baseboard_fab2_lib.baseboard_fab2(sch_1):page88_i25@mstr_sconn.sconn288_h44441003(chips)!SCONN288_H44441003_PIP-SCONN,HA!!!F206!VSS(20)!!!!
S!GND!J9L1!202!@baseboard_fab2_lib.baseboard_fab2(sch_1):page88_i25@mstr_sconn.sconn288_h44441003(chips)!SCONN288_H44441003_PIP-SCONN,HA!!!F206!VSS(21)!!!!
S!GND!J9L1!200!@baseboard_fab2_lib.baseboard_fab2(sch_1):page88_i25@mstr_sconn.sconn288_h44441003(chips)!SCONN288_H44441003_PIP-SCONN,HA!!!F206!VSS(22)!!!!
S!GND!J9L1!198!@baseboard_fab2_lib.baseboard_fab2(sch_1):page88_i25@mstr_sconn.sconn288_h44441003(chips)!SCONN288_H44441003_PIP-SCONN,HA!!!F206!VSS(23)!!!!
S!GND!J9L1!195!@baseboard_fab2_lib.baseboard_fab2(sch_1):page88_i25@mstr_sconn.sconn288_h44441003(chips)!SCONN288_H44441003_PIP-SCONN,HA!!!F206!VSS(24)!!!!
S!GND!J9L1!193!@baseboard_fab2_lib.baseboard_fab2(sch_1):page88_i25@mstr_sconn.sconn288_h44441003(chips)!SCONN288_H44441003_PIP-SCONN,HA!!!F206!VSS(25)!!!!
S!GND!J9L1!191!@baseboard_fab2_lib.baseboard_fab2(sch_1):page88_i25@mstr_sconn.sconn288_h44441003(chips)!SCONN288_H44441003_PIP-SCONN,HA!!!F206!VSS(26)!!!!
S!GND!J9L1!189!@baseboard_fab2_lib.baseboard_fab2(sch_1):page88_i25@mstr_sconn.sconn288_h44441003(chips)!SCONN288_H44441003_PIP-SCONN,HA!!!F206!VSS(27)!!!!
S!GND!J9L1!187!@baseboard_fab2_lib.baseboard_fab2(sch_1):page88_i25@mstr_sconn.sconn288_h44441003(chips)!SCONN288_H44441003_PIP-SCONN,HA!!!F206!VSS(28)!!!!
S!GND!J9L1!184!@baseboard_fab2_lib.baseboard_fab2(sch_1):page88_i25@mstr_sconn.sconn288_h44441003(chips)!SCONN288_H44441003_PIP-SCONN,HA!!!F206!VSS(29)!!!!
S!GND!J9L1!279!@baseboard_fab2_lib.baseboard_fab2(sch_1):page88_i25@mstr_sconn.sconn288_h44441003(chips)!SCONN288_H44441003_PIP-SCONN,HA!!!F206!VSS(2)!!!!
S!GND!J9L1!182!@baseboard_fab2_lib.baseboard_fab2(sch_1):page88_i25@mstr_sconn.sconn288_h44441003(chips)!SCONN288_H44441003_PIP-SCONN,HA!!!F206!VSS(30)!!!!
S!GND!J9L1!180!@baseboard_fab2_lib.baseboard_fab2(sch_1):page88_i25@mstr_sconn.sconn288_h44441003(chips)!SCONN288_H44441003_PIP-SCONN,HA!!!F206!VSS(31)!!!!
S!GND!J9L1!178!@baseboard_fab2_lib.baseboard_fab2(sch_1):page88_i25@mstr_sconn.sconn288_h44441003(chips)!SCONN288_H44441003_PIP-SCONN,HA!!!F206!VSS(32)!!!!
S!GND!J9L1!176!@baseboard_fab2_lib.baseboard_fab2(sch_1):page88_i25@mstr_sconn.sconn288_h44441003(chips)!SCONN288_H44441003_PIP-SCONN,HA!!!F206!VSS(33)!!!!
S!GND!J9L1!173!@baseboard_fab2_lib.baseboard_fab2(sch_1):page88_i25@mstr_sconn.sconn288_h44441003(chips)!SCONN288_H44441003_PIP-SCONN,HA!!!F206!VSS(34)!!!!
S!GND!J9L1!171!@baseboard_fab2_lib.baseboard_fab2(sch_1):page88_i25@mstr_sconn.sconn288_h44441003(chips)!SCONN288_H44441003_PIP-SCONN,HA!!!F206!VSS(35)!!!!
S!GND!J9L1!169!@baseboard_fab2_lib.baseboard_fab2(sch_1):page88_i25@mstr_sconn.sconn288_h44441003(chips)!SCONN288_H44441003_PIP-SCONN,HA!!!F206!VSS(36)!!!!
S!GND!J9L1!167!@baseboard_fab2_lib.baseboard_fab2(sch_1):page88_i25@mstr_sconn.sconn288_h44441003(chips)!SCONN288_H44441003_PIP-SCONN,HA!!!F206!VSS(37)!!!!
S!GND!J9L1!165!@baseboard_fab2_lib.baseboard_fab2(sch_1):page88_i25@mstr_sconn.sconn288_h44441003(chips)!SCONN288_H44441003_PIP-SCONN,HA!!!F206!VSS(38)!!!!
S!GND!J9L1!162!@baseboard_fab2_lib.baseboard_fab2(sch_1):page88_i25@mstr_sconn.sconn288_h44441003(chips)!SCONN288_H44441003_PIP-SCONN,HA!!!F206!VSS(39)!!!!
S!GND!J9L1!276!@baseboard_fab2_lib.baseboard_fab2(sch_1):page88_i25@mstr_sconn.sconn288_h44441003(chips)!SCONN288_H44441003_PIP-SCONN,HA!!!F206!VSS(3)!!!!
S!GND!J9L1!160!@baseboard_fab2_lib.baseboard_fab2(sch_1):page88_i25@mstr_sconn.sconn288_h44441003(chips)!SCONN288_H44441003_PIP-SCONN,HA!!!F206!VSS(40)!!!!
S!GND!J9L1!158!@baseboard_fab2_lib.baseboard_fab2(sch_1):page88_i25@mstr_sconn.sconn288_h44441003(chips)!SCONN288_H44441003_PIP-SCONN,HA!!!F206!VSS(41)!!!!
S!GND!J9L1!156!@baseboard_fab2_lib.baseboard_fab2(sch_1):page88_i25@mstr_sconn.sconn288_h44441003(chips)!SCONN288_H44441003_PIP-SCONN,HA!!!F206!VSS(42)!!!!
S!GND!J9L1!154!@baseboard_fab2_lib.baseboard_fab2(sch_1):page88_i25@mstr_sconn.sconn288_h44441003(chips)!SCONN288_H44441003_PIP-SCONN,HA!!!F206!VSS(43)!!!!
S!GND!J9L1!151!@baseboard_fab2_lib.baseboard_fab2(sch_1):page88_i25@mstr_sconn.sconn288_h44441003(chips)!SCONN288_H44441003_PIP-SCONN,HA!!!F206!VSS(44)!!!!
S!GND!J9L1!149!@baseboard_fab2_lib.baseboard_fab2(sch_1):page88_i25@mstr_sconn.sconn288_h44441003(chips)!SCONN288_H44441003_PIP-SCONN,HA!!!F206!VSS(45)!!!!
S!GND!J9L1!147!@baseboard_fab2_lib.baseboard_fab2(sch_1):page88_i25@mstr_sconn.sconn288_h44441003(chips)!SCONN288_H44441003_PIP-SCONN,HA!!!F206!VSS(46)!!!!
S!GND!J9L1!138!@baseboard_fab2_lib.baseboard_fab2(sch_1):page88_i25@mstr_sconn.sconn288_h44441003(chips)!SCONN288_H44441003_PIP-SCONN,HA!!!F206!VSS(47)!!!!
S!GND!J9L1!136!@baseboard_fab2_lib.baseboard_fab2(sch_1):page88_i25@mstr_sconn.sconn288_h44441003(chips)!SCONN288_H44441003_PIP-SCONN,HA!!!F206!VSS(48)!!!!
S!GND!J9L1!134!@baseboard_fab2_lib.baseboard_fab2(sch_1):page88_i25@mstr_sconn.sconn288_h44441003(chips)!SCONN288_H44441003_PIP-SCONN,HA!!!F206!VSS(49)!!!!
S!GND!J9L1!274!@baseboard_fab2_lib.baseboard_fab2(sch_1):page88_i25@mstr_sconn.sconn288_h44441003(chips)!SCONN288_H44441003_PIP-SCONN,HA!!!F206!VSS(4)!!!!
S!GND!J9L1!131!@baseboard_fab2_lib.baseboard_fab2(sch_1):page88_i25@mstr_sconn.sconn288_h44441003(chips)!SCONN288_H44441003_PIP-SCONN,HA!!!F206!VSS(50)!!!!
S!GND!J9L1!129!@baseboard_fab2_lib.baseboard_fab2(sch_1):page88_i25@mstr_sconn.sconn288_h44441003(chips)!SCONN288_H44441003_PIP-SCONN,HA!!!F206!VSS(51)!!!!
S!GND!J9L1!127!@baseboard_fab2_lib.baseboard_fab2(sch_1):page88_i25@mstr_sconn.sconn288_h44441003(chips)!SCONN288_H44441003_PIP-SCONN,HA!!!F206!VSS(52)!!!!
S!GND!J9L1!125!@baseboard_fab2_lib.baseboard_fab2(sch_1):page88_i25@mstr_sconn.sconn288_h44441003(chips)!SCONN288_H44441003_PIP-SCONN,HA!!!F206!VSS(53)!!!!
S!GND!J9L1!123!@baseboard_fab2_lib.baseboard_fab2(sch_1):page88_i25@mstr_sconn.sconn288_h44441003(chips)!SCONN288_H44441003_PIP-SCONN,HA!!!F206!VSS(54)!!!!
S!GND!J9L1!120!@baseboard_fab2_lib.baseboard_fab2(sch_1):page88_i25@mstr_sconn.sconn288_h44441003(chips)!SCONN288_H44441003_PIP-SCONN,HA!!!F206!VSS(55)!!!!
S!GND!J9L1!118!@baseboard_fab2_lib.baseboard_fab2(sch_1):page88_i25@mstr_sconn.sconn288_h44441003(chips)!SCONN288_H44441003_PIP-SCONN,HA!!!F206!VSS(56)!!!!
S!GND!J9L1!116!@baseboard_fab2_lib.baseboard_fab2(sch_1):page88_i25@mstr_sconn.sconn288_h44441003(chips)!SCONN288_H44441003_PIP-SCONN,HA!!!F206!VSS(57)!!!!
S!GND!J9L1!114!@baseboard_fab2_lib.baseboard_fab2(sch_1):page88_i25@mstr_sconn.sconn288_h44441003(chips)!SCONN288_H44441003_PIP-SCONN,HA!!!F206!VSS(58)!!!!
S!GND!J9L1!112!@baseboard_fab2_lib.baseboard_fab2(sch_1):page88_i25@mstr_sconn.sconn288_h44441003(chips)!SCONN288_H44441003_PIP-SCONN,HA!!!F206!VSS(59)!!!!
S!GND!J9L1!272!@baseboard_fab2_lib.baseboard_fab2(sch_1):page88_i25@mstr_sconn.sconn288_h44441003(chips)!SCONN288_H44441003_PIP-SCONN,HA!!!F206!VSS(5)!!!!
S!GND!J9L1!109!@baseboard_fab2_lib.baseboard_fab2(sch_1):page88_i25@mstr_sconn.sconn288_h44441003(chips)!SCONN288_H44441003_PIP-SCONN,HA!!!F206!VSS(60)!!!!
S!GND!J9L1!107!@baseboard_fab2_lib.baseboard_fab2(sch_1):page88_i25@mstr_sconn.sconn288_h44441003(chips)!SCONN288_H44441003_PIP-SCONN,HA!!!F206!VSS(61)!!!!
S!GND!J9L1!105!@baseboard_fab2_lib.baseboard_fab2(sch_1):page88_i25@mstr_sconn.sconn288_h44441003(chips)!SCONN288_H44441003_PIP-SCONN,HA!!!F206!VSS(62)!!!!
S!GND!J9L1!103!@baseboard_fab2_lib.baseboard_fab2(sch_1):page88_i25@mstr_sconn.sconn288_h44441003(chips)!SCONN288_H44441003_PIP-SCONN,HA!!!F206!VSS(63)!!!!
S!GND!J9L1!101!@baseboard_fab2_lib.baseboard_fab2(sch_1):page88_i25@mstr_sconn.sconn288_h44441003(chips)!SCONN288_H44441003_PIP-SCONN,HA!!!F206!VSS(64)!!!!
S!GND!J9L1!98!@baseboard_fab2_lib.baseboard_fab2(sch_1):page88_i25@mstr_sconn.sconn288_h44441003(chips)!SCONN288_H44441003_PIP-SCONN,HA!!!F206!VSS(65)!!!!
S!GND!J9L1!96!@baseboard_fab2_lib.baseboard_fab2(sch_1):page88_i25@mstr_sconn.sconn288_h44441003(chips)!SCONN288_H44441003_PIP-SCONN,HA!!!F206!VSS(66)!!!!
S!GND!J9L1!94!@baseboard_fab2_lib.baseboard_fab2(sch_1):page88_i25@mstr_sconn.sconn288_h44441003(chips)!SCONN288_H44441003_PIP-SCONN,HA!!!F206!VSS(67)!!!!
S!GND!J9L1!57!@baseboard_fab2_lib.baseboard_fab2(sch_1):page88_i25@mstr_sconn.sconn288_h44441003(chips)!SCONN288_H44441003_PIP-SCONN,HA!!!F206!VSS(68)!!!!
S!GND!J9L1!55!@baseboard_fab2_lib.baseboard_fab2(sch_1):page88_i25@mstr_sconn.sconn288_h44441003(chips)!SCONN288_H44441003_PIP-SCONN,HA!!!F206!VSS(69)!!!!
S!GND!J9L1!270!@baseboard_fab2_lib.baseboard_fab2(sch_1):page88_i25@mstr_sconn.sconn288_h44441003(chips)!SCONN288_H44441003_PIP-SCONN,HA!!!F206!VSS(6)!!!!
S!GND!J9L1!53!@baseboard_fab2_lib.baseboard_fab2(sch_1):page88_i25@mstr_sconn.sconn288_h44441003(chips)!SCONN288_H44441003_PIP-SCONN,HA!!!F206!VSS(70)!!!!
S!GND!J9L1!50!@baseboard_fab2_lib.baseboard_fab2(sch_1):page88_i25@mstr_sconn.sconn288_h44441003(chips)!SCONN288_H44441003_PIP-SCONN,HA!!!F206!VSS(71)!!!!
S!GND!J9L1!48!@baseboard_fab2_lib.baseboard_fab2(sch_1):page88_i25@mstr_sconn.sconn288_h44441003(chips)!SCONN288_H44441003_PIP-SCONN,HA!!!F206!VSS(72)!!!!
S!GND!J9L1!46!@baseboard_fab2_lib.baseboard_fab2(sch_1):page88_i25@mstr_sconn.sconn288_h44441003(chips)!SCONN288_H44441003_PIP-SCONN,HA!!!F206!VSS(73)!!!!
S!GND!J9L1!44!@baseboard_fab2_lib.baseboard_fab2(sch_1):page88_i25@mstr_sconn.sconn288_h44441003(chips)!SCONN288_H44441003_PIP-SCONN,HA!!!F206!VSS(74)!!!!
S!GND!J9L1!42!@baseboard_fab2_lib.baseboard_fab2(sch_1):page88_i25@mstr_sconn.sconn288_h44441003(chips)!SCONN288_H44441003_PIP-SCONN,HA!!!F206!VSS(75)!!!!
S!GND!J9L1!39!@baseboard_fab2_lib.baseboard_fab2(sch_1):page88_i25@mstr_sconn.sconn288_h44441003(chips)!SCONN288_H44441003_PIP-SCONN,HA!!!F206!VSS(76)!!!!
S!GND!J9L1!37!@baseboard_fab2_lib.baseboard_fab2(sch_1):page88_i25@mstr_sconn.sconn288_h44441003(chips)!SCONN288_H44441003_PIP-SCONN,HA!!!F206!VSS(77)!!!!
S!GND!J9L1!35!@baseboard_fab2_lib.baseboard_fab2(sch_1):page88_i25@mstr_sconn.sconn288_h44441003(chips)!SCONN288_H44441003_PIP-SCONN,HA!!!F206!VSS(78)!!!!
S!GND!J9L1!33!@baseboard_fab2_lib.baseboard_fab2(sch_1):page88_i25@mstr_sconn.sconn288_h44441003(chips)!SCONN288_H44441003_PIP-SCONN,HA!!!F206!VSS(79)!!!!
S!GND!J9L1!268!@baseboard_fab2_lib.baseboard_fab2(sch_1):page88_i25@mstr_sconn.sconn288_h44441003(chips)!SCONN288_H44441003_PIP-SCONN,HA!!!F206!VSS(7)!!!!
S!GND!J9L1!31!@baseboard_fab2_lib.baseboard_fab2(sch_1):page88_i25@mstr_sconn.sconn288_h44441003(chips)!SCONN288_H44441003_PIP-SCONN,HA!!!F206!VSS(80)!!!!
S!GND!J9L1!28!@baseboard_fab2_lib.baseboard_fab2(sch_1):page88_i25@mstr_sconn.sconn288_h44441003(chips)!SCONN288_H44441003_PIP-SCONN,HA!!!F206!VSS(81)!!!!
S!GND!J9L1!26!@baseboard_fab2_lib.baseboard_fab2(sch_1):page88_i25@mstr_sconn.sconn288_h44441003(chips)!SCONN288_H44441003_PIP-SCONN,HA!!!F206!VSS(82)!!!!
S!GND!J9L1!24!@baseboard_fab2_lib.baseboard_fab2(sch_1):page88_i25@mstr_sconn.sconn288_h44441003(chips)!SCONN288_H44441003_PIP-SCONN,HA!!!F206!VSS(83)!!!!
S!GND!J9L1!22!@baseboard_fab2_lib.baseboard_fab2(sch_1):page88_i25@mstr_sconn.sconn288_h44441003(chips)!SCONN288_H44441003_PIP-SCONN,HA!!!F206!VSS(84)!!!!
S!GND!J9L1!20!@baseboard_fab2_lib.baseboard_fab2(sch_1):page88_i25@mstr_sconn.sconn288_h44441003(chips)!SCONN288_H44441003_PIP-SCONN,HA!!!F206!VSS(85)!!!!
S!GND!J9L1!17!@baseboard_fab2_lib.baseboard_fab2(sch_1):page88_i25@mstr_sconn.sconn288_h44441003(chips)!SCONN288_H44441003_PIP-SCONN,HA!!!F206!VSS(86)!!!!
S!GND!J9L1!15!@baseboard_fab2_lib.baseboard_fab2(sch_1):page88_i25@mstr_sconn.sconn288_h44441003(chips)!SCONN288_H44441003_PIP-SCONN,HA!!!F206!VSS(87)!!!!
S!GND!J9L1!13!@baseboard_fab2_lib.baseboard_fab2(sch_1):page88_i25@mstr_sconn.sconn288_h44441003(chips)!SCONN288_H44441003_PIP-SCONN,HA!!!F206!VSS(88)!!!!
S!GND!J9L1!11!@baseboard_fab2_lib.baseboard_fab2(sch_1):page88_i25@mstr_sconn.sconn288_h44441003(chips)!SCONN288_H44441003_PIP-SCONN,HA!!!F206!VSS(89)!!!!
S!GND!J9L1!265!@baseboard_fab2_lib.baseboard_fab2(sch_1):page88_i25@mstr_sconn.sconn288_h44441003(chips)!SCONN288_H44441003_PIP-SCONN,HA!!!F206!VSS(8)!!!!
S!GND!J9L1!9!@baseboard_fab2_lib.baseboard_fab2(sch_1):page88_i25@mstr_sconn.sconn288_h44441003(chips)!SCONN288_H44441003_PIP-SCONN,HA!!!F206!VSS(90)!!!!
S!GND!J9L1!6!@baseboard_fab2_lib.baseboard_fab2(sch_1):page88_i25@mstr_sconn.sconn288_h44441003(chips)!SCONN288_H44441003_PIP-SCONN,HA!!!F206!VSS(91)!!!!
S!GND!J9L1!4!@baseboard_fab2_lib.baseboard_fab2(sch_1):page88_i25@mstr_sconn.sconn288_h44441003(chips)!SCONN288_H44441003_PIP-SCONN,HA!!!F206!VSS(92)!!!!
S!GND!J9L1!2!@baseboard_fab2_lib.baseboard_fab2(sch_1):page88_i25@mstr_sconn.sconn288_h44441003(chips)!SCONN288_H44441003_PIP-SCONN,HA!!!F206!VSS(93)!!!!
S!GND!J9L1!263!@baseboard_fab2_lib.baseboard_fab2(sch_1):page88_i25@mstr_sconn.sconn288_h44441003(chips)!SCONN288_H44441003_PIP-SCONN,HA!!!F206!VSS(9)!!!!
S!P12V_NVDIMM_KLM!J9L1!145!@baseboard_fab2_lib.baseboard_fab2(sch_1):page88_i168@mstr_sconn.sconn288_h44441003(chips)!SCONN288_H44441003_PIP-SCONN,HA!!!F205!\12v\(0)!!!!
S!P12V_NVDIMM_KLM!J9L1!1!@baseboard_fab2_lib.baseboard_fab2(sch_1):page88_i168@mstr_sconn.sconn288_h44441003(chips)!SCONN288_H44441003_PIP-SCONN,HA!!!F205!\12v\(1)!!!!
S!PVDDQ_KLM!J9L1!236!@baseboard_fab2_lib.baseboard_fab2(sch_1):page88_i168@mstr_sconn.sconn288_h44441003(chips)!SCONN288_H44441003_PIP-SCONN,HA!!!F205!VDD(0)!!!!
S!PVDDQ_KLM!J9L1!209!@baseboard_fab2_lib.baseboard_fab2(sch_1):page88_i168@mstr_sconn.sconn288_h44441003(chips)!SCONN288_H44441003_PIP-SCONN,HA!!!F205!VDD(10)!!!!
S!PVDDQ_KLM!J9L1!206!@baseboard_fab2_lib.baseboard_fab2(sch_1):page88_i168@mstr_sconn.sconn288_h44441003(chips)!SCONN288_H44441003_PIP-SCONN,HA!!!F205!VDD(11)!!!!
S!PVDDQ_KLM!J9L1!204!@baseboard_fab2_lib.baseboard_fab2(sch_1):page88_i168@mstr_sconn.sconn288_h44441003(chips)!SCONN288_H44441003_PIP-SCONN,HA!!!F205!VDD(12)!!!!
S!PVDDQ_KLM!J9L1!92!@baseboard_fab2_lib.baseboard_fab2(sch_1):page88_i168@mstr_sconn.sconn288_h44441003(chips)!SCONN288_H44441003_PIP-SCONN,HA!!!F205!VDD(13)!!!!
S!PVDDQ_KLM!J9L1!90!@baseboard_fab2_lib.baseboard_fab2(sch_1):page88_i168@mstr_sconn.sconn288_h44441003(chips)!SCONN288_H44441003_PIP-SCONN,HA!!!F205!VDD(14)!!!!
S!PVDDQ_KLM!J9L1!88!@baseboard_fab2_lib.baseboard_fab2(sch_1):page88_i168@mstr_sconn.sconn288_h44441003(chips)!SCONN288_H44441003_PIP-SCONN,HA!!!F205!VDD(15)!!!!
S!PVDDQ_KLM!J9L1!85!@baseboard_fab2_lib.baseboard_fab2(sch_1):page88_i168@mstr_sconn.sconn288_h44441003(chips)!SCONN288_H44441003_PIP-SCONN,HA!!!F205!VDD(16)!!!!
S!PVDDQ_KLM!J9L1!83!@baseboard_fab2_lib.baseboard_fab2(sch_1):page88_i168@mstr_sconn.sconn288_h44441003(chips)!SCONN288_H44441003_PIP-SCONN,HA!!!F205!VDD(17)!!!!
S!PVDDQ_KLM!J9L1!80!@baseboard_fab2_lib.baseboard_fab2(sch_1):page88_i168@mstr_sconn.sconn288_h44441003(chips)!SCONN288_H44441003_PIP-SCONN,HA!!!F205!VDD(18)!!!!
S!PVDDQ_KLM!J9L1!76!@baseboard_fab2_lib.baseboard_fab2(sch_1):page88_i168@mstr_sconn.sconn288_h44441003(chips)!SCONN288_H44441003_PIP-SCONN,HA!!!F205!VDD(19)!!!!
S!PVDDQ_KLM!J9L1!233!@baseboard_fab2_lib.baseboard_fab2(sch_1):page88_i168@mstr_sconn.sconn288_h44441003(chips)!SCONN288_H44441003_PIP-SCONN,HA!!!F205!VDD(1)!!!!
S!PVDDQ_KLM!J9L1!73!@baseboard_fab2_lib.baseboard_fab2(sch_1):page88_i168@mstr_sconn.sconn288_h44441003(chips)!SCONN288_H44441003_PIP-SCONN,HA!!!F205!VDD(20)!!!!
S!PVDDQ_KLM!J9L1!70!@baseboard_fab2_lib.baseboard_fab2(sch_1):page88_i168@mstr_sconn.sconn288_h44441003(chips)!SCONN288_H44441003_PIP-SCONN,HA!!!F205!VDD(21)!!!!
S!PVDDQ_KLM!J9L1!67!@baseboard_fab2_lib.baseboard_fab2(sch_1):page88_i168@mstr_sconn.sconn288_h44441003(chips)!SCONN288_H44441003_PIP-SCONN,HA!!!F205!VDD(22)!!!!
S!PVDDQ_KLM!J9L1!64!@baseboard_fab2_lib.baseboard_fab2(sch_1):page88_i168@mstr_sconn.sconn288_h44441003(chips)!SCONN288_H44441003_PIP-SCONN,HA!!!F205!VDD(23)!!!!
S!PVDDQ_KLM!J9L1!61!@baseboard_fab2_lib.baseboard_fab2(sch_1):page88_i168@mstr_sconn.sconn288_h44441003(chips)!SCONN288_H44441003_PIP-SCONN,HA!!!F205!VDD(24)!!!!
S!PVDDQ_KLM!J9L1!59!@baseboard_fab2_lib.baseboard_fab2(sch_1):page88_i168@mstr_sconn.sconn288_h44441003(chips)!SCONN288_H44441003_PIP-SCONN,HA!!!F205!VDD(25)!!!!
S!PVDDQ_KLM!J9L1!231!@baseboard_fab2_lib.baseboard_fab2(sch_1):page88_i168@mstr_sconn.sconn288_h44441003(chips)!SCONN288_H44441003_PIP-SCONN,HA!!!F205!VDD(2)!!!!
S!PVDDQ_KLM!J9L1!229!@baseboard_fab2_lib.baseboard_fab2(sch_1):page88_i168@mstr_sconn.sconn288_h44441003(chips)!SCONN288_H44441003_PIP-SCONN,HA!!!F205!VDD(3)!!!!
S!PVDDQ_KLM!J9L1!226!@baseboard_fab2_lib.baseboard_fab2(sch_1):page88_i168@mstr_sconn.sconn288_h44441003(chips)!SCONN288_H44441003_PIP-SCONN,HA!!!F205!VDD(4)!!!!
S!PVDDQ_KLM!J9L1!223!@baseboard_fab2_lib.baseboard_fab2(sch_1):page88_i168@mstr_sconn.sconn288_h44441003(chips)!SCONN288_H44441003_PIP-SCONN,HA!!!F205!VDD(5)!!!!
S!PVDDQ_KLM!J9L1!220!@baseboard_fab2_lib.baseboard_fab2(sch_1):page88_i168@mstr_sconn.sconn288_h44441003(chips)!SCONN288_H44441003_PIP-SCONN,HA!!!F205!VDD(6)!!!!
S!PVDDQ_KLM!J9L1!217!@baseboard_fab2_lib.baseboard_fab2(sch_1):page88_i168@mstr_sconn.sconn288_h44441003(chips)!SCONN288_H44441003_PIP-SCONN,HA!!!F205!VDD(7)!!!!
S!PVDDQ_KLM!J9L1!215!@baseboard_fab2_lib.baseboard_fab2(sch_1):page88_i168@mstr_sconn.sconn288_h44441003(chips)!SCONN288_H44441003_PIP-SCONN,HA!!!F205!VDD(8)!!!!
S!PVDDQ_KLM!J9L1!212!@baseboard_fab2_lib.baseboard_fab2(sch_1):page88_i168@mstr_sconn.sconn288_h44441003(chips)!SCONN288_H44441003_PIP-SCONN,HA!!!F205!VDD(9)!!!!
S!PVPP_KLM!J9L1!287!@baseboard_fab2_lib.baseboard_fab2(sch_1):page88_i168@mstr_sconn.sconn288_h44441003(chips)!SCONN288_H44441003_PIP-SCONN,HA!!!F205!VPP(0)!!!!
S!PVPP_KLM!J9L1!286!@baseboard_fab2_lib.baseboard_fab2(sch_1):page88_i168@mstr_sconn.sconn288_h44441003(chips)!SCONN288_H44441003_PIP-SCONN,HA!!!F205!VPP(1)!!!!
S!PVPP_KLM!J9L1!288!@baseboard_fab2_lib.baseboard_fab2(sch_1):page88_i168@mstr_sconn.sconn288_h44441003(chips)!SCONN288_H44441003_PIP-SCONN,HA!!!F205!VPP(2)!!!!
S!PVPP_KLM!J9L1!143!@baseboard_fab2_lib.baseboard_fab2(sch_1):page88_i168@mstr_sconn.sconn288_h44441003(chips)!SCONN288_H44441003_PIP-SCONN,HA!!!F205!VPP(3)!!!!
S!PVPP_KLM!J9L1!142!@baseboard_fab2_lib.baseboard_fab2(sch_1):page88_i168@mstr_sconn.sconn288_h44441003(chips)!SCONN288_H44441003_PIP-SCONN,HA!!!F205!VPP(4)!!!!
S!PVTT_KLM!J9L1!221!@baseboard_fab2_lib.baseboard_fab2(sch_1):page88_i168@mstr_sconn.sconn288_h44441003(chips)!SCONN288_H44441003_PIP-SCONN,HA!!!F205!VTT(0)!!!!
S!PVTT_KLM!J9L1!77!@baseboard_fab2_lib.baseboard_fab2(sch_1):page88_i168@mstr_sconn.sconn288_h44441003(chips)!SCONN288_H44441003_PIP-SCONN,HA!!!F205!VTT(1)!!!!
S!FM_MEZZ_PRSNTB1_N!J8E3!1!@baseboard_fab2_lib.baseboard_fab2(sch_1):page187_i119@mstr_sconn.sconn80_e67482007(chips)!SCONN80_E67482007_SM-CONN,E674A!!!F132!IO1!!!!
S!P3E_OCP_CPU0_PE3_C_TXP<7>!J8E3!10!@baseboard_fab2_lib.baseboard_fab2(sch_1):page187_i119@mstr_sconn.sconn80_e67482007(chips)!SCONN80_E67482007_SM-CONN,E674A!!!F132!IO10!!!!
S!GND!J8E3!11!@baseboard_fab2_lib.baseboard_fab2(sch_1):page187_i119@mstr_sconn.sconn80_e67482007(chips)!SCONN80_E67482007_SM-CONN,E674A!!!F132!IO11!!!!
S!P3E_OCP_CPU0_PE3_C_TXN<7>!J8E3!12!@baseboard_fab2_lib.baseboard_fab2(sch_1):page187_i119@mstr_sconn.sconn80_e67482007(chips)!SCONN80_E67482007_SM-CONN,E674A!!!F132!IO12!!!!
S!P3E_CPU0_PE3_OCP_RXN<6>!J8E3!13!@baseboard_fab2_lib.baseboard_fab2(sch_1):page187_i119@mstr_sconn.sconn80_e67482007(chips)!SCONN80_E67482007_SM-CONN,E674A!!!F132!IO13!!!!
S!GND!J8E3!14!@baseboard_fab2_lib.baseboard_fab2(sch_1):page187_i119@mstr_sconn.sconn80_e67482007(chips)!SCONN80_E67482007_SM-CONN,E674A!!!F132!IO14!!!!
S!P3E_CPU0_PE3_OCP_RXP<6>!J8E3!15!@baseboard_fab2_lib.baseboard_fab2(sch_1):page187_i119@mstr_sconn.sconn80_e67482007(chips)!SCONN80_E67482007_SM-CONN,E674A!!!F132!IO15!!!!
S!GND!J8E3!16!@baseboard_fab2_lib.baseboard_fab2(sch_1):page187_i119@mstr_sconn.sconn80_e67482007(chips)!SCONN80_E67482007_SM-CONN,E674A!!!F132!IO16!!!!
S!GND!J8E3!17!@baseboard_fab2_lib.baseboard_fab2(sch_1):page187_i119@mstr_sconn.sconn80_e67482007(chips)!SCONN80_E67482007_SM-CONN,E674A!!!F132!IO17!!!!
S!P3E_OCP_CPU0_PE3_C_TXP<6>!J8E3!18!@baseboard_fab2_lib.baseboard_fab2(sch_1):page187_i119@mstr_sconn.sconn80_e67482007(chips)!SCONN80_E67482007_SM-CONN,E674A!!!F132!IO18!!!!
S!GND!J8E3!19!@baseboard_fab2_lib.baseboard_fab2(sch_1):page187_i119@mstr_sconn.sconn80_e67482007(chips)!SCONN80_E67482007_SM-CONN,E674A!!!F132!IO19!!!!
S!P12V_STBY!J8E3!2!@baseboard_fab2_lib.baseboard_fab2(sch_1):page187_i119@mstr_sconn.sconn80_e67482007(chips)!SCONN80_E67482007_SM-CONN,E674A!!!F132!IO2!!!!
S!P3E_OCP_CPU0_PE3_C_TXN<6>!J8E3!20!@baseboard_fab2_lib.baseboard_fab2(sch_1):page187_i119@mstr_sconn.sconn80_e67482007(chips)!SCONN80_E67482007_SM-CONN,E674A!!!F132!IO20!!!!
S!P3E_CPU0_PE3_OCP_RXN<5>!J8E3!21!@baseboard_fab2_lib.baseboard_fab2(sch_1):page187_i119@mstr_sconn.sconn80_e67482007(chips)!SCONN80_E67482007_SM-CONN,E674A!!!F132!IO21!!!!
S!GND!J8E3!22!@baseboard_fab2_lib.baseboard_fab2(sch_1):page187_i119@mstr_sconn.sconn80_e67482007(chips)!SCONN80_E67482007_SM-CONN,E674A!!!F132!IO22!!!!
S!P3E_CPU0_PE3_OCP_RXP<5>!J8E3!23!@baseboard_fab2_lib.baseboard_fab2(sch_1):page187_i119@mstr_sconn.sconn80_e67482007(chips)!SCONN80_E67482007_SM-CONN,E674A!!!F132!IO23!!!!
S!GND!J8E3!24!@baseboard_fab2_lib.baseboard_fab2(sch_1):page187_i119@mstr_sconn.sconn80_e67482007(chips)!SCONN80_E67482007_SM-CONN,E674A!!!F132!IO24!!!!
S!GND!J8E3!25!@baseboard_fab2_lib.baseboard_fab2(sch_1):page187_i119@mstr_sconn.sconn80_e67482007(chips)!SCONN80_E67482007_SM-CONN,E674A!!!F132!IO25!!!!
S!P3E_OCP_CPU0_PE3_C_TXP<5>!J8E3!26!@baseboard_fab2_lib.baseboard_fab2(sch_1):page187_i119@mstr_sconn.sconn80_e67482007(chips)!SCONN80_E67482007_SM-CONN,E674A!!!F132!IO26!!!!
S!GND!J8E3!27!@baseboard_fab2_lib.baseboard_fab2(sch_1):page187_i119@mstr_sconn.sconn80_e67482007(chips)!SCONN80_E67482007_SM-CONN,E674A!!!F132!IO27!!!!
S!P3E_OCP_CPU0_PE3_C_TXN<5>!J8E3!28!@baseboard_fab2_lib.baseboard_fab2(sch_1):page187_i119@mstr_sconn.sconn80_e67482007(chips)!SCONN80_E67482007_SM-CONN,E674A!!!F132!IO28!!!!
S!P3E_CPU0_PE3_OCP_RXN<4>!J8E3!29!@baseboard_fab2_lib.baseboard_fab2(sch_1):page187_i119@mstr_sconn.sconn80_e67482007(chips)!SCONN80_E67482007_SM-CONN,E674A!!!F132!IO29!!!!
S!GND!J8E3!3!@baseboard_fab2_lib.baseboard_fab2(sch_1):page187_i119@mstr_sconn.sconn80_e67482007(chips)!SCONN80_E67482007_SM-CONN,E674A!!!F132!IO3!!!!
S!GND!J8E3!30!@baseboard_fab2_lib.baseboard_fab2(sch_1):page187_i119@mstr_sconn.sconn80_e67482007(chips)!SCONN80_E67482007_SM-CONN,E674A!!!F132!IO30!!!!
S!P3E_CPU0_PE3_OCP_RXP<4>!J8E3!31!@baseboard_fab2_lib.baseboard_fab2(sch_1):page187_i119@mstr_sconn.sconn80_e67482007(chips)!SCONN80_E67482007_SM-CONN,E674A!!!F132!IO31!!!!
S!GND!J8E3!32!@baseboard_fab2_lib.baseboard_fab2(sch_1):page187_i119@mstr_sconn.sconn80_e67482007(chips)!SCONN80_E67482007_SM-CONN,E674A!!!F132!IO32!!!!
S!GND!J8E3!33!@baseboard_fab2_lib.baseboard_fab2(sch_1):page187_i119@mstr_sconn.sconn80_e67482007(chips)!SCONN80_E67482007_SM-CONN,E674A!!!F132!IO33!!!!
S!P3E_OCP_CPU0_PE3_C_TXP<4>!J8E3!34!@baseboard_fab2_lib.baseboard_fab2(sch_1):page187_i119@mstr_sconn.sconn80_e67482007(chips)!SCONN80_E67482007_SM-CONN,E674A!!!F132!IO34!!!!
S!GND!J8E3!35!@baseboard_fab2_lib.baseboard_fab2(sch_1):page187_i119@mstr_sconn.sconn80_e67482007(chips)!SCONN80_E67482007_SM-CONN,E674A!!!F132!IO35!!!!
S!P3E_OCP_CPU0_PE3_C_TXN<4>!J8E3!36!@baseboard_fab2_lib.baseboard_fab2(sch_1):page187_i119@mstr_sconn.sconn80_e67482007(chips)!SCONN80_E67482007_SM-CONN,E674A!!!F132!IO36!!!!
S!P3E_CPU0_PE3_OCP_RXP<3>!J8E3!37!@baseboard_fab2_lib.baseboard_fab2(sch_1):page187_i119@mstr_sconn.sconn80_e67482007(chips)!SCONN80_E67482007_SM-CONN,E674A!!!F132!IO37!!!!
S!GND!J8E3!38!@baseboard_fab2_lib.baseboard_fab2(sch_1):page187_i119@mstr_sconn.sconn80_e67482007(chips)!SCONN80_E67482007_SM-CONN,E674A!!!F132!IO38!!!!
S!P3E_CPU0_PE3_OCP_RXN<3>!J8E3!39!@baseboard_fab2_lib.baseboard_fab2(sch_1):page187_i119@mstr_sconn.sconn80_e67482007(chips)!SCONN80_E67482007_SM-CONN,E674A!!!F132!IO39!!!!
S!P12V_STBY!J8E3!4!@baseboard_fab2_lib.baseboard_fab2(sch_1):page187_i119@mstr_sconn.sconn80_e67482007(chips)!SCONN80_E67482007_SM-CONN,E674A!!!F132!IO4!!!!
S!GND!J8E3!40!@baseboard_fab2_lib.baseboard_fab2(sch_1):page187_i119@mstr_sconn.sconn80_e67482007(chips)!SCONN80_E67482007_SM-CONN,E674A!!!F132!IO40!!!!
S!GND!J8E3!41!@baseboard_fab2_lib.baseboard_fab2(sch_1):page187_i119@mstr_sconn.sconn80_e67482007(chips)!SCONN80_E67482007_SM-CONN,E674A!!!F132!IO41!!!!
S!P3E_OCP_CPU0_PE3_C_TXP<3>!J8E3!42!@baseboard_fab2_lib.baseboard_fab2(sch_1):page187_i119@mstr_sconn.sconn80_e67482007(chips)!SCONN80_E67482007_SM-CONN,E674A!!!F132!IO42!!!!
S!GND!J8E3!43!@baseboard_fab2_lib.baseboard_fab2(sch_1):page187_i119@mstr_sconn.sconn80_e67482007(chips)!SCONN80_E67482007_SM-CONN,E674A!!!F132!IO43!!!!
S!P3E_OCP_CPU0_PE3_C_TXN<3>!J8E3!44!@baseboard_fab2_lib.baseboard_fab2(sch_1):page187_i119@mstr_sconn.sconn80_e67482007(chips)!SCONN80_E67482007_SM-CONN,E674A!!!F132!IO44!!!!
S!P3E_CPU0_PE3_OCP_RXP<2>!J8E3!45!@baseboard_fab2_lib.baseboard_fab2(sch_1):page187_i119@mstr_sconn.sconn80_e67482007(chips)!SCONN80_E67482007_SM-CONN,E674A!!!F132!IO45!!!!
S!GND!J8E3!46!@baseboard_fab2_lib.baseboard_fab2(sch_1):page187_i119@mstr_sconn.sconn80_e67482007(chips)!SCONN80_E67482007_SM-CONN,E674A!!!F132!IO46!!!!
S!P3E_CPU0_PE3_OCP_RXN<2>!J8E3!47!@baseboard_fab2_lib.baseboard_fab2(sch_1):page187_i119@mstr_sconn.sconn80_e67482007(chips)!SCONN80_E67482007_SM-CONN,E674A!!!F132!IO47!!!!
S!GND!J8E3!48!@baseboard_fab2_lib.baseboard_fab2(sch_1):page187_i119@mstr_sconn.sconn80_e67482007(chips)!SCONN80_E67482007_SM-CONN,E674A!!!F132!IO48!!!!
S!GND!J8E3!49!@baseboard_fab2_lib.baseboard_fab2(sch_1):page187_i119@mstr_sconn.sconn80_e67482007(chips)!SCONN80_E67482007_SM-CONN,E674A!!!F132!IO49!!!!
S!P3E_CPU0_PE3_OCP_RXP<7>!J8E3!5!@baseboard_fab2_lib.baseboard_fab2(sch_1):page187_i119@mstr_sconn.sconn80_e67482007(chips)!SCONN80_E67482007_SM-CONN,E674A!!!F132!IO5!!!!
S!P3E_OCP_CPU0_PE3_C_TXP<2>!J8E3!50!@baseboard_fab2_lib.baseboard_fab2(sch_1):page187_i119@mstr_sconn.sconn80_e67482007(chips)!SCONN80_E67482007_SM-CONN,E674A!!!F132!IO50!!!!
S!GND!J8E3!51!@baseboard_fab2_lib.baseboard_fab2(sch_1):page187_i119@mstr_sconn.sconn80_e67482007(chips)!SCONN80_E67482007_SM-CONN,E674A!!!F132!IO51!!!!
S!P3E_OCP_CPU0_PE3_C_TXN<2>!J8E3!52!@baseboard_fab2_lib.baseboard_fab2(sch_1):page187_i119@mstr_sconn.sconn80_e67482007(chips)!SCONN80_E67482007_SM-CONN,E674A!!!F132!IO52!!!!
S!P3E_CPU0_PE3_OCP_RXP<1>!J8E3!53!@baseboard_fab2_lib.baseboard_fab2(sch_1):page187_i119@mstr_sconn.sconn80_e67482007(chips)!SCONN80_E67482007_SM-CONN,E674A!!!F132!IO53!!!!
S!GND!J8E3!54!@baseboard_fab2_lib.baseboard_fab2(sch_1):page187_i119@mstr_sconn.sconn80_e67482007(chips)!SCONN80_E67482007_SM-CONN,E674A!!!F132!IO54!!!!
S!P3E_CPU0_PE3_OCP_RXN<1>!J8E3!55!@baseboard_fab2_lib.baseboard_fab2(sch_1):page187_i119@mstr_sconn.sconn80_e67482007(chips)!SCONN80_E67482007_SM-CONN,E674A!!!F132!IO55!!!!
S!GND!J8E3!56!@baseboard_fab2_lib.baseboard_fab2(sch_1):page187_i119@mstr_sconn.sconn80_e67482007(chips)!SCONN80_E67482007_SM-CONN,E674A!!!F132!IO56!!!!
S!GND!J8E3!57!@baseboard_fab2_lib.baseboard_fab2(sch_1):page187_i119@mstr_sconn.sconn80_e67482007(chips)!SCONN80_E67482007_SM-CONN,E674A!!!F132!IO57!!!!
S!P3E_OCP_CPU0_PE3_C_TXP<1>!J8E3!58!@baseboard_fab2_lib.baseboard_fab2(sch_1):page187_i119@mstr_sconn.sconn80_e67482007(chips)!SCONN80_E67482007_SM-CONN,E674A!!!F132!IO58!!!!
S!GND!J8E3!59!@baseboard_fab2_lib.baseboard_fab2(sch_1):page187_i119@mstr_sconn.sconn80_e67482007(chips)!SCONN80_E67482007_SM-CONN,E674A!!!F132!IO59!!!!
S!TP_RSVD_B1!J8E3!6!@baseboard_fab2_lib.baseboard_fab2(sch_1):page187_i119@mstr_sconn.sconn80_e67482007(chips)!SCONN80_E67482007_SM-CONN,E674A!!!F132!IO6!!!!
S!P3E_OCP_CPU0_PE3_C_TXN<1>!J8E3!60!@baseboard_fab2_lib.baseboard_fab2(sch_1):page187_i119@mstr_sconn.sconn80_e67482007(chips)!SCONN80_E67482007_SM-CONN,E674A!!!F132!IO60!!!!
S!P3E_CPU0_PE3_OCP_RXP<0>!J8E3!61!@baseboard_fab2_lib.baseboard_fab2(sch_1):page187_i119@mstr_sconn.sconn80_e67482007(chips)!SCONN80_E67482007_SM-CONN,E674A!!!F132!IO61!!!!
S!GND!J8E3!62!@baseboard_fab2_lib.baseboard_fab2(sch_1):page187_i119@mstr_sconn.sconn80_e67482007(chips)!SCONN80_E67482007_SM-CONN,E674A!!!F132!IO62!!!!
S!P3E_CPU0_PE3_OCP_RXN<0>!J8E3!63!@baseboard_fab2_lib.baseboard_fab2(sch_1):page187_i119@mstr_sconn.sconn80_e67482007(chips)!SCONN80_E67482007_SM-CONN,E674A!!!F132!IO63!!!!
S!GND!J8E3!64!@baseboard_fab2_lib.baseboard_fab2(sch_1):page187_i119@mstr_sconn.sconn80_e67482007(chips)!SCONN80_E67482007_SM-CONN,E674A!!!F132!IO64!!!!
S!GND!J8E3!65!@baseboard_fab2_lib.baseboard_fab2(sch_1):page187_i119@mstr_sconn.sconn80_e67482007(chips)!SCONN80_E67482007_SM-CONN,E674A!!!F132!IO65!!!!
S!P3E_OCP_CPU0_PE3_C_TXP<0>!J8E3!66!@baseboard_fab2_lib.baseboard_fab2(sch_1):page187_i119@mstr_sconn.sconn80_e67482007(chips)!SCONN80_E67482007_SM-CONN,E674A!!!F132!IO66!!!!
S!GND!J8E3!67!@baseboard_fab2_lib.baseboard_fab2(sch_1):page187_i119@mstr_sconn.sconn80_e67482007(chips)!SCONN80_E67482007_SM-CONN,E674A!!!F132!IO67!!!!
S!P3E_OCP_CPU0_PE3_C_TXN<0>!J8E3!68!@baseboard_fab2_lib.baseboard_fab2(sch_1):page187_i119@mstr_sconn.sconn80_e67482007(chips)!SCONN80_E67482007_SM-CONN,E674A!!!F132!IO68!!!!
S!CLK_100M_MEZZ3_DP!J8E3!69!@baseboard_fab2_lib.baseboard_fab2(sch_1):page187_i119@mstr_sconn.sconn80_e67482007(chips)!SCONN80_E67482007_SM-CONN,E674A!!!F132!IO69!!!!
S!P3E_CPU0_PE3_OCP_RXN<7>!J8E3!7!@baseboard_fab2_lib.baseboard_fab2(sch_1):page187_i119@mstr_sconn.sconn80_e67482007(chips)!SCONN80_E67482007_SM-CONN,E674A!!!F132!IO7!!!!
S!GND!J8E3!70!@baseboard_fab2_lib.baseboard_fab2(sch_1):page187_i119@mstr_sconn.sconn80_e67482007(chips)!SCONN80_E67482007_SM-CONN,E674A!!!F132!IO70!!!!
S!CLK_100M_MEZZ3_DN!J8E3!71!@baseboard_fab2_lib.baseboard_fab2(sch_1):page187_i119@mstr_sconn.sconn80_e67482007(chips)!SCONN80_E67482007_SM-CONN,E674A!!!F132!IO71!!!!
S!GND!J8E3!72!@baseboard_fab2_lib.baseboard_fab2(sch_1):page187_i119@mstr_sconn.sconn80_e67482007(chips)!SCONN80_E67482007_SM-CONN,E674A!!!F132!IO72!!!!
S!GND!J8E3!73!@baseboard_fab2_lib.baseboard_fab2(sch_1):page187_i119@mstr_sconn.sconn80_e67482007(chips)!SCONN80_E67482007_SM-CONN,E674A!!!F132!IO73!!!!
S!CLK_100M_MEZZ4_DP!J8E3!74!@baseboard_fab2_lib.baseboard_fab2(sch_1):page187_i119@mstr_sconn.sconn80_e67482007(chips)!SCONN80_E67482007_SM-CONN,E674A!!!F132!IO74!!!!
S!RST_PCIE_CPU_DEV1_R_N!J8E3!75!@baseboard_fab2_lib.baseboard_fab2(sch_1):page187_i119@mstr_sconn.sconn80_e67482007(chips)!SCONN80_E67482007_SM-CONN,E674A!!!F132!IO75!!!!
S!CLK_100M_MEZZ4_DN!J8E3!76!@baseboard_fab2_lib.baseboard_fab2(sch_1):page187_i119@mstr_sconn.sconn80_e67482007(chips)!SCONN80_E67482007_SM-CONN,E674A!!!F132!IO76!!!!
S!RST_PCIE_CPU_DEV2_R_N!J8E3!77!@baseboard_fab2_lib.baseboard_fab2(sch_1):page187_i119@mstr_sconn.sconn80_e67482007(chips)!SCONN80_E67482007_SM-CONN,E674A!!!F132!IO77!!!!
S!GND!J8E3!78!@baseboard_fab2_lib.baseboard_fab2(sch_1):page187_i119@mstr_sconn.sconn80_e67482007(chips)!SCONN80_E67482007_SM-CONN,E674A!!!F132!IO78!!!!
S!RST_PCIE_CPU_DEV3_R_N!J8E3!79!@baseboard_fab2_lib.baseboard_fab2(sch_1):page187_i119@mstr_sconn.sconn80_e67482007(chips)!SCONN80_E67482007_SM-CONN,E674A!!!F132!IO79!!!!
S!GND!J8E3!8!@baseboard_fab2_lib.baseboard_fab2(sch_1):page187_i119@mstr_sconn.sconn80_e67482007(chips)!SCONN80_E67482007_SM-CONN,E674A!!!F132!IO8!!!!
S!FM_OCP_MEZZB_PRES_N!J8E3!80!@baseboard_fab2_lib.baseboard_fab2(sch_1):page187_i119@mstr_sconn.sconn80_e67482007(chips)!SCONN80_E67482007_SM-CONN,E674A!!!F132!IO80!!!!
S!GND!J8E3!9!@baseboard_fab2_lib.baseboard_fab2(sch_1):page187_i119@mstr_sconn.sconn80_e67482007(chips)!SCONN80_E67482007_SM-CONN,E674A!!!F132!IO9!!!!
S!VR_PVCCIOMCP_CPU0_XADDR1!R3N29!1!@baseboard_fab2_lib.baseboard_fab2(sch_1):page194_i156@mstr_discrete.res(chips)!RES_0402-16K,1.0%,1/16W,CHIP,GA!!!F1063!A!!!!
S!GND!R3N29!2!@baseboard_fab2_lib.baseboard_fab2(sch_1):page194_i156@mstr_discrete.res(chips)!RES_0402-16K,1.0%,1/16W,CHIP,GA!!!F1063!B!!!!
S!A_HSC_ISTART!R1D34!1!@baseboard_fab2_lib.baseboard_fab2(sch_1):page199_i102@mstr_discrete.res(chips)!RES_0402-16K,1.0%,1/16W,CHIP,GA!!!F1064!A!!!!
S!AGND_HSC!R1D34!2!@baseboard_fab2_lib.baseboard_fab2(sch_1):page199_i102@mstr_discrete.res(chips)!RES_0402-16K,1.0%,1/16W,CHIP,GA!!!F1064!B!!!!
S!VR_PVDDQ_GHJ_XADDR2!R1G22!1!@baseboard_fab2_lib.baseboard_fab2(sch_1):page223_i78@mstr_discrete.res(chips)!RES_0402-5.36K,1.0%,1/16W,CHIPA!!!F388!A!!!!
S!GND!R1G22!2!@baseboard_fab2_lib.baseboard_fab2(sch_1):page223_i78@mstr_discrete.res(chips)!RES_0402-5.36K,1.0%,1/16W,CHIPA!!!F388!B!!!!
S!VR_PVDDQ_KLM_XADDR2!R1B15!1!@baseboard_fab2_lib.baseboard_fab2(sch_1):page226_i77@mstr_discrete.res(chips)!RES_0402-5.36K,1.0%,1/16W,CHIPA!!!F389!A!!!!
S!GND!R1B15!2!@baseboard_fab2_lib.baseboard_fab2(sch_1):page226_i77@mstr_discrete.res(chips)!RES_0402-5.36K,1.0%,1/16W,CHIPA!!!F389!B!!!!
S!FM_MEZZA_PRSNT1_N!J9B3!1!@baseboard_fab2_lib.baseboard_fab2(sch_1):page186_i336@mstr_sconn.sconn120_a28699018(chips)!SCONN120_A28699018_SM-SCONN,A2A!!!F240!IO1!!!!
S!GND!J9B3!10!@baseboard_fab2_lib.baseboard_fab2(sch_1):page186_i336@mstr_sconn.sconn120_a28699018(chips)!SCONN120_A28699018_SM-SCONN,A2A!!!F240!IO10!!!!
S!GND!J9B3!100!@baseboard_fab2_lib.baseboard_fab2(sch_1):page186_i336@mstr_sconn.sconn120_a28699018(chips)!SCONN120_A28699018_SM-SCONN,A2A!!!F240!IO100!!!!
S!P3E_CPU0_PE3_OCP_RXN<10>!J9B3!101!@baseboard_fab2_lib.baseboard_fab2(sch_1):page186_i336@mstr_sconn.sconn120_a28699018(chips)!SCONN120_A28699018_SM-SCONN,A2A!!!F240!IO101!!!!
S!GND!J9B3!102!@baseboard_fab2_lib.baseboard_fab2(sch_1):page186_i336@mstr_sconn.sconn120_a28699018(chips)!SCONN120_A28699018_SM-SCONN,A2A!!!F240!IO102!!!!
S!GND!J9B3!103!@baseboard_fab2_lib.baseboard_fab2(sch_1):page186_i336@mstr_sconn.sconn120_a28699018(chips)!SCONN120_A28699018_SM-SCONN,A2A!!!F240!IO103!!!!
S!P3E_OCP_CPU0_PE3_C_TXP<9>!J9B3!104!@baseboard_fab2_lib.baseboard_fab2(sch_1):page186_i336@mstr_sconn.sconn120_a28699018(chips)!SCONN120_A28699018_SM-SCONN,A2A!!!F240!IO104!!!!
S!GND!J9B3!105!@baseboard_fab2_lib.baseboard_fab2(sch_1):page186_i336@mstr_sconn.sconn120_a28699018(chips)!SCONN120_A28699018_SM-SCONN,A2A!!!F240!IO105!!!!
S!P3E_OCP_CPU0_PE3_C_TXN<9>!J9B3!106!@baseboard_fab2_lib.baseboard_fab2(sch_1):page186_i336@mstr_sconn.sconn120_a28699018(chips)!SCONN120_A28699018_SM-SCONN,A2A!!!F240!IO106!!!!
S!P3E_CPU0_PE3_OCP_RXP<9>!J9B3!107!@baseboard_fab2_lib.baseboard_fab2(sch_1):page186_i336@mstr_sconn.sconn120_a28699018(chips)!SCONN120_A28699018_SM-SCONN,A2A!!!F240!IO107!!!!
S!GND!J9B3!108!@baseboard_fab2_lib.baseboard_fab2(sch_1):page186_i336@mstr_sconn.sconn120_a28699018(chips)!SCONN120_A28699018_SM-SCONN,A2A!!!F240!IO108!!!!
S!P3E_CPU0_PE3_OCP_RXN<9>!J9B3!109!@baseboard_fab2_lib.baseboard_fab2(sch_1):page186_i336@mstr_sconn.sconn120_a28699018(chips)!SCONN120_A28699018_SM-SCONN,A2A!!!F240!IO109!!!!
S!GND!J9B3!11!@baseboard_fab2_lib.baseboard_fab2(sch_1):page186_i336@mstr_sconn.sconn120_a28699018(chips)!SCONN120_A28699018_SM-SCONN,A2A!!!F240!IO11!!!!
S!GND!J9B3!110!@baseboard_fab2_lib.baseboard_fab2(sch_1):page186_i336@mstr_sconn.sconn120_a28699018(chips)!SCONN120_A28699018_SM-SCONN,A2A!!!F240!IO110!!!!
S!GND!J9B3!111!@baseboard_fab2_lib.baseboard_fab2(sch_1):page186_i336@mstr_sconn.sconn120_a28699018(chips)!SCONN120_A28699018_SM-SCONN,A2A!!!F240!IO111!!!!
S!P3E_OCP_CPU0_PE3_C_TXP<8>!J9B3!112!@baseboard_fab2_lib.baseboard_fab2(sch_1):page186_i336@mstr_sconn.sconn120_a28699018(chips)!SCONN120_A28699018_SM-SCONN,A2A!!!F240!IO112!!!!
S!GND!J9B3!113!@baseboard_fab2_lib.baseboard_fab2(sch_1):page186_i336@mstr_sconn.sconn120_a28699018(chips)!SCONN120_A28699018_SM-SCONN,A2A!!!F240!IO113!!!!
S!P3E_OCP_CPU0_PE3_C_TXN<8>!J9B3!114!@baseboard_fab2_lib.baseboard_fab2(sch_1):page186_i336@mstr_sconn.sconn120_a28699018(chips)!SCONN120_A28699018_SM-SCONN,A2A!!!F240!IO114!!!!
S!P3E_CPU0_PE3_OCP_RXP<8>!J9B3!115!@baseboard_fab2_lib.baseboard_fab2(sch_1):page186_i336@mstr_sconn.sconn120_a28699018(chips)!SCONN120_A28699018_SM-SCONN,A2A!!!F240!IO115!!!!
S!GND!J9B3!116!@baseboard_fab2_lib.baseboard_fab2(sch_1):page186_i336@mstr_sconn.sconn120_a28699018(chips)!SCONN120_A28699018_SM-SCONN,A2A!!!F240!IO116!!!!
S!P3E_CPU0_PE3_OCP_RXN<8>!J9B3!117!@baseboard_fab2_lib.baseboard_fab2(sch_1):page186_i336@mstr_sconn.sconn120_a28699018(chips)!SCONN120_A28699018_SM-SCONN,A2A!!!F240!IO117!!!!
S!GND!J9B3!118!@baseboard_fab2_lib.baseboard_fab2(sch_1):page186_i336@mstr_sconn.sconn120_a28699018(chips)!SCONN120_A28699018_SM-SCONN,A2A!!!F240!IO118!!!!
S!GND!J9B3!119!@baseboard_fab2_lib.baseboard_fab2(sch_1):page186_i336@mstr_sconn.sconn120_a28699018(chips)!SCONN120_A28699018_SM-SCONN,A2A!!!F240!IO119!!!!
S!P3V3_STBY!J9B3!12!@baseboard_fab2_lib.baseboard_fab2(sch_1):page186_i336@mstr_sconn.sconn120_a28699018(chips)!SCONN120_A28699018_SM-SCONN,A2A!!!F240!IO12!!!!
S!FM_OCP_MEZZA_PRES_N!J9B3!120!@baseboard_fab2_lib.baseboard_fab2(sch_1):page186_i336@mstr_sconn.sconn120_a28699018(chips)!SCONN120_A28699018_SM-SCONN,A2A!!!F240!IO120!!!!
S!P3V3_STBY!J9B3!13!@baseboard_fab2_lib.baseboard_fab2(sch_1):page186_i336@mstr_sconn.sconn120_a28699018(chips)!SCONN120_A28699018_SM-SCONN,A2A!!!F240!IO13!!!!
S!GND!J9B3!14!@baseboard_fab2_lib.baseboard_fab2(sch_1):page186_i336@mstr_sconn.sconn120_a28699018(chips)!SCONN120_A28699018_SM-SCONN,A2A!!!F240!IO14!!!!
S!GND!J9B3!15!@baseboard_fab2_lib.baseboard_fab2(sch_1):page186_i336@mstr_sconn.sconn120_a28699018(chips)!SCONN120_A28699018_SM-SCONN,A2A!!!F240!IO15!!!!
S!GND!J9B3!16!@baseboard_fab2_lib.baseboard_fab2(sch_1):page186_i336@mstr_sconn.sconn120_a28699018(chips)!SCONN120_A28699018_SM-SCONN,A2A!!!F240!IO16!!!!
S!GND!J9B3!17!@baseboard_fab2_lib.baseboard_fab2(sch_1):page186_i336@mstr_sconn.sconn120_a28699018(chips)!SCONN120_A28699018_SM-SCONN,A2A!!!F240!IO17!!!!
S!P3V3!J9B3!18!@baseboard_fab2_lib.baseboard_fab2(sch_1):page186_i336@mstr_sconn.sconn120_a28699018(chips)!SCONN120_A28699018_SM-SCONN,A2A!!!F240!IO18!!!!
S!P3V3!J9B3!19!@baseboard_fab2_lib.baseboard_fab2(sch_1):page186_i336@mstr_sconn.sconn120_a28699018(chips)!SCONN120_A28699018_SM-SCONN,A2A!!!F240!IO19!!!!
S!P12V_STBY!J9B3!2!@baseboard_fab2_lib.baseboard_fab2(sch_1):page186_i336@mstr_sconn.sconn120_a28699018(chips)!SCONN120_A28699018_SM-SCONN,A2A!!!F240!IO2!!!!
S!P3V3!J9B3!20!@baseboard_fab2_lib.baseboard_fab2(sch_1):page186_i336@mstr_sconn.sconn120_a28699018(chips)!SCONN120_A28699018_SM-SCONN,A2A!!!F240!IO20!!!!
S!P3V3!J9B3!21!@baseboard_fab2_lib.baseboard_fab2(sch_1):page186_i336@mstr_sconn.sconn120_a28699018(chips)!SCONN120_A28699018_SM-SCONN,A2A!!!F240!IO21!!!!
S!P3V3!J9B3!22!@baseboard_fab2_lib.baseboard_fab2(sch_1):page186_i336@mstr_sconn.sconn120_a28699018(chips)!SCONN120_A28699018_SM-SCONN,A2A!!!F240!IO22!!!!
S!P3V3!J9B3!23!@baseboard_fab2_lib.baseboard_fab2(sch_1):page186_i336@mstr_sconn.sconn120_a28699018(chips)!SCONN120_A28699018_SM-SCONN,A2A!!!F240!IO23!!!!
S!P3V3!J9B3!24!@baseboard_fab2_lib.baseboard_fab2(sch_1):page186_i336@mstr_sconn.sconn120_a28699018(chips)!SCONN120_A28699018_SM-SCONN,A2A!!!F240!IO24!!!!
S!P3V3!J9B3!25!@baseboard_fab2_lib.baseboard_fab2(sch_1):page186_i336@mstr_sconn.sconn120_a28699018(chips)!SCONN120_A28699018_SM-SCONN,A2A!!!F240!IO25!!!!
S!GND!J9B3!26!@baseboard_fab2_lib.baseboard_fab2(sch_1):page186_i336@mstr_sconn.sconn120_a28699018(chips)!SCONN120_A28699018_SM-SCONN,A2A!!!F240!IO26!!!!
S!RMII_BMC_OCP_CRSDV_R!J9B3!27!@baseboard_fab2_lib.baseboard_fab2(sch_1):page186_i336@mstr_sconn.sconn120_a28699018(chips)!SCONN120_A28699018_SM-SCONN,A2A!!!F240!IO27!!!!
S!IRQ_MEZZ_LAN_ALERT_N!J9B3!28!@baseboard_fab2_lib.baseboard_fab2(sch_1):page186_i336@mstr_sconn.sconn120_a28699018(chips)!SCONN120_A28699018_SM-SCONN,A2A!!!F240!IO28!!!!
S!CLK_50M_CKMNG_OCP!J9B3!29!@baseboard_fab2_lib.baseboard_fab2(sch_1):page186_i336@mstr_sconn.sconn120_a28699018(chips)!SCONN120_A28699018_SM-SCONN,A2A!!!F240!IO29!!!!
S!P5V_STBY!J9B3!3!@baseboard_fab2_lib.baseboard_fab2(sch_1):page186_i336@mstr_sconn.sconn120_a28699018(chips)!SCONN120_A28699018_SM-SCONN,A2A!!!F240!IO3!!!!
S!SMB_OCP_FRU_STBY_LVC3_SCL!J9B3!30!@baseboard_fab2_lib.baseboard_fab2(sch_1):page186_i336@mstr_sconn.sconn120_a28699018(chips)!SCONN120_A28699018_SM-SCONN,A2A!!!F240!IO30!!!!
S!RMII_BMC_OCP_TXEN!J9B3!31!@baseboard_fab2_lib.baseboard_fab2(sch_1):page186_i336@mstr_sconn.sconn120_a28699018(chips)!SCONN120_A28699018_SM-SCONN,A2A!!!F240!IO31!!!!
S!SMB_OCP_FRU_STBY_LVC3_SDA!J9B3!32!@baseboard_fab2_lib.baseboard_fab2(sch_1):page186_i336@mstr_sconn.sconn120_a28699018(chips)!SCONN120_A28699018_SM-SCONN,A2A!!!F240!IO32!!!!
S!RST_PCIE_CPU_DEV0_R_N!J9B3!33!@baseboard_fab2_lib.baseboard_fab2(sch_1):page186_i336@mstr_sconn.sconn120_a28699018(chips)!SCONN120_A28699018_SM-SCONN,A2A!!!F240!IO33!!!!
S!FM_PE_OCP_WAKE_N!J9B3!34!@baseboard_fab2_lib.baseboard_fab2(sch_1):page186_i336@mstr_sconn.sconn120_a28699018(chips)!SCONN120_A28699018_SM-SCONN,A2A!!!F240!IO34!!!!
S!SMB_OCP_LAN_STBY_LVC3_SCL!J9B3!35!@baseboard_fab2_lib.baseboard_fab2(sch_1):page186_i336@mstr_sconn.sconn120_a28699018(chips)!SCONN120_A28699018_SM-SCONN,A2A!!!F240!IO35!!!!
S!RMII_BMC_OCP_RXER_R!J9B3!36!@baseboard_fab2_lib.baseboard_fab2(sch_1):page186_i336@mstr_sconn.sconn120_a28699018(chips)!SCONN120_A28699018_SM-SCONN,A2A!!!F240!IO36!!!!
S!SMB_OCP_LAN_STBY_LVC3_SDA!J9B3!37!@baseboard_fab2_lib.baseboard_fab2(sch_1):page186_i336@mstr_sconn.sconn120_a28699018(chips)!SCONN120_A28699018_SM-SCONN,A2A!!!F240!IO37!!!!
S!GND!J9B3!38!@baseboard_fab2_lib.baseboard_fab2(sch_1):page186_i336@mstr_sconn.sconn120_a28699018(chips)!SCONN120_A28699018_SM-SCONN,A2A!!!F240!IO38!!!!
S!GND!J9B3!39!@baseboard_fab2_lib.baseboard_fab2(sch_1):page186_i336@mstr_sconn.sconn120_a28699018(chips)!SCONN120_A28699018_SM-SCONN,A2A!!!F240!IO39!!!!
S!P12V_STBY!J9B3!4!@baseboard_fab2_lib.baseboard_fab2(sch_1):page186_i336@mstr_sconn.sconn120_a28699018(chips)!SCONN120_A28699018_SM-SCONN,A2A!!!F240!IO4!!!!
S!RMII_BMC_OCP_TXD0!J9B3!40!@baseboard_fab2_lib.baseboard_fab2(sch_1):page186_i336@mstr_sconn.sconn120_a28699018(chips)!SCONN120_A28699018_SM-SCONN,A2A!!!F240!IO40!!!!
S!GND!J9B3!41!@baseboard_fab2_lib.baseboard_fab2(sch_1):page186_i336@mstr_sconn.sconn120_a28699018(chips)!SCONN120_A28699018_SM-SCONN,A2A!!!F240!IO41!!!!
S!RMII_BMC_OCP_TXD1!J9B3!42!@baseboard_fab2_lib.baseboard_fab2(sch_1):page186_i336@mstr_sconn.sconn120_a28699018(chips)!SCONN120_A28699018_SM-SCONN,A2A!!!F240!IO42!!!!
S!RMII_BMC_OCP_RXD0_R!J9B3!43!@baseboard_fab2_lib.baseboard_fab2(sch_1):page186_i336@mstr_sconn.sconn120_a28699018(chips)!SCONN120_A28699018_SM-SCONN,A2A!!!F240!IO43!!!!
S!GND!J9B3!44!@baseboard_fab2_lib.baseboard_fab2(sch_1):page186_i336@mstr_sconn.sconn120_a28699018(chips)!SCONN120_A28699018_SM-SCONN,A2A!!!F240!IO44!!!!
S!RMII_BMC_OCP_RXD1_R!J9B3!45!@baseboard_fab2_lib.baseboard_fab2(sch_1):page186_i336@mstr_sconn.sconn120_a28699018(chips)!SCONN120_A28699018_SM-SCONN,A2A!!!F240!IO45!!!!
S!GND!J9B3!46!@baseboard_fab2_lib.baseboard_fab2(sch_1):page186_i336@mstr_sconn.sconn120_a28699018(chips)!SCONN120_A28699018_SM-SCONN,A2A!!!F240!IO46!!!!
S!GND!J9B3!47!@baseboard_fab2_lib.baseboard_fab2(sch_1):page186_i336@mstr_sconn.sconn120_a28699018(chips)!SCONN120_A28699018_SM-SCONN,A2A!!!F240!IO47!!!!
S!CLK_100M_MEZZ1_DP!J9B3!48!@baseboard_fab2_lib.baseboard_fab2(sch_1):page186_i336@mstr_sconn.sconn120_a28699018(chips)!SCONN120_A28699018_SM-SCONN,A2A!!!F240!IO48!!!!
S!GND!J9B3!49!@baseboard_fab2_lib.baseboard_fab2(sch_1):page186_i336@mstr_sconn.sconn120_a28699018(chips)!SCONN120_A28699018_SM-SCONN,A2A!!!F240!IO49!!!!
S!P5V_STBY!J9B3!5!@baseboard_fab2_lib.baseboard_fab2(sch_1):page186_i336@mstr_sconn.sconn120_a28699018(chips)!SCONN120_A28699018_SM-SCONN,A2A!!!F240!IO5!!!!
S!CLK_100M_MEZZ1_DN!J9B3!50!@baseboard_fab2_lib.baseboard_fab2(sch_1):page186_i336@mstr_sconn.sconn120_a28699018(chips)!SCONN120_A28699018_SM-SCONN,A2A!!!F240!IO50!!!!
S!CLK_100M_MEZZ2_DP!J9B3!51!@baseboard_fab2_lib.baseboard_fab2(sch_1):page186_i336@mstr_sconn.sconn120_a28699018(chips)!SCONN120_A28699018_SM-SCONN,A2A!!!F240!IO51!!!!
S!GND!J9B3!52!@baseboard_fab2_lib.baseboard_fab2(sch_1):page186_i336@mstr_sconn.sconn120_a28699018(chips)!SCONN120_A28699018_SM-SCONN,A2A!!!F240!IO52!!!!
S!CLK_100M_MEZZ2_DN!J9B3!53!@baseboard_fab2_lib.baseboard_fab2(sch_1):page186_i336@mstr_sconn.sconn120_a28699018(chips)!SCONN120_A28699018_SM-SCONN,A2A!!!F240!IO53!!!!
S!GND!J9B3!54!@baseboard_fab2_lib.baseboard_fab2(sch_1):page186_i336@mstr_sconn.sconn120_a28699018(chips)!SCONN120_A28699018_SM-SCONN,A2A!!!F240!IO54!!!!
S!GND!J9B3!55!@baseboard_fab2_lib.baseboard_fab2(sch_1):page186_i336@mstr_sconn.sconn120_a28699018(chips)!SCONN120_A28699018_SM-SCONN,A2A!!!F240!IO55!!!!
S!P3E_OCP_CPU0_PE3_C_TXP<15>!J9B3!56!@baseboard_fab2_lib.baseboard_fab2(sch_1):page186_i336@mstr_sconn.sconn120_a28699018(chips)!SCONN120_A28699018_SM-SCONN,A2A!!!F240!IO56!!!!
S!GND!J9B3!57!@baseboard_fab2_lib.baseboard_fab2(sch_1):page186_i336@mstr_sconn.sconn120_a28699018(chips)!SCONN120_A28699018_SM-SCONN,A2A!!!F240!IO57!!!!
S!P3E_OCP_CPU0_PE3_C_TXN<15>!J9B3!58!@baseboard_fab2_lib.baseboard_fab2(sch_1):page186_i336@mstr_sconn.sconn120_a28699018(chips)!SCONN120_A28699018_SM-SCONN,A2A!!!F240!IO58!!!!
S!P3E_CPU0_PE3_OCP_RXP<15>!J9B3!59!@baseboard_fab2_lib.baseboard_fab2(sch_1):page186_i336@mstr_sconn.sconn120_a28699018(chips)!SCONN120_A28699018_SM-SCONN,A2A!!!F240!IO59!!!!
S!P12V_STBY!J9B3!6!@baseboard_fab2_lib.baseboard_fab2(sch_1):page186_i336@mstr_sconn.sconn120_a28699018(chips)!SCONN120_A28699018_SM-SCONN,A2A!!!F240!IO6!!!!
S!GND!J9B3!60!@baseboard_fab2_lib.baseboard_fab2(sch_1):page186_i336@mstr_sconn.sconn120_a28699018(chips)!SCONN120_A28699018_SM-SCONN,A2A!!!F240!IO60!!!!
S!P3E_CPU0_PE3_OCP_RXN<15>!J9B3!61!@baseboard_fab2_lib.baseboard_fab2(sch_1):page186_i336@mstr_sconn.sconn120_a28699018(chips)!SCONN120_A28699018_SM-SCONN,A2A!!!F240!IO61!!!!
S!GND!J9B3!62!@baseboard_fab2_lib.baseboard_fab2(sch_1):page186_i336@mstr_sconn.sconn120_a28699018(chips)!SCONN120_A28699018_SM-SCONN,A2A!!!F240!IO62!!!!
S!GND!J9B3!63!@baseboard_fab2_lib.baseboard_fab2(sch_1):page186_i336@mstr_sconn.sconn120_a28699018(chips)!SCONN120_A28699018_SM-SCONN,A2A!!!F240!IO63!!!!
S!P3E_OCP_CPU0_PE3_C_TXP<14>!J9B3!64!@baseboard_fab2_lib.baseboard_fab2(sch_1):page186_i336@mstr_sconn.sconn120_a28699018(chips)!SCONN120_A28699018_SM-SCONN,A2A!!!F240!IO64!!!!
S!GND!J9B3!65!@baseboard_fab2_lib.baseboard_fab2(sch_1):page186_i336@mstr_sconn.sconn120_a28699018(chips)!SCONN120_A28699018_SM-SCONN,A2A!!!F240!IO65!!!!
S!P3E_OCP_CPU0_PE3_C_TXN<14>!J9B3!66!@baseboard_fab2_lib.baseboard_fab2(sch_1):page186_i336@mstr_sconn.sconn120_a28699018(chips)!SCONN120_A28699018_SM-SCONN,A2A!!!F240!IO66!!!!
S!P3E_CPU0_PE3_OCP_RXP<14>!J9B3!67!@baseboard_fab2_lib.baseboard_fab2(sch_1):page186_i336@mstr_sconn.sconn120_a28699018(chips)!SCONN120_A28699018_SM-SCONN,A2A!!!F240!IO67!!!!
S!GND!J9B3!68!@baseboard_fab2_lib.baseboard_fab2(sch_1):page186_i336@mstr_sconn.sconn120_a28699018(chips)!SCONN120_A28699018_SM-SCONN,A2A!!!F240!IO68!!!!
S!P3E_CPU0_PE3_OCP_RXN<14>!J9B3!69!@baseboard_fab2_lib.baseboard_fab2(sch_1):page186_i336@mstr_sconn.sconn120_a28699018(chips)!SCONN120_A28699018_SM-SCONN,A2A!!!F240!IO69!!!!
S!P5V_STBY!J9B3!7!@baseboard_fab2_lib.baseboard_fab2(sch_1):page186_i336@mstr_sconn.sconn120_a28699018(chips)!SCONN120_A28699018_SM-SCONN,A2A!!!F240!IO7!!!!
S!GND!J9B3!70!@baseboard_fab2_lib.baseboard_fab2(sch_1):page186_i336@mstr_sconn.sconn120_a28699018(chips)!SCONN120_A28699018_SM-SCONN,A2A!!!F240!IO70!!!!
S!GND!J9B3!71!@baseboard_fab2_lib.baseboard_fab2(sch_1):page186_i336@mstr_sconn.sconn120_a28699018(chips)!SCONN120_A28699018_SM-SCONN,A2A!!!F240!IO71!!!!
S!P3E_OCP_CPU0_PE3_C_TXP<13>!J9B3!72!@baseboard_fab2_lib.baseboard_fab2(sch_1):page186_i336@mstr_sconn.sconn120_a28699018(chips)!SCONN120_A28699018_SM-SCONN,A2A!!!F240!IO72!!!!
S!GND!J9B3!73!@baseboard_fab2_lib.baseboard_fab2(sch_1):page186_i336@mstr_sconn.sconn120_a28699018(chips)!SCONN120_A28699018_SM-SCONN,A2A!!!F240!IO73!!!!
S!P3E_OCP_CPU0_PE3_C_TXN<13>!J9B3!74!@baseboard_fab2_lib.baseboard_fab2(sch_1):page186_i336@mstr_sconn.sconn120_a28699018(chips)!SCONN120_A28699018_SM-SCONN,A2A!!!F240!IO74!!!!
S!P3E_CPU0_PE3_OCP_RXP<13>!J9B3!75!@baseboard_fab2_lib.baseboard_fab2(sch_1):page186_i336@mstr_sconn.sconn120_a28699018(chips)!SCONN120_A28699018_SM-SCONN,A2A!!!F240!IO75!!!!
S!GND!J9B3!76!@baseboard_fab2_lib.baseboard_fab2(sch_1):page186_i336@mstr_sconn.sconn120_a28699018(chips)!SCONN120_A28699018_SM-SCONN,A2A!!!F240!IO76!!!!
S!P3E_CPU0_PE3_OCP_RXN<13>!J9B3!77!@baseboard_fab2_lib.baseboard_fab2(sch_1):page186_i336@mstr_sconn.sconn120_a28699018(chips)!SCONN120_A28699018_SM-SCONN,A2A!!!F240!IO77!!!!
S!GND!J9B3!78!@baseboard_fab2_lib.baseboard_fab2(sch_1):page186_i336@mstr_sconn.sconn120_a28699018(chips)!SCONN120_A28699018_SM-SCONN,A2A!!!F240!IO78!!!!
S!GND!J9B3!79!@baseboard_fab2_lib.baseboard_fab2(sch_1):page186_i336@mstr_sconn.sconn120_a28699018(chips)!SCONN120_A28699018_SM-SCONN,A2A!!!F240!IO79!!!!
S!GND!J9B3!8!@baseboard_fab2_lib.baseboard_fab2(sch_1):page186_i336@mstr_sconn.sconn120_a28699018(chips)!SCONN120_A28699018_SM-SCONN,A2A!!!F240!IO8!!!!
S!P3E_OCP_CPU0_PE3_C_TXP<12>!J9B3!80!@baseboard_fab2_lib.baseboard_fab2(sch_1):page186_i336@mstr_sconn.sconn120_a28699018(chips)!SCONN120_A28699018_SM-SCONN,A2A!!!F240!IO80!!!!
S!GND!J9B3!81!@baseboard_fab2_lib.baseboard_fab2(sch_1):page186_i336@mstr_sconn.sconn120_a28699018(chips)!SCONN120_A28699018_SM-SCONN,A2A!!!F240!IO81!!!!
S!P3E_OCP_CPU0_PE3_C_TXN<12>!J9B3!82!@baseboard_fab2_lib.baseboard_fab2(sch_1):page186_i336@mstr_sconn.sconn120_a28699018(chips)!SCONN120_A28699018_SM-SCONN,A2A!!!F240!IO82!!!!
S!P3E_CPU0_PE3_OCP_RXP<12>!J9B3!83!@baseboard_fab2_lib.baseboard_fab2(sch_1):page186_i336@mstr_sconn.sconn120_a28699018(chips)!SCONN120_A28699018_SM-SCONN,A2A!!!F240!IO83!!!!
S!GND!J9B3!84!@baseboard_fab2_lib.baseboard_fab2(sch_1):page186_i336@mstr_sconn.sconn120_a28699018(chips)!SCONN120_A28699018_SM-SCONN,A2A!!!F240!IO84!!!!
S!P3E_CPU0_PE3_OCP_RXN<12>!J9B3!85!@baseboard_fab2_lib.baseboard_fab2(sch_1):page186_i336@mstr_sconn.sconn120_a28699018(chips)!SCONN120_A28699018_SM-SCONN,A2A!!!F240!IO85!!!!
S!GND!J9B3!86!@baseboard_fab2_lib.baseboard_fab2(sch_1):page186_i336@mstr_sconn.sconn120_a28699018(chips)!SCONN120_A28699018_SM-SCONN,A2A!!!F240!IO86!!!!
S!GND!J9B3!87!@baseboard_fab2_lib.baseboard_fab2(sch_1):page186_i336@mstr_sconn.sconn120_a28699018(chips)!SCONN120_A28699018_SM-SCONN,A2A!!!F240!IO87!!!!
S!P3E_OCP_CPU0_PE3_C_TXP<11>!J9B3!88!@baseboard_fab2_lib.baseboard_fab2(sch_1):page186_i336@mstr_sconn.sconn120_a28699018(chips)!SCONN120_A28699018_SM-SCONN,A2A!!!F240!IO88!!!!
S!GND!J9B3!89!@baseboard_fab2_lib.baseboard_fab2(sch_1):page186_i336@mstr_sconn.sconn120_a28699018(chips)!SCONN120_A28699018_SM-SCONN,A2A!!!F240!IO89!!!!
S!GND!J9B3!9!@baseboard_fab2_lib.baseboard_fab2(sch_1):page186_i336@mstr_sconn.sconn120_a28699018(chips)!SCONN120_A28699018_SM-SCONN,A2A!!!F240!IO9!!!!
S!P3E_OCP_CPU0_PE3_C_TXN<11>!J9B3!90!@baseboard_fab2_lib.baseboard_fab2(sch_1):page186_i336@mstr_sconn.sconn120_a28699018(chips)!SCONN120_A28699018_SM-SCONN,A2A!!!F240!IO90!!!!
S!P3E_CPU0_PE3_OCP_RXP<11>!J9B3!91!@baseboard_fab2_lib.baseboard_fab2(sch_1):page186_i336@mstr_sconn.sconn120_a28699018(chips)!SCONN120_A28699018_SM-SCONN,A2A!!!F240!IO91!!!!
S!GND!J9B3!92!@baseboard_fab2_lib.baseboard_fab2(sch_1):page186_i336@mstr_sconn.sconn120_a28699018(chips)!SCONN120_A28699018_SM-SCONN,A2A!!!F240!IO92!!!!
S!P3E_CPU0_PE3_OCP_RXN<11>!J9B3!93!@baseboard_fab2_lib.baseboard_fab2(sch_1):page186_i336@mstr_sconn.sconn120_a28699018(chips)!SCONN120_A28699018_SM-SCONN,A2A!!!F240!IO93!!!!
S!GND!J9B3!94!@baseboard_fab2_lib.baseboard_fab2(sch_1):page186_i336@mstr_sconn.sconn120_a28699018(chips)!SCONN120_A28699018_SM-SCONN,A2A!!!F240!IO94!!!!
S!GND!J9B3!95!@baseboard_fab2_lib.baseboard_fab2(sch_1):page186_i336@mstr_sconn.sconn120_a28699018(chips)!SCONN120_A28699018_SM-SCONN,A2A!!!F240!IO95!!!!
S!P3E_OCP_CPU0_PE3_C_TXP<10>!J9B3!96!@baseboard_fab2_lib.baseboard_fab2(sch_1):page186_i336@mstr_sconn.sconn120_a28699018(chips)!SCONN120_A28699018_SM-SCONN,A2A!!!F240!IO96!!!!
S!GND!J9B3!97!@baseboard_fab2_lib.baseboard_fab2(sch_1):page186_i336@mstr_sconn.sconn120_a28699018(chips)!SCONN120_A28699018_SM-SCONN,A2A!!!F240!IO97!!!!
S!P3E_OCP_CPU0_PE3_C_TXN<10>!J9B3!98!@baseboard_fab2_lib.baseboard_fab2(sch_1):page186_i336@mstr_sconn.sconn120_a28699018(chips)!SCONN120_A28699018_SM-SCONN,A2A!!!F240!IO98!!!!
S!P3E_CPU0_PE3_OCP_RXP<10>!J9B3!99!@baseboard_fab2_lib.baseboard_fab2(sch_1):page186_i336@mstr_sconn.sconn120_a28699018(chips)!SCONN120_A28699018_SM-SCONN,A2A!!!F240!IO99!!!!
S!XDP_CPU_TCK_BUF!Q9A1!5!@baseboard_fab2_lib.baseboard_fab2(sch_1):page111_i94@mstr_discrete.npn_dual(chips)!NPN_DUAL_SSOPLF-MBT3904,EMPTY,A!1!!F1998!B(0)!!!!
S!P3V3!Q9A1!3!@baseboard_fab2_lib.baseboard_fab2(sch_1):page111_i94@mstr_discrete.npn_dual(chips)!NPN_DUAL_SSOPLF-MBT3904,EMPTY,A!1!!F1998!C(0)!!!!
S!XDP_CPU_TCK0!Q9A1!4!@baseboard_fab2_lib.baseboard_fab2(sch_1):page111_i94@mstr_discrete.npn_dual(chips)!NPN_DUAL_SSOPLF-MBT3904,EMPTY,A!1!!F1998!E(0)!!!!
S!XDP_CPU_TCK_BUF!Q9A1!2!@baseboard_fab2_lib.baseboard_fab2(sch_1):page111_i93@mstr_discrete.npn_dual(chips)!NPN_DUAL_SSOPLF-MBT3904,EMPTY,A!1!!F1997!B(0)!!!!
S!XDP_CPU_TCK_BUF!Q9A1!6!@baseboard_fab2_lib.baseboard_fab2(sch_1):page111_i93@mstr_discrete.npn_dual(chips)!NPN_DUAL_SSOPLF-MBT3904,EMPTY,A!1!!F1997!C(0)!!!!
S!XDP_CPU_GTL_TCK_R2!Q9A1!1!@baseboard_fab2_lib.baseboard_fab2(sch_1):page111_i93@mstr_discrete.npn_dual(chips)!NPN_DUAL_SSOPLF-MBT3904,EMPTY,A!1!!F1997!E(0)!!!!
S!FAN_PWM_OUT_SYS0_R!CR1E1!2!@baseboard_fab2_lib.baseboard_fab2(sch_1):page161_i50@mstr_discrete.diode(chips)!DIODE_SM-SDMK0340L,EMPTY,H7179A!!!F2216!A!!!!
S!P5V_STBY!CR1E1!1!@baseboard_fab2_lib.baseboard_fab2(sch_1):page161_i50@mstr_discrete.diode(chips)!DIODE_SM-SDMK0340L,EMPTY,H7179A!!!F2216!C!!!!
S!FAN_PWM_OUT_SYS1_R!CR1B1!2!@baseboard_fab2_lib.baseboard_fab2(sch_1):page161_i64@mstr_discrete.diode(chips)!DIODE_SM-SDMK0340L,EMPTY,H7179A!!!F2217!A!!!!
S!P5V_STBY!CR1B1!1!@baseboard_fab2_lib.baseboard_fab2(sch_1):page161_i64@mstr_discrete.diode(chips)!DIODE_SM-SDMK0340L,EMPTY,H7179A!!!F2217!C!!!!
S!GND!RM8D1!1!@baseboard_fab2_lib.baseboard_fab2(sch_1):page184_i104@mstr_misc.standoff(chips)!STANDOFF_TH1-SO,H72821-001!!!F66!IO1!!!!
S!P5V_HDD_SATA!J8A4!1!@baseboard_fab2_lib.baseboard_fab2(sch_1):page172_i25@mstr_conn.conn4_h73295001(chips)!CONN4_H73295001_PIP-CONN,H7329A!!!F2244!IO1!!!!
S!GND!J8A4!2!@baseboard_fab2_lib.baseboard_fab2(sch_1):page172_i25@mstr_conn.conn4_h73295001(chips)!CONN4_H73295001_PIP-CONN,H7329A!!!F2244!IO2!!!!
S!GND!J8A4!3!@baseboard_fab2_lib.baseboard_fab2(sch_1):page172_i25@mstr_conn.conn4_h73295001(chips)!CONN4_H73295001_PIP-CONN,H7329A!!!F2244!IO3!!!!
S!P12V_HDD_SATA!J8A4!4!@baseboard_fab2_lib.baseboard_fab2(sch_1):page172_i25@mstr_conn.conn4_h73295001(chips)!CONN4_H73295001_PIP-CONN,H7329A!!!F2244!IO4!!!!
S!FAN_TACH1_CPU1_D2!CR1F2!2!@baseboard_fab2_lib.baseboard_fab2(sch_1):page161_i133@mstr_discrete.diode(chips)!DIODE_SM-SDMK0340L,IC,H71799-0A!!!F2212!A!!!!
S!FAN_TACH1_CPU1_D1!CR1F2!1!@baseboard_fab2_lib.baseboard_fab2(sch_1):page161_i133@mstr_discrete.diode(chips)!DIODE_SM-SDMK0340L,IC,H71799-0A!!!F2212!C!!!!
S!FAN_TACH3_CPU1_D2!CR1B3!2!@baseboard_fab2_lib.baseboard_fab2(sch_1):page161_i123@mstr_discrete.diode(chips)!DIODE_SM-SDMK0340L,IC,H71799-0A!!!F2214!A!!!!
S!FAN_TACH3_CPU1_D1!CR1B3!1!@baseboard_fab2_lib.baseboard_fab2(sch_1):page161_i123@mstr_discrete.diode(chips)!DIODE_SM-SDMK0340L,IC,H71799-0A!!!F2214!C!!!!
S!FAN_TACH0_CPU0_D2!CR1F1!2!@baseboard_fab2_lib.baseboard_fab2(sch_1):page161_i42@mstr_discrete.diode(chips)!DIODE_SM-SDMK0340L,IC,H71799-0A!!!F2213!A!!!!
S!FAN_TACH0_CPU0_D1!CR1F1!1!@baseboard_fab2_lib.baseboard_fab2(sch_1):page161_i42@mstr_discrete.diode(chips)!DIODE_SM-SDMK0340L,IC,H71799-0A!!!F2213!C!!!!
S!FAN_TACH2_CPU1_D2!CR1B2!2!@baseboard_fab2_lib.baseboard_fab2(sch_1):page161_i62@mstr_discrete.diode(chips)!DIODE_SM-SDMK0340L,IC,H71799-0A!!!F2215!A!!!!
S!FAN_TACH2_CPU1_D1!CR1B2!1!@baseboard_fab2_lib.baseboard_fab2(sch_1):page161_i62@mstr_discrete.diode(chips)!DIODE_SM-SDMK0340L,IC,H71799-0A!!!F2215!C!!!!
S!FM_MATED_IN_N!CR1F4!2!@baseboard_fab2_lib.baseboard_fab2(sch_1):page181_i178@mstr_discrete.diode(chips)!DIODE_SM-SDMK0340L,IC,H71799-0A!!!F2210!A!!!!
S!FM_MATED_IN_D1_N!CR1F4!1!@baseboard_fab2_lib.baseboard_fab2(sch_1):page181_i178@mstr_discrete.diode(chips)!DIODE_SM-SDMK0340L,IC,H71799-0A!!!F2210!C!!!!
S!FM_MATED_IN_D1_N!CR1F3!2!@baseboard_fab2_lib.baseboard_fab2(sch_1):page181_i180@mstr_discrete.diode(chips)!DIODE_SM-SDMK0340L,IC,H71799-0A!!!F2211!A!!!!
S!FM_MATED_IN_D2_N!CR1F3!1!@baseboard_fab2_lib.baseboard_fab2(sch_1):page181_i180@mstr_discrete.diode(chips)!DIODE_SM-SDMK0340L,IC,H71799-0A!!!F2211!C!!!!
S!P3V3_STBY!R6P32!1!@baseboard_fab2_lib.baseboard_fab2(sch_1):page201_i102@mstr_discrete.res(chips)!RES_0402-2.0K,1%,1/16W,EMPTY,GA!!!F1036!A!!!!
S!SMB_VR_STBY_LVC3_SDA!R6P32!2!@baseboard_fab2_lib.baseboard_fab2(sch_1):page201_i102@mstr_discrete.res(chips)!RES_0402-2.0K,1%,1/16W,EMPTY,GA!!!F1036!B!!!!
S!P3V3_STBY!R6P37!1!@baseboard_fab2_lib.baseboard_fab2(sch_1):page201_i103@mstr_discrete.res(chips)!RES_0402-2.0K,1%,1/16W,EMPTY,GA!!!F1035!A!!!!
S!SMB_VR_STBY_LVC3_SCL!R6P37!2!@baseboard_fab2_lib.baseboard_fab2(sch_1):page201_i103@mstr_discrete.res(chips)!RES_0402-2.0K,1%,1/16W,EMPTY,GA!!!F1035!B!!!!
S!A_HSC_ISET!R1D16!1!@baseboard_fab2_lib.baseboard_fab2(sch_1):page199_i85@mstr_discrete.res(chips)!RES_0402-69.8K,1%,1/16W,CHIP,GA!!!F315!A!!!!
S!A_HSC_ISET_S2!R1D16!2!@baseboard_fab2_lib.baseboard_fab2(sch_1):page199_i85@mstr_discrete.res(chips)!RES_0402-69.8K,1%,1/16W,CHIP,GA!!!F315!B!!!!
S!A_HSC_OV!R1D43!1!@baseboard_fab2_lib.baseboard_fab2(sch_1):page199_i9@mstr_discrete.res(chips)!RES_0402-7.5K,1%,1/16W,CHIP,G2A!!!F314!A!!!!
S!AGND_HSC!R1D43!2!@baseboard_fab2_lib.baseboard_fab2(sch_1):page199_i9@mstr_discrete.res(chips)!RES_0402-7.5K,1%,1/16W,CHIP,G2A!!!F314!B!!!!
S!A_HSC_CSOUT!R1D14!1!@baseboard_fab2_lib.baseboard_fab2(sch_1):page200_i173@mstr_discrete.res(chips)!RES_0402-105.0K,1%,1/16W,CHIP,A!!!F1111!A!!!!
S!A_HSC_LOW!R1D14!2!@baseboard_fab2_lib.baseboard_fab2(sch_1):page200_i173@mstr_discrete.res(chips)!RES_0402-105.0K,1%,1/16W,CHIP,A!!!F1111!B!!!!
S!P5V_STBY!R9A6!1!@baseboard_fab2_lib.baseboard_fab2(sch_1):page155_i191@mstr_discrete.res(chips)!RES_0402-20.0K,1%,1/16W,EMPTY,A!!!F901!A!!!!
S!SPA_5V_SIN_SW!R9A6!2!@baseboard_fab2_lib.baseboard_fab2(sch_1):page155_i191@mstr_discrete.res(chips)!RES_0402-20.0K,1%,1/16W,EMPTY,A!!!F901!B!!!!
S!P5V_STBY!R1L37!1!@baseboard_fab2_lib.baseboard_fab2(sch_1):page177_i33@mstr_discrete.res(chips)!RES_0402-301.0,1%,1/16W,CHIP,GA!!!F759!A!!!!
S!LED_P5V_STBY!R1L37!2!@baseboard_fab2_lib.baseboard_fab2(sch_1):page177_i33@mstr_discrete.res(chips)!RES_0402-301.0,1%,1/16W,CHIP,GA!!!F759!B!!!!
S!A_HSC_C!C1E2!1!@baseboard_fab2_lib.baseboard_fab2(sch_1):page200_i155@mstr_discrete.cap(chips)!CAP_1206-0.068UF,50V,20%,X7R,1A!!!F2286!A!!!!
S!GND!C1E2!2!@baseboard_fab2_lib.baseboard_fab2(sch_1):page200_i155@mstr_discrete.cap(chips)!CAP_1206-0.068UF,50V,20%,X7R,1A!!!F2286!B!!!!
S!P3V3_STBY_PLD_D!J7G2!1!@baseboard_fab2_lib.baseboard_fab2(sch_1):page189_i47@mstr_conn.conn8_c77962004(chips)!CONN8_C77962004_PIP-CONN,C7796A!!!F2235!IO1!!!!
S!JTAG_TDO_R!J7G2!2!@baseboard_fab2_lib.baseboard_fab2(sch_1):page189_i47@mstr_conn.conn8_c77962004(chips)!CONN8_C77962004_PIP-CONN,C7796A!!!F2235!IO2!!!!
S!JTAG_TDI_R!J7G2!3!@baseboard_fab2_lib.baseboard_fab2(sch_1):page189_i47@mstr_conn.conn8_c77962004(chips)!CONN8_C77962004_PIP-CONN,C7796A!!!F2235!IO3!!!!
S!JTAG_TRST_N!J7G2!4!@baseboard_fab2_lib.baseboard_fab2(sch_1):page189_i47@mstr_conn.conn8_c77962004(chips)!CONN8_C77962004_PIP-CONN,C7796A!!!F2235!IO4!!!!
S!PWRGD_P3V3_STBY!J7G2!5!@baseboard_fab2_lib.baseboard_fab2(sch_1):page189_i47@mstr_conn.conn8_c77962004(chips)!CONN8_C77962004_PIP-CONN,C7796A!!!F2235!IO5!!!!
S!JTAG_TMS_R!J7G2!6!@baseboard_fab2_lib.baseboard_fab2(sch_1):page189_i47@mstr_conn.conn8_c77962004(chips)!CONN8_C77962004_PIP-CONN,C7796A!!!F2235!IO6!!!!
S!GND!J7G2!7!@baseboard_fab2_lib.baseboard_fab2(sch_1):page189_i47@mstr_conn.conn8_c77962004(chips)!CONN8_C77962004_PIP-CONN,C7796A!!!F2235!IO7!!!!
S!JTAG_TCK_R!J7G2!8!@baseboard_fab2_lib.baseboard_fab2(sch_1):page189_i47@mstr_conn.conn8_c77962004(chips)!CONN8_C77962004_PIP-CONN,C7796A!!!F2235!IO8!!!!
S!PVPP_KLM!C6L8!1!@baseboard_fab2_lib.baseboard_fab2(sch_1):page234_i210@mstr_discrete.capp(chips)!CAPP_7343-220UF,4V,20%,POSCAP,A!!!F4104!A!!!!
S!GND!C6L8!2!@baseboard_fab2_lib.baseboard_fab2(sch_1):page234_i210@mstr_discrete.capp(chips)!CAPP_7343-220UF,4V,20%,POSCAP,A!!!F4104!B!!!!
S!PVPP_ABC!C4T3!1!@baseboard_fab2_lib.baseboard_fab2(sch_1):page231_i217@mstr_discrete.capp(chips)!CAPP_7343-220UF,4V,20%,POSCAP,A!!!F4105!A!!!!
S!GND!C4T3!2!@baseboard_fab2_lib.baseboard_fab2(sch_1):page231_i217@mstr_discrete.capp(chips)!CAPP_7343-220UF,4V,20%,POSCAP,A!!!F4105!B!!!!
S!PVPP_DEF!C4M1!1!@baseboard_fab2_lib.baseboard_fab2(sch_1):page232_i267@mstr_discrete.capp(chips)!CAPP_7343-220UF,4V,20%,POSCAP,A!!!F4106!A!!!!
S!GND!C4M1!2!@baseboard_fab2_lib.baseboard_fab2(sch_1):page232_i267@mstr_discrete.capp(chips)!CAPP_7343-220UF,4V,20%,POSCAP,A!!!F4106!B!!!!
S!PVPP_GHJ!C4F11!1!@baseboard_fab2_lib.baseboard_fab2(sch_1):page233_i256@mstr_discrete.capp(chips)!CAPP_7343-220UF,4V,20%,POSCAP,A!!!F4107!A!!!!
S!GND!C4F11!2!@baseboard_fab2_lib.baseboard_fab2(sch_1):page233_i256@mstr_discrete.capp(chips)!CAPP_7343-220UF,4V,20%,POSCAP,A!!!F4107!B!!!!
S!P1V8_MCP_CPU1!C3F1!1!@baseboard_fab2_lib.baseboard_fab2(sch_1):page193_i140@mstr_discrete.cap(chips)!CAP_0603-47UF,4V,20%,X5R,60243A!!!F2730!A!!!!
S!GND!C3F1!2!@baseboard_fab2_lib.baseboard_fab2(sch_1):page193_i140@mstr_discrete.cap(chips)!CAP_0603-47UF,4V,20%,X5R,60243A!!!F2730!B!!!!
S!P1V8_MCP_CPU1!C4F2!1!@baseboard_fab2_lib.baseboard_fab2(sch_1):page193_i141@mstr_discrete.cap(chips)!CAP_0603-47UF,4V,20%,X5R,60243A!!!F2727!A!!!!
S!GND!C4F2!2!@baseboard_fab2_lib.baseboard_fab2(sch_1):page193_i141@mstr_discrete.cap(chips)!CAP_0603-47UF,4V,20%,X5R,60243A!!!F2727!B!!!!
S!P1V8_MCP_CPU0!C3T2!1!@baseboard_fab2_lib.baseboard_fab2(sch_1):page194_i150@mstr_discrete.cap(chips)!CAP_0603-47UF,4V,20%,X5R,60243A!!!F2728!A!!!!
S!GND!C3T2!2!@baseboard_fab2_lib.baseboard_fab2(sch_1):page194_i150@mstr_discrete.cap(chips)!CAP_0603-47UF,4V,20%,X5R,60243A!!!F2728!B!!!!
S!P1V8_MCP_CPU0!C3T1!1!@baseboard_fab2_lib.baseboard_fab2(sch_1):page194_i149@mstr_discrete.cap(chips)!CAP_0603-47UF,4V,20%,X5R,60243A!!!F2729!A!!!!
S!GND!C3T1!2!@baseboard_fab2_lib.baseboard_fab2(sch_1):page194_i149@mstr_discrete.cap(chips)!CAP_0603-47UF,4V,20%,X5R,60243A!!!F2729!B!!!!
S!PVDDQ_ABC!C5T1!1!@baseboard_fab2_lib.baseboard_fab2(sch_1):page217_i212@mstr_discrete.cap(chips)!CAP_0603-47UF,4V,20%,X5R,60243A!!!F2710!A!!!!
S!GND!C5T1!2!@baseboard_fab2_lib.baseboard_fab2(sch_1):page217_i212@mstr_discrete.cap(chips)!CAP_0603-47UF,4V,20%,X5R,60243A!!!F2710!B!!!!
S!PVDDQ_ABC!C5T4!1!@baseboard_fab2_lib.baseboard_fab2(sch_1):page217_i211@mstr_discrete.cap(chips)!CAP_0603-47UF,4V,20%,X5R,60243A!!!F2707!A!!!!
S!GND!C5T4!2!@baseboard_fab2_lib.baseboard_fab2(sch_1):page217_i211@mstr_discrete.cap(chips)!CAP_0603-47UF,4V,20%,X5R,60243A!!!F2707!B!!!!
S!PVDDQ_ABC!C5T13!1!@baseboard_fab2_lib.baseboard_fab2(sch_1):page217_i210@mstr_discrete.cap(chips)!CAP_0603-47UF,4V,20%,X5R,60243A!!!F2706!A!!!!
S!GND!C5T13!2!@baseboard_fab2_lib.baseboard_fab2(sch_1):page217_i210@mstr_discrete.cap(chips)!CAP_0603-47UF,4V,20%,X5R,60243A!!!F2706!B!!!!
S!PVDDQ_ABC!C5U11!1!@baseboard_fab2_lib.baseboard_fab2(sch_1):page217_i209@mstr_discrete.cap(chips)!CAP_0603-47UF,4V,20%,X5R,60243A!!!F2705!A!!!!
S!GND!C5U11!2!@baseboard_fab2_lib.baseboard_fab2(sch_1):page217_i209@mstr_discrete.cap(chips)!CAP_0603-47UF,4V,20%,X5R,60243A!!!F2705!B!!!!
S!PVDDQ_ABC!C5T2!1!@baseboard_fab2_lib.baseboard_fab2(sch_1):page217_i208@mstr_discrete.cap(chips)!CAP_0603-47UF,4V,20%,X5R,60243A!!!F2709!A!!!!
S!GND!C5T2!2!@baseboard_fab2_lib.baseboard_fab2(sch_1):page217_i208@mstr_discrete.cap(chips)!CAP_0603-47UF,4V,20%,X5R,60243A!!!F2709!B!!!!
S!PVDDQ_GHJ!C2G15!1!@baseboard_fab2_lib.baseboard_fab2(sch_1):page225_i200@mstr_discrete.cap(chips)!CAP_0603-47UF,4V,20%,X5R,60243A!!!F2731!A!!!!
S!GND!C2G15!2!@baseboard_fab2_lib.baseboard_fab2(sch_1):page225_i200@mstr_discrete.cap(chips)!CAP_0603-47UF,4V,20%,X5R,60243A!!!F2731!B!!!!
S!PVDDQ_GHJ!C2F1!1!@baseboard_fab2_lib.baseboard_fab2(sch_1):page225_i201@mstr_discrete.cap(chips)!CAP_0603-47UF,4V,20%,X5R,60243A!!!F2734!A!!!!
S!GND!C2F1!2!@baseboard_fab2_lib.baseboard_fab2(sch_1):page225_i201@mstr_discrete.cap(chips)!CAP_0603-47UF,4V,20%,X5R,60243A!!!F2734!B!!!!
S!PVDDQ_GHJ!C8T1!1!@baseboard_fab2_lib.baseboard_fab2(sch_1):page225_i202@mstr_discrete.cap(chips)!CAP_0603-47UF,4V,20%,X5R,60243A!!!F2693!A!!!!
S!GND!C8T1!2!@baseboard_fab2_lib.baseboard_fab2(sch_1):page225_i202@mstr_discrete.cap(chips)!CAP_0603-47UF,4V,20%,X5R,60243A!!!F2693!B!!!!
S!PVDDQ_GHJ!C8U9!1!@baseboard_fab2_lib.baseboard_fab2(sch_1):page225_i203@mstr_discrete.cap(chips)!CAP_0603-47UF,4V,20%,X5R,60243A!!!F2688!A!!!!
S!GND!C8U9!2!@baseboard_fab2_lib.baseboard_fab2(sch_1):page225_i203@mstr_discrete.cap(chips)!CAP_0603-47UF,4V,20%,X5R,60243A!!!F2688!B!!!!
S!PVDDQ_GHJ!C8T11!1!@baseboard_fab2_lib.baseboard_fab2(sch_1):page225_i204@mstr_discrete.cap(chips)!CAP_0603-47UF,4V,20%,X5R,60243A!!!F2689!A!!!!
S!GND!C8T11!2!@baseboard_fab2_lib.baseboard_fab2(sch_1):page225_i204@mstr_discrete.cap(chips)!CAP_0603-47UF,4V,20%,X5R,60243A!!!F2689!B!!!!
S!PVDDQ_KLM!C7M5!1!@baseboard_fab2_lib.baseboard_fab2(sch_1):page228_i202@mstr_discrete.cap(chips)!CAP_0603-47UF,4V,20%,X5R,60243A!!!F2702!A!!!!
S!GND!C7M5!2!@baseboard_fab2_lib.baseboard_fab2(sch_1):page228_i202@mstr_discrete.cap(chips)!CAP_0603-47UF,4V,20%,X5R,60243A!!!F2702!B!!!!
S!PVDDQ_KLM!C8M10!1!@baseboard_fab2_lib.baseboard_fab2(sch_1):page228_i203@mstr_discrete.cap(chips)!CAP_0603-47UF,4V,20%,X5R,60243A!!!F2695!A!!!!
S!GND!C8M10!2!@baseboard_fab2_lib.baseboard_fab2(sch_1):page228_i203@mstr_discrete.cap(chips)!CAP_0603-47UF,4V,20%,X5R,60243A!!!F2695!B!!!!
S!PVDDQ_KLM!C2B2!1!@baseboard_fab2_lib.baseboard_fab2(sch_1):page228_i204@mstr_discrete.cap(chips)!CAP_0603-47UF,4V,20%,X5R,60243A!!!F2735!A!!!!
S!GND!C2B2!2!@baseboard_fab2_lib.baseboard_fab2(sch_1):page228_i204@mstr_discrete.cap(chips)!CAP_0603-47UF,4V,20%,X5R,60243A!!!F2735!B!!!!
S!PVDDQ_KLM!C8M9!1!@baseboard_fab2_lib.baseboard_fab2(sch_1):page228_i205@mstr_discrete.cap(chips)!CAP_0603-47UF,4V,20%,X5R,60243A!!!F2696!A!!!!
S!GND!C8M9!2!@baseboard_fab2_lib.baseboard_fab2(sch_1):page228_i205@mstr_discrete.cap(chips)!CAP_0603-47UF,4V,20%,X5R,60243A!!!F2696!B!!!!
S!PVDDQ_KLM!C8M2!1!@baseboard_fab2_lib.baseboard_fab2(sch_1):page228_i206@mstr_discrete.cap(chips)!CAP_0603-47UF,4V,20%,X5R,60243A!!!F2698!A!!!!
S!GND!C8M2!2!@baseboard_fab2_lib.baseboard_fab2(sch_1):page228_i206@mstr_discrete.cap(chips)!CAP_0603-47UF,4V,20%,X5R,60243A!!!F2698!B!!!!
S!PVDDQ_DEF!C5M3!1!@baseboard_fab2_lib.baseboard_fab2(sch_1):page220_i199@mstr_discrete.cap(chips)!CAP_0603-47UF,4V,20%,X5R,60243A!!!F2715!A!!!!
S!GND!C5M3!2!@baseboard_fab2_lib.baseboard_fab2(sch_1):page220_i199@mstr_discrete.cap(chips)!CAP_0603-47UF,4V,20%,X5R,60243A!!!F2715!B!!!!
S!PVDDQ_DEF!C5M11!1!@baseboard_fab2_lib.baseboard_fab2(sch_1):page220_i200@mstr_discrete.cap(chips)!CAP_0603-47UF,4V,20%,X5R,60243A!!!F2712!A!!!!
S!GND!C5M11!2!@baseboard_fab2_lib.baseboard_fab2(sch_1):page220_i200@mstr_discrete.cap(chips)!CAP_0603-47UF,4V,20%,X5R,60243A!!!F2712!B!!!!
S!PVTT_ABC!C5U16!1!@baseboard_fab2_lib.baseboard_fab2(sch_1):page221_i52@mstr_discrete.cap(chips)!CAP_0603-47UF,4V,20%,X5R,60243A!!!F2703!A!!!!
S!GND!C5U16!2!@baseboard_fab2_lib.baseboard_fab2(sch_1):page221_i52@mstr_discrete.cap(chips)!CAP_0603-47UF,4V,20%,X5R,60243A!!!F2703!B!!!!
S!PVTT_ABC!C5U12!1!@baseboard_fab2_lib.baseboard_fab2(sch_1):page221_i50@mstr_discrete.cap(chips)!CAP_0603-47UF,4V,20%,X5R,60243A!!!F2704!A!!!!
S!GND!C5U12!2!@baseboard_fab2_lib.baseboard_fab2(sch_1):page221_i50@mstr_discrete.cap(chips)!CAP_0603-47UF,4V,20%,X5R,60243A!!!F2704!B!!!!
S!PVTT_ABC!C5T3!1!@baseboard_fab2_lib.baseboard_fab2(sch_1):page221_i51@mstr_discrete.cap(chips)!CAP_0603-47UF,4V,20%,X5R,60243A!!!F2708!A!!!!
S!GND!C5T3!2!@baseboard_fab2_lib.baseboard_fab2(sch_1):page221_i51@mstr_discrete.cap(chips)!CAP_0603-47UF,4V,20%,X5R,60243A!!!F2708!B!!!!
S!PVTT_DEF!C5L4!1!@baseboard_fab2_lib.baseboard_fab2(sch_1):page222_i47@mstr_discrete.cap(chips)!CAP_0603-47UF,4V,20%,X5R,60243A!!!F2718!A!!!!
S!GND!C5L4!2!@baseboard_fab2_lib.baseboard_fab2(sch_1):page222_i47@mstr_discrete.cap(chips)!CAP_0603-47UF,4V,20%,X5R,60243A!!!F2718!B!!!!
S!PVTT_DEF!C5M13!1!@baseboard_fab2_lib.baseboard_fab2(sch_1):page222_i48@mstr_discrete.cap(chips)!CAP_0603-47UF,4V,20%,X5R,60243A!!!F2711!A!!!!
S!GND!C5M13!2!@baseboard_fab2_lib.baseboard_fab2(sch_1):page222_i48@mstr_discrete.cap(chips)!CAP_0603-47UF,4V,20%,X5R,60243A!!!F2711!B!!!!
S!PVTT_DEF!C5L5!1!@baseboard_fab2_lib.baseboard_fab2(sch_1):page222_i49@mstr_discrete.cap(chips)!CAP_0603-47UF,4V,20%,X5R,60243A!!!F2717!A!!!!
S!GND!C5L5!2!@baseboard_fab2_lib.baseboard_fab2(sch_1):page222_i49@mstr_discrete.cap(chips)!CAP_0603-47UF,4V,20%,X5R,60243A!!!F2717!B!!!!
S!PVTT_GHJ!C2F2!1!@baseboard_fab2_lib.baseboard_fab2(sch_1):page229_i47@mstr_discrete.cap(chips)!CAP_0603-47UF,4V,20%,X5R,60243A!!!F2733!A!!!!
S!GND!C2F2!2!@baseboard_fab2_lib.baseboard_fab2(sch_1):page229_i47@mstr_discrete.cap(chips)!CAP_0603-47UF,4V,20%,X5R,60243A!!!F2733!B!!!!
S!PVTT_GHJ!C8T3!1!@baseboard_fab2_lib.baseboard_fab2(sch_1):page229_i48@mstr_discrete.cap(chips)!CAP_0603-47UF,4V,20%,X5R,60243A!!!F2691!A!!!!
S!GND!C8T3!2!@baseboard_fab2_lib.baseboard_fab2(sch_1):page229_i48@mstr_discrete.cap(chips)!CAP_0603-47UF,4V,20%,X5R,60243A!!!F2691!B!!!!
S!PVTT_GHJ!C8U10!1!@baseboard_fab2_lib.baseboard_fab2(sch_1):page229_i49@mstr_discrete.cap(chips)!CAP_0603-47UF,4V,20%,X5R,60243A!!!F2687!A!!!!
S!GND!C8U10!2!@baseboard_fab2_lib.baseboard_fab2(sch_1):page229_i49@mstr_discrete.cap(chips)!CAP_0603-47UF,4V,20%,X5R,60243A!!!F2687!B!!!!
S!PVTT_KLM!C8M12!1!@baseboard_fab2_lib.baseboard_fab2(sch_1):page230_i47@mstr_discrete.cap(chips)!CAP_0603-47UF,4V,20%,X5R,60243A!!!F2694!A!!!!
S!GND!C8M12!2!@baseboard_fab2_lib.baseboard_fab2(sch_1):page230_i47@mstr_discrete.cap(chips)!CAP_0603-47UF,4V,20%,X5R,60243A!!!F2694!B!!!!
S!PVTT_KLM!C8L3!1!@baseboard_fab2_lib.baseboard_fab2(sch_1):page230_i48@mstr_discrete.cap(chips)!CAP_0603-47UF,4V,20%,X5R,60243A!!!F2701!A!!!!
S!GND!C8L3!2!@baseboard_fab2_lib.baseboard_fab2(sch_1):page230_i48@mstr_discrete.cap(chips)!CAP_0603-47UF,4V,20%,X5R,60243A!!!F2701!B!!!!
S!PVTT_KLM!C8L4!1!@baseboard_fab2_lib.baseboard_fab2(sch_1):page230_i49@mstr_discrete.cap(chips)!CAP_0603-47UF,4V,20%,X5R,60243A!!!F2700!A!!!!
S!GND!C8L4!2!@baseboard_fab2_lib.baseboard_fab2(sch_1):page230_i49@mstr_discrete.cap(chips)!CAP_0603-47UF,4V,20%,X5R,60243A!!!F2700!B!!!!
S!PVDDQ_DEF!C4M5!1!@baseboard_fab2_lib.baseboard_fab2(sch_1):page220_i196@mstr_discrete.cap(chips)!CAP_0603-47UF,4V,20%,X5R,60243A!!!F2726!A!!!!
S!GND!C4M5!2!@baseboard_fab2_lib.baseboard_fab2(sch_1):page220_i196@mstr_discrete.cap(chips)!CAP_0603-47UF,4V,20%,X5R,60243A!!!F2726!B!!!!
S!PVDDQ_DEF!C5M9!1!@baseboard_fab2_lib.baseboard_fab2(sch_1):page220_i195@mstr_discrete.cap(chips)!CAP_0603-47UF,4V,20%,X5R,60243A!!!F2714!A!!!!
S!GND!C5M9!2!@baseboard_fab2_lib.baseboard_fab2(sch_1):page220_i195@mstr_discrete.cap(chips)!CAP_0603-47UF,4V,20%,X5R,60243A!!!F2714!B!!!!
S!PVDDQ_DEF!C5M10!1!@baseboard_fab2_lib.baseboard_fab2(sch_1):page220_i198@mstr_discrete.cap(chips)!CAP_0603-47UF,4V,20%,X5R,60243A!!!F2713!A!!!!
S!GND!C5M10!2!@baseboard_fab2_lib.baseboard_fab2(sch_1):page220_i198@mstr_discrete.cap(chips)!CAP_0603-47UF,4V,20%,X5R,60243A!!!F2713!B!!!!
S!PVDDQ_ABC!C5F2!1!@baseboard_fab2_lib.baseboard_fab2(sch_1):page217_i205@mstr_discrete.cap(chips)!CAP_0603-47UF,4V,20%,X5R,60243A!!!F2721!A!!!!
S!GND!C5F2!2!@baseboard_fab2_lib.baseboard_fab2(sch_1):page217_i205@mstr_discrete.cap(chips)!CAP_0603-47UF,4V,20%,X5R,60243A!!!F2721!B!!!!
S!PVDDQ_ABC!C5F1!1!@baseboard_fab2_lib.baseboard_fab2(sch_1):page217_i206@mstr_discrete.cap(chips)!CAP_0603-47UF,4V,20%,X5R,60243A!!!F2722!A!!!!
S!GND!C5F1!2!@baseboard_fab2_lib.baseboard_fab2(sch_1):page217_i206@mstr_discrete.cap(chips)!CAP_0603-47UF,4V,20%,X5R,60243A!!!F2722!B!!!!
S!PVDDQ_ABC!C5G10!1!@baseboard_fab2_lib.baseboard_fab2(sch_1):page217_i207@mstr_discrete.cap(chips)!CAP_0603-47UF,4V,20%,X5R,60243A!!!F2720!A!!!!
S!GND!C5G10!2!@baseboard_fab2_lib.baseboard_fab2(sch_1):page217_i207@mstr_discrete.cap(chips)!CAP_0603-47UF,4V,20%,X5R,60243A!!!F2720!B!!!!
S!PVDDQ_DEF!C5L15!1!@baseboard_fab2_lib.baseboard_fab2(sch_1):page220_i192@mstr_discrete.cap(chips)!CAP_0603-47UF,4V,20%,X5R,60243A!!!F2716!A!!!!
S!GND!C5L15!2!@baseboard_fab2_lib.baseboard_fab2(sch_1):page220_i192@mstr_discrete.cap(chips)!CAP_0603-47UF,4V,20%,X5R,60243A!!!F2716!B!!!!
S!PVDDQ_DEF!C5B2!1!@baseboard_fab2_lib.baseboard_fab2(sch_1):page220_i197@mstr_discrete.cap(chips)!CAP_0603-47UF,4V,20%,X5R,60243A!!!F2723!A!!!!
S!GND!C5B2!2!@baseboard_fab2_lib.baseboard_fab2(sch_1):page220_i197@mstr_discrete.cap(chips)!CAP_0603-47UF,4V,20%,X5R,60243A!!!F2723!B!!!!
S!PVDDQ_DEF!C5A5!1!@baseboard_fab2_lib.baseboard_fab2(sch_1):page220_i193@mstr_discrete.cap(chips)!CAP_0603-47UF,4V,20%,X5R,60243A!!!F2725!A!!!!
S!GND!C5A5!2!@baseboard_fab2_lib.baseboard_fab2(sch_1):page220_i193@mstr_discrete.cap(chips)!CAP_0603-47UF,4V,20%,X5R,60243A!!!F2725!B!!!!
S!PVDDQ_DEF!C5B1!1!@baseboard_fab2_lib.baseboard_fab2(sch_1):page220_i194@mstr_discrete.cap(chips)!CAP_0603-47UF,4V,20%,X5R,60243A!!!F2724!A!!!!
S!GND!C5B1!2!@baseboard_fab2_lib.baseboard_fab2(sch_1):page220_i194@mstr_discrete.cap(chips)!CAP_0603-47UF,4V,20%,X5R,60243A!!!F2724!B!!!!
S!PVDDQ_GHJ!C8U13!1!@baseboard_fab2_lib.baseboard_fab2(sch_1):page225_i199@mstr_discrete.cap(chips)!CAP_0603-47UF,4V,20%,X5R,60243A!!!F2686!A!!!!
S!GND!C8U13!2!@baseboard_fab2_lib.baseboard_fab2(sch_1):page225_i199@mstr_discrete.cap(chips)!CAP_0603-47UF,4V,20%,X5R,60243A!!!F2686!B!!!!
S!PVDDQ_GHJ!C8T4!1!@baseboard_fab2_lib.baseboard_fab2(sch_1):page225_i196@mstr_discrete.cap(chips)!CAP_0603-47UF,4V,20%,X5R,60243A!!!F2690!A!!!!
S!GND!C8T4!2!@baseboard_fab2_lib.baseboard_fab2(sch_1):page225_i196@mstr_discrete.cap(chips)!CAP_0603-47UF,4V,20%,X5R,60243A!!!F2690!B!!!!
S!PVDDQ_GHJ!C2G8!1!@baseboard_fab2_lib.baseboard_fab2(sch_1):page225_i197@mstr_discrete.cap(chips)!CAP_0603-47UF,4V,20%,X5R,60243A!!!F2732!A!!!!
S!GND!C2G8!2!@baseboard_fab2_lib.baseboard_fab2(sch_1):page225_i197@mstr_discrete.cap(chips)!CAP_0603-47UF,4V,20%,X5R,60243A!!!F2732!B!!!!
S!PVDDQ_GHJ!C8T2!1!@baseboard_fab2_lib.baseboard_fab2(sch_1):page225_i198@mstr_discrete.cap(chips)!CAP_0603-47UF,4V,20%,X5R,60243A!!!F2692!A!!!!
S!GND!C8T2!2!@baseboard_fab2_lib.baseboard_fab2(sch_1):page225_i198@mstr_discrete.cap(chips)!CAP_0603-47UF,4V,20%,X5R,60243A!!!F2692!B!!!!
S!PVDDQ_KLM!C8L12!1!@baseboard_fab2_lib.baseboard_fab2(sch_1):page228_i201@mstr_discrete.cap(chips)!CAP_0603-47UF,4V,20%,X5R,60243A!!!F2699!A!!!!
S!GND!C8L12!2!@baseboard_fab2_lib.baseboard_fab2(sch_1):page228_i201@mstr_discrete.cap(chips)!CAP_0603-47UF,4V,20%,X5R,60243A!!!F2699!B!!!!
S!PVDDQ_KLM!C8M8!1!@baseboard_fab2_lib.baseboard_fab2(sch_1):page228_i198@mstr_discrete.cap(chips)!CAP_0603-47UF,4V,20%,X5R,60243A!!!F2697!A!!!!
S!GND!C8M8!2!@baseboard_fab2_lib.baseboard_fab2(sch_1):page228_i198@mstr_discrete.cap(chips)!CAP_0603-47UF,4V,20%,X5R,60243A!!!F2697!B!!!!
S!PVDDQ_KLM!C2A5!1!@baseboard_fab2_lib.baseboard_fab2(sch_1):page228_i199@mstr_discrete.cap(chips)!CAP_0603-47UF,4V,20%,X5R,60243A!!!F2737!A!!!!
S!GND!C2A5!2!@baseboard_fab2_lib.baseboard_fab2(sch_1):page228_i199@mstr_discrete.cap(chips)!CAP_0603-47UF,4V,20%,X5R,60243A!!!F2737!B!!!!
S!PVDDQ_KLM!C2B1!1!@baseboard_fab2_lib.baseboard_fab2(sch_1):page228_i200@mstr_discrete.cap(chips)!CAP_0603-47UF,4V,20%,X5R,60243A!!!F2736!A!!!!
S!GND!C2B1!2!@baseboard_fab2_lib.baseboard_fab2(sch_1):page228_i200@mstr_discrete.cap(chips)!CAP_0603-47UF,4V,20%,X5R,60243A!!!F2736!B!!!!
S!PVDDQ_ABC!C5G19!1!@baseboard_fab2_lib.baseboard_fab2(sch_1):page217_i213@mstr_discrete.cap(chips)!CAP_0603-47UF,4V,20%,X5R,60243A!!!F2719!A!!!!
S!GND!C5G19!2!@baseboard_fab2_lib.baseboard_fab2(sch_1):page217_i213@mstr_discrete.cap(chips)!CAP_0603-47UF,4V,20%,X5R,60243A!!!F2719!B!!!!
S!P12V_STBY!C4F6!1!@baseboard_fab2_lib.baseboard_fab2(sch_1):page195_i82@mstr_discrete.capp(chips)!CAPP_4040LF-470UF,16V,20%,ALUMA!!!F4108!A!!!!
S!GND!C4F6!2!@baseboard_fab2_lib.baseboard_fab2(sch_1):page195_i82@mstr_discrete.capp(chips)!CAPP_4040LF-470UF,16V,20%,ALUMA!!!F4108!B!!!!
S!P12V_STBY!C4B13!1!@baseboard_fab2_lib.baseboard_fab2(sch_1):page195_i83@mstr_discrete.capp(chips)!CAPP_4040LF-470UF,16V,20%,ALUMA!!!F4109!A!!!!
S!GND!C4B13!2!@baseboard_fab2_lib.baseboard_fab2(sch_1):page195_i83@mstr_discrete.capp(chips)!CAPP_4040LF-470UF,16V,20%,ALUMA!!!F4109!B!!!!
S!P12V_STBY!C1B14!1!@baseboard_fab2_lib.baseboard_fab2(sch_1):page195_i84@mstr_discrete.capp(chips)!CAPP_4040LF-470UF,16V,20%,ALUMA!!!F4111!A!!!!
S!GND!C1B14!2!@baseboard_fab2_lib.baseboard_fab2(sch_1):page195_i84@mstr_discrete.capp(chips)!CAPP_4040LF-470UF,16V,20%,ALUMA!!!F4111!B!!!!
S!P12V_STBY!C1F7!1!@baseboard_fab2_lib.baseboard_fab2(sch_1):page195_i85@mstr_discrete.capp(chips)!CAPP_4040LF-470UF,16V,20%,ALUMA!!!F4110!A!!!!
S!GND!C1F7!2!@baseboard_fab2_lib.baseboard_fab2(sch_1):page195_i85@mstr_discrete.capp(chips)!CAPP_4040LF-470UF,16V,20%,ALUMA!!!F4110!B!!!!
S!P12V!F9B1!1!@baseboard_fab2_lib.baseboard_fab2(sch_1):page172_i38@mstr_discrete.fuse(chips)!FUSE_SM-IC,C94311-016!1!!F2128!A(0)!!!!
S!P12V_HDD_SATA!F9B1!2!@baseboard_fab2_lib.baseboard_fab2(sch_1):page172_i38@mstr_discrete.fuse(chips)!FUSE_SM-IC,C94311-016!1!!F2128!B(0)!!!!
S!P5V!F8B1!1!@baseboard_fab2_lib.baseboard_fab2(sch_1):page172_i41@mstr_discrete.fuse(chips)!FUSE_SMLF-IC,C94311-006!1!!F2127!A(0)!!!!
S!P5V_HDD_SATA!F8B1!2!@baseboard_fab2_lib.baseboard_fab2(sch_1):page172_i41@mstr_discrete.fuse(chips)!FUSE_SMLF-IC,C94311-006!1!!F2127!B(0)!!!!
S!PECI_BMC!R9F20!1!@baseboard_fab2_lib.baseboard_fab2(sch_1):page145_i133@mstr_discrete.res(chips)!RES_0402-348,1%,1/16W,EMPTY,G2A!!!F659!A!!!!
S!GND!R9F20!2!@baseboard_fab2_lib.baseboard_fab2(sch_1):page145_i133@mstr_discrete.res(chips)!RES_0402-348,1%,1/16W,EMPTY,G2A!!!F659!B!!!!
S!LED_POSTCODE_0_R!J9A2!1!@baseboard_fab2_lib.baseboard_fab2(sch_1):page155_i171@mstr_conn.conn14_h54902001(chips)!CONN14_H54902001_PIP-CONN,H549A!!!F2253!IO1!!!!
S!SPA_5V_SIN_SW!J9A2!10!@baseboard_fab2_lib.baseboard_fab2(sch_1):page155_i171@mstr_conn.conn14_h54902001(chips)!CONN14_H54902001_PIP-CONN,H549A!!!F2253!IO10!!!!
S!FM_DEBUG_RST_BTN_N!J9A2!11!@baseboard_fab2_lib.baseboard_fab2(sch_1):page155_i171@mstr_conn.conn14_h54902001(chips)!CONN14_H54902001_PIP-CONN,H549A!!!F2253!IO11!!!!
S!FM_UART_SWITCH_N!J9A2!12!@baseboard_fab2_lib.baseboard_fab2(sch_1):page155_i171@mstr_conn.conn14_h54902001(chips)!CONN14_H54902001_PIP-CONN,H549A!!!F2253!IO12!!!!
S!GND!J9A2!13!@baseboard_fab2_lib.baseboard_fab2(sch_1):page155_i171@mstr_conn.conn14_h54902001(chips)!CONN14_H54902001_PIP-CONN,H549A!!!F2253!IO13!!!!
S!P5V_STBY_DGB_FS!J9A2!14!@baseboard_fab2_lib.baseboard_fab2(sch_1):page155_i171@mstr_conn.conn14_h54902001(chips)!CONN14_H54902001_PIP-CONN,H549A!!!F2253!IO14!!!!
S!LED_POSTCODE_1_R!J9A2!2!@baseboard_fab2_lib.baseboard_fab2(sch_1):page155_i171@mstr_conn.conn14_h54902001(chips)!CONN14_H54902001_PIP-CONN,H549A!!!F2253!IO2!!!!
S!LED_POSTCODE_2_R!J9A2!3!@baseboard_fab2_lib.baseboard_fab2(sch_1):page155_i171@mstr_conn.conn14_h54902001(chips)!CONN14_H54902001_PIP-CONN,H549A!!!F2253!IO3!!!!
S!LED_POSTCODE_3_R!J9A2!4!@baseboard_fab2_lib.baseboard_fab2(sch_1):page155_i171@mstr_conn.conn14_h54902001(chips)!CONN14_H54902001_PIP-CONN,H549A!!!F2253!IO4!!!!
S!LED_POSTCODE_4_R!J9A2!5!@baseboard_fab2_lib.baseboard_fab2(sch_1):page155_i171@mstr_conn.conn14_h54902001(chips)!CONN14_H54902001_PIP-CONN,H549A!!!F2253!IO5!!!!
S!LED_POSTCODE_5_R!J9A2!6!@baseboard_fab2_lib.baseboard_fab2(sch_1):page155_i171@mstr_conn.conn14_h54902001(chips)!CONN14_H54902001_PIP-CONN,H549A!!!F2253!IO6!!!!
S!LED_POSTCODE_6_R!J9A2!7!@baseboard_fab2_lib.baseboard_fab2(sch_1):page155_i171@mstr_conn.conn14_h54902001(chips)!CONN14_H54902001_PIP-CONN,H549A!!!F2253!IO7!!!!
S!LED_POSTCODE_7_R!J9A2!8!@baseboard_fab2_lib.baseboard_fab2(sch_1):page155_i171@mstr_conn.conn14_h54902001(chips)!CONN14_H54902001_PIP-CONN,H549A!!!F2253!IO8!!!!
S!SPA_MID_DBG_TX!J9A2!9!@baseboard_fab2_lib.baseboard_fab2(sch_1):page155_i171@mstr_conn.conn14_h54902001(chips)!CONN14_H54902001_PIP-CONN,H549A!!!F2253!IO9!!!!
S!GND!RM1E1!1!@baseboard_fab2_lib.baseboard_fab2(sch_1):page195_i26@mstr_conn.conn3_g98259001(chips)!CONN3_G98259001_PIP-CONN,G9825A!!!F2246!IO1!!!!
S!GND!RM1E1!2!@baseboard_fab2_lib.baseboard_fab2(sch_1):page195_i26@mstr_conn.conn3_g98259001(chips)!CONN3_G98259001_PIP-CONN,G9825A!!!F2246!IO2!!!!
S!GND!RM1E1!3!@baseboard_fab2_lib.baseboard_fab2(sch_1):page195_i26@mstr_conn.conn3_g98259001(chips)!CONN3_G98259001_PIP-CONN,G9825A!!!F2246!IO3!!!!
S!GND!J9A1!1!@baseboard_fab2_lib.baseboard_fab2(sch_1):page134_i22@mstr_conn.conn4_d42317002(chips)!CONN4_D42317002_PIP-CONN,D4231A!!!F2245!IO1!!!!
S!PU_KEY_CONN_PIN2_R!J9A1!2!@baseboard_fab2_lib.baseboard_fab2(sch_1):page134_i22@mstr_conn.conn4_d42317002(chips)!CONN4_D42317002_PIP-CONN,D4231A!!!F2245!IO2!!!!
S!GND!J9A1!3!@baseboard_fab2_lib.baseboard_fab2(sch_1):page134_i22@mstr_conn.conn4_d42317002(chips)!CONN4_D42317002_PIP-CONN,D4231A!!!F2245!IO3!!!!
S!FM_PCH_SATA_RAID_KEY_R!J9A1!4!@baseboard_fab2_lib.baseboard_fab2(sch_1):page134_i22@mstr_conn.conn4_d42317002(chips)!CONN4_D42317002_PIP-CONN,D4231A!!!F2245!IO4!!!!
S!P3V3_STBY!J1F3!1!@baseboard_fab2_lib.baseboard_fab2(sch_1):page181_i189@mstr_conn.conn8_h62179001(chips)!CONN8_H62179001_PIP-CONN,H6217A!!!F2234!IO1!!!!
S!FM_MP_PS_REDUNDANT_LOST_N!J1F3!2!@baseboard_fab2_lib.baseboard_fab2(sch_1):page181_i189@mstr_conn.conn8_h62179001(chips)!CONN8_H62179001_PIP-CONN,H6217A!!!F2234!IO2!!!!
S!FM_MP_PS_FAIL_N!J1F3!3!@baseboard_fab2_lib.baseboard_fab2(sch_1):page181_i189@mstr_conn.conn8_h62179001(chips)!CONN8_H62179001_PIP-CONN,H6217A!!!F2234!IO3!!!!
S!FM_MATED_IN_N!J1F3!4!@baseboard_fab2_lib.baseboard_fab2(sch_1):page181_i189@mstr_conn.conn8_h62179001(chips)!CONN8_H62179001_PIP-CONN,H6217A!!!F2234!IO4!!!!
S!IRQ_SML1_PMBUS_ALERT_R_N!J1F3!5!@baseboard_fab2_lib.baseboard_fab2(sch_1):page181_i189@mstr_conn.conn8_h62179001(chips)!CONN8_H62179001_PIP-CONN,H6217A!!!F2234!IO5!!!!
S!SMB_BMC_PMBUS_STBY_LVC3_SDA!J1F3!6!@baseboard_fab2_lib.baseboard_fab2(sch_1):page181_i189@mstr_conn.conn8_h62179001(chips)!CONN8_H62179001_PIP-CONN,H6217A!!!F2234!IO6!!!!
S!SMB_BMC_PMBUS_STBY_LVC3_SCL!J1F3!7!@baseboard_fab2_lib.baseboard_fab2(sch_1):page181_i189@mstr_conn.conn8_h62179001(chips)!CONN8_H62179001_PIP-CONN,H6217A!!!F2234!IO7!!!!
S!GND!J1F3!8!@baseboard_fab2_lib.baseboard_fab2(sch_1):page181_i189@mstr_conn.conn8_h62179001(chips)!CONN8_H62179001_PIP-CONN,H6217A!!!F2234!IO8!!!!
S!USB2_P01_ESD_DN!J9B1!2!@baseboard_fab2_lib.baseboard_fab2(sch_1):page176_i69@mstr_conn.conn9_h51826001(chips)!CONN9_H51826001_PIP2-CONN,H518A!!!F2233!DN!!!!
S!USB2_P01_ESD_DP!J9B1!3!@baseboard_fab2_lib.baseboard_fab2(sch_1):page176_i69@mstr_conn.conn9_h51826001(chips)!CONN9_H51826001_PIP2-CONN,H518A!!!F2233!DP!!!!
S!GND!J9B1!4!@baseboard_fab2_lib.baseboard_fab2(sch_1):page176_i69@mstr_conn.conn9_h51826001(chips)!CONN9_H51826001_PIP2-CONN,H518A!!!F2233!GND!!!!
S!GND!J9B1!7!@baseboard_fab2_lib.baseboard_fab2(sch_1):page176_i69@mstr_conn.conn9_h51826001(chips)!CONN9_H51826001_PIP2-CONN,H518A!!!F2233!GND_DRAIN!!!!
S!GND!J9B1!MH1!@baseboard_fab2_lib.baseboard_fab2(sch_1):page176_i69@mstr_conn.conn9_h51826001(chips)!CONN9_H51826001_PIP2-CONN,H518A!!!F2233!MH1!!!!
S!GND!J9B1!MH2!@baseboard_fab2_lib.baseboard_fab2(sch_1):page176_i69@mstr_conn.conn9_h51826001(chips)!CONN9_H51826001_PIP2-CONN,H518A!!!F2233!MH2!!!!
S!GND!J9B1!MH3!@baseboard_fab2_lib.baseboard_fab2(sch_1):page176_i69@mstr_conn.conn9_h51826001(chips)!CONN9_H51826001_PIP2-CONN,H518A!!!F2233!MH3!!!!
S!GND!J9B1!MH4!@baseboard_fab2_lib.baseboard_fab2(sch_1):page176_i69@mstr_conn.conn9_h51826001(chips)!CONN9_H51826001_PIP2-CONN,H518A!!!F2233!MH4!!!!
S!USB3_P01_FB_RXN!J9B1!5!@baseboard_fab2_lib.baseboard_fab2(sch_1):page176_i69@mstr_conn.conn9_h51826001(chips)!CONN9_H51826001_PIP2-CONN,H518A!!!F2233!STDA_SSRXN!!!!
S!USB3_P01_FB_RXP!J9B1!6!@baseboard_fab2_lib.baseboard_fab2(sch_1):page176_i69@mstr_conn.conn9_h51826001(chips)!CONN9_H51826001_PIP2-CONN,H518A!!!F2233!STDA_SSRXP!!!!
S!USB3_P01_FB_TXN!J9B1!8!@baseboard_fab2_lib.baseboard_fab2(sch_1):page176_i69@mstr_conn.conn9_h51826001(chips)!CONN9_H51826001_PIP2-CONN,H518A!!!F2233!STDA_SSTXN!!!!
S!USB3_P01_FB_TXP!J9B1!9!@baseboard_fab2_lib.baseboard_fab2(sch_1):page176_i69@mstr_conn.conn9_h51826001(chips)!CONN9_H51826001_PIP2-CONN,H518A!!!F2233!STDA_SSTXP!!!!
S!P5V_USB!J9B1!1!@baseboard_fab2_lib.baseboard_fab2(sch_1):page176_i69@mstr_conn.conn9_h51826001(chips)!CONN9_H51826001_PIP2-CONN,H518A!!!F2233!VBUS!!!!
S!VR_P5V_STBY_COMP!R8E39!1!@baseboard_fab2_lib.baseboard_fab2(sch_1):page241_i54@mstr_discrete.res(chips)!RES_0402-24.9K,1%,1/16W,CHIP,GA!!!F844!A!!!!
S!VR_P5V_STBY_RC_COMP!R8E39!2!@baseboard_fab2_lib.baseboard_fab2(sch_1):page241_i54@mstr_discrete.res(chips)!RES_0402-24.9K,1%,1/16W,CHIP,GA!!!F844!B!!!!
S!FM_UARTSW_MSB_R_N!DS9A7!1!@baseboard_fab2_lib.baseboard_fab2(sch_1):page158_i134@mstr_discrete.led(chips)!LED_A1LF-GREEN,IC,D14725-022!!!F2030!A!!!!
S!FM_UARTSW_MSB_N!DS9A7!2!@baseboard_fab2_lib.baseboard_fab2(sch_1):page158_i134@mstr_discrete.led(chips)!LED_A1LF-GREEN,IC,D14725-022!!!F2030!C!!!!
S!FM_UARTSW_LSB_R_N!DS9A4!1!@baseboard_fab2_lib.baseboard_fab2(sch_1):page158_i130@mstr_discrete.led(chips)!LED_A1LF-GREEN,IC,D14725-022!!!F2031!A!!!!
S!FM_UARTSW_LSB_N!DS9A4!2!@baseboard_fab2_lib.baseboard_fab2(sch_1):page158_i130@mstr_discrete.led(chips)!LED_A1LF-GREEN,IC,D14725-022!!!F2031!C!!!!
S!GND!U1L2!3!!TTL1G86_SOTLF-74AHCT1G86,IC,D3B!!!!!!!!
S!P5V_STBY!U1L2!5!!TTL1G86_SOTLF-74AHCT1G86,IC,D3B!!!!!!!!
S!PWRGD_P3V3_R!U1L2!1!@baseboard_fab2_lib.baseboard_fab2(sch_1):page175_i57@mstr_ttl.ttl1g86(chips)!TTL1G86_SOTLF-74AHCT1G86,IC,D3B!!!F21!A!!!!
S!FP_PWR_ID_LED_N!U1L2!2!@baseboard_fab2_lib.baseboard_fab2(sch_1):page175_i57@mstr_ttl.ttl1g86(chips)!TTL1G86_SOTLF-74AHCT1G86,IC,D3B!!!F21!B!!!!
S!FP_ID_LED_P5V_STBY_N!U1L2!4!@baseboard_fab2_lib.baseboard_fab2(sch_1):page175_i57@mstr_ttl.ttl1g86(chips)!TTL1G86_SOTLF-74AHCT1G86,IC,D3B!!!F21!Y!!!!
S!P12V_STBY!C3B6!1!@baseboard_fab2_lib.baseboard_fab2(sch_1):page195_i100@mstr_discrete.capp(chips)!CAPP_3018-68UF,16V,20%,TANT,72A!!!F4125!A!!!!
S!GND!C3B6!2!@baseboard_fab2_lib.baseboard_fab2(sch_1):page195_i100@mstr_discrete.capp(chips)!CAPP_3018-68UF,16V,20%,TANT,72A!!!F4125!B!!!!
S!P12V_STBY!C3T3!1!@baseboard_fab2_lib.baseboard_fab2(sch_1):page195_i113@mstr_discrete.capp(chips)!CAPP_3018-68UF,16V,20%,TANT,72A!!!F4124!A!!!!
S!GND!C3T3!2!@baseboard_fab2_lib.baseboard_fab2(sch_1):page195_i113@mstr_discrete.capp(chips)!CAPP_3018-68UF,16V,20%,TANT,72A!!!F4124!B!!!!
S!P12V_STBY!C4F5!1!@baseboard_fab2_lib.baseboard_fab2(sch_1):page195_i96@mstr_discrete.capp(chips)!CAPP_3018-68UF,16V,20%,TANT,72A!!!F4118!A!!!!
S!GND!C4F5!2!@baseboard_fab2_lib.baseboard_fab2(sch_1):page195_i96@mstr_discrete.capp(chips)!CAPP_3018-68UF,16V,20%,TANT,72A!!!F4118!B!!!!
S!P12V_STBY!C4F4!1!@baseboard_fab2_lib.baseboard_fab2(sch_1):page195_i112@mstr_discrete.capp(chips)!CAPP_3018-68UF,16V,20%,TANT,72A!!!F4119!A!!!!
S!GND!C4F4!2!@baseboard_fab2_lib.baseboard_fab2(sch_1):page195_i112@mstr_discrete.capp(chips)!CAPP_3018-68UF,16V,20%,TANT,72A!!!F4119!B!!!!
S!P12V_STBY!C4B14!1!@baseboard_fab2_lib.baseboard_fab2(sch_1):page195_i97@mstr_discrete.capp(chips)!CAPP_3018-68UF,16V,20%,TANT,72A!!!F4120!A!!!!
S!GND!C4B14!2!@baseboard_fab2_lib.baseboard_fab2(sch_1):page195_i97@mstr_discrete.capp(chips)!CAPP_3018-68UF,16V,20%,TANT,72A!!!F4120!B!!!!
S!P12V_STBY!C9T3!1!@baseboard_fab2_lib.baseboard_fab2(sch_1):page195_i111@mstr_discrete.capp(chips)!CAPP_3018-68UF,16V,20%,TANT,72A!!!F4112!A!!!!
S!GND!C9T3!2!@baseboard_fab2_lib.baseboard_fab2(sch_1):page195_i111@mstr_discrete.capp(chips)!CAPP_3018-68UF,16V,20%,TANT,72A!!!F4112!B!!!!
S!P12V_STBY!C1M5!1!@baseboard_fab2_lib.baseboard_fab2(sch_1):page195_i103@mstr_discrete.capp(chips)!CAPP_3018-68UF,16V,20%,TANT,72A!!!F4127!A!!!!
S!GND!C1M5!2!@baseboard_fab2_lib.baseboard_fab2(sch_1):page195_i103@mstr_discrete.capp(chips)!CAPP_3018-68UF,16V,20%,TANT,72A!!!F4127!B!!!!
S!P12V_STBY!C6N5!1!@baseboard_fab2_lib.baseboard_fab2(sch_1):page195_i109@mstr_discrete.capp(chips)!CAPP_3018-68UF,16V,20%,TANT,72A!!!F4115!A!!!!
S!GND!C6N5!2!@baseboard_fab2_lib.baseboard_fab2(sch_1):page195_i109@mstr_discrete.capp(chips)!CAPP_3018-68UF,16V,20%,TANT,72A!!!F4115!B!!!!
S!P12V_STBY!C1R23!1!@baseboard_fab2_lib.baseboard_fab2(sch_1):page195_i101@mstr_discrete.capp(chips)!CAPP_3018-68UF,16V,20%,TANT,72A!!!F4126!A!!!!
S!GND!C1R23!2!@baseboard_fab2_lib.baseboard_fab2(sch_1):page195_i101@mstr_discrete.capp(chips)!CAPP_3018-68UF,16V,20%,TANT,72A!!!F4126!B!!!!
S!P12V_STBY!C7M6!1!@baseboard_fab2_lib.baseboard_fab2(sch_1):page195_i108@mstr_discrete.capp(chips)!CAPP_3018-68UF,16V,20%,TANT,72A!!!F4114!A!!!!
S!GND!C7M6!2!@baseboard_fab2_lib.baseboard_fab2(sch_1):page195_i108@mstr_discrete.capp(chips)!CAPP_3018-68UF,16V,20%,TANT,72A!!!F4114!B!!!!
S!P12V_STBY!C9M3!1!@baseboard_fab2_lib.baseboard_fab2(sch_1):page195_i99@mstr_discrete.capp(chips)!CAPP_3018-68UF,16V,20%,TANT,72A!!!F4113!A!!!!
S!GND!C9M3!2!@baseboard_fab2_lib.baseboard_fab2(sch_1):page195_i99@mstr_discrete.capp(chips)!CAPP_3018-68UF,16V,20%,TANT,72A!!!F4113!B!!!!
S!P12V_STBY!C3T13!1!@baseboard_fab2_lib.baseboard_fab2(sch_1):page195_i104@mstr_discrete.capp(chips)!CAPP_3018-68UF,16V,20%,TANT,72A!!!F4122!A!!!!
S!GND!C3T13!2!@baseboard_fab2_lib.baseboard_fab2(sch_1):page195_i104@mstr_discrete.capp(chips)!CAPP_3018-68UF,16V,20%,TANT,72A!!!F4122!B!!!!
S!P12V_STBY!C3T6!1!@baseboard_fab2_lib.baseboard_fab2(sch_1):page195_i98@mstr_discrete.capp(chips)!CAPP_3018-68UF,16V,20%,TANT,72A!!!F4123!A!!!!
S!GND!C3T6!2!@baseboard_fab2_lib.baseboard_fab2(sch_1):page195_i98@mstr_discrete.capp(chips)!CAPP_3018-68UF,16V,20%,TANT,72A!!!F4123!B!!!!
S!P12V_STBY!C3T15!1!@baseboard_fab2_lib.baseboard_fab2(sch_1):page195_i106@mstr_discrete.capp(chips)!CAPP_3018-68UF,16V,20%,TANT,72A!!!F4121!A!!!!
S!GND!C3T15!2!@baseboard_fab2_lib.baseboard_fab2(sch_1):page195_i106@mstr_discrete.capp(chips)!CAPP_3018-68UF,16V,20%,TANT,72A!!!F4121!B!!!!
S!P12V_STBY!C4M6!1!@baseboard_fab2_lib.baseboard_fab2(sch_1):page195_i102@mstr_discrete.capp(chips)!CAPP_3018-68UF,16V,20%,TANT,72A!!!F4117!A!!!!
S!GND!C4M6!2!@baseboard_fab2_lib.baseboard_fab2(sch_1):page195_i102@mstr_discrete.capp(chips)!CAPP_3018-68UF,16V,20%,TANT,72A!!!F4117!B!!!!
S!P12V_STBY!C4M7!1!@baseboard_fab2_lib.baseboard_fab2(sch_1):page195_i105@mstr_discrete.capp(chips)!CAPP_3018-68UF,16V,20%,TANT,72A!!!F4116!A!!!!
S!GND!C4M7!2!@baseboard_fab2_lib.baseboard_fab2(sch_1):page195_i105@mstr_discrete.capp(chips)!CAPP_3018-68UF,16V,20%,TANT,72A!!!F4116!B!!!!
S!VR_P5V_STBY_SS!C8E15!1!@baseboard_fab2_lib.baseboard_fab2(sch_1):page241_i63@mstr_discrete.cap(chips)!CAP_0402LF-0.022UF,16V,10%,X7RA!!!F3491!A!!!!
S!AGND_P5V_STBY!C8E15!2!@baseboard_fab2_lib.baseboard_fab2(sch_1):page241_i63@mstr_discrete.cap(chips)!CAP_0402LF-0.022UF,16V,10%,X7RA!!!F3491!B!!!!
S!CLK_100M_CPU1_RC_REFCLK1_DP!R7P9!1!@baseboard_fab2_lib.baseboard_fab2(sch_1):page103_i121@mstr_discrete.res(chips)!RES_0402-42.2,1.0%,1/16W,EMPTYA!!!F470!A!!!!
S!GND!R7P9!2!@baseboard_fab2_lib.baseboard_fab2(sch_1):page103_i121@mstr_discrete.res(chips)!RES_0402-42.2,1.0%,1/16W,EMPTYA!!!F470!B!!!!
S!CLK_100M_CPU1_RC_REFCLK1_DN!R7P12!1!@baseboard_fab2_lib.baseboard_fab2(sch_1):page103_i123@mstr_discrete.res(chips)!RES_0402-42.2,1.0%,1/16W,EMPTYA!!!F469!A!!!!
S!GND!R7P12!2!@baseboard_fab2_lib.baseboard_fab2(sch_1):page103_i123@mstr_discrete.res(chips)!RES_0402-42.2,1.0%,1/16W,EMPTYA!!!F469!B!!!!
S!CLK_100M_CPU1_RC_REFCLK0_DP!R7P6!1!@baseboard_fab2_lib.baseboard_fab2(sch_1):page103_i125@mstr_discrete.res(chips)!RES_0402-42.2,1.0%,1/16W,EMPTYA!!!F472!A!!!!
S!GND!R7P6!2!@baseboard_fab2_lib.baseboard_fab2(sch_1):page103_i125@mstr_discrete.res(chips)!RES_0402-42.2,1.0%,1/16W,EMPTYA!!!F472!B!!!!
S!CLK_100M_CPU1_RC_REFCLK0_DN!R7P7!1!@baseboard_fab2_lib.baseboard_fab2(sch_1):page103_i127@mstr_discrete.res(chips)!RES_0402-42.2,1.0%,1/16W,EMPTYA!!!F471!A!!!!
S!GND!R7P7!2!@baseboard_fab2_lib.baseboard_fab2(sch_1):page103_i127@mstr_discrete.res(chips)!RES_0402-42.2,1.0%,1/16W,EMPTYA!!!F471!B!!!!
S!CLK_100M_CPU1_PE_REFCLK_DP!R7P3!1!@baseboard_fab2_lib.baseboard_fab2(sch_1):page103_i129@mstr_discrete.res(chips)!RES_0402-42.2,1.0%,1/16W,EMPTYA!!!F474!A!!!!
S!GND!R7P3!2!@baseboard_fab2_lib.baseboard_fab2(sch_1):page103_i129@mstr_discrete.res(chips)!RES_0402-42.2,1.0%,1/16W,EMPTYA!!!F474!B!!!!
S!CLK_100M_CPU1_PE_REFCLK_DN!R7P4!1!@baseboard_fab2_lib.baseboard_fab2(sch_1):page103_i131@mstr_discrete.res(chips)!RES_0402-42.2,1.0%,1/16W,EMPTYA!!!F473!A!!!!
S!GND!R7P4!2!@baseboard_fab2_lib.baseboard_fab2(sch_1):page103_i131@mstr_discrete.res(chips)!RES_0402-42.2,1.0%,1/16W,EMPTYA!!!F473!B!!!!
S!CLK_100M_CPU1_BCLK2_DP!R7P1!1!@baseboard_fab2_lib.baseboard_fab2(sch_1):page103_i133@mstr_discrete.res(chips)!RES_0402-42.2,1.0%,1/16W,EMPTYA!!!F476!A!!!!
S!GND!R7P1!2!@baseboard_fab2_lib.baseboard_fab2(sch_1):page103_i133@mstr_discrete.res(chips)!RES_0402-42.2,1.0%,1/16W,EMPTYA!!!F476!B!!!!
S!CLK_100M_CPU1_BCLK2_DN!R7P2!1!@baseboard_fab2_lib.baseboard_fab2(sch_1):page103_i135@mstr_discrete.res(chips)!RES_0402-42.2,1.0%,1/16W,EMPTYA!!!F475!A!!!!
S!GND!R7P2!2!@baseboard_fab2_lib.baseboard_fab2(sch_1):page103_i135@mstr_discrete.res(chips)!RES_0402-42.2,1.0%,1/16W,EMPTYA!!!F475!B!!!!
S!CLK_100M_CPU1_BCLK1_DN!R6P8!1!@baseboard_fab2_lib.baseboard_fab2(sch_1):page103_i139@mstr_discrete.res(chips)!RES_0402-42.2,1.0%,1/16W,EMPTYA!!!F483!A!!!!
S!GND!R6P8!2!@baseboard_fab2_lib.baseboard_fab2(sch_1):page103_i139@mstr_discrete.res(chips)!RES_0402-42.2,1.0%,1/16W,EMPTYA!!!F483!B!!!!
S!CLK_100M_CPU1_BCLK0_DP!R6P5!1!@baseboard_fab2_lib.baseboard_fab2(sch_1):page103_i141@mstr_discrete.res(chips)!RES_0402-42.2,1.0%,1/16W,EMPTYA!!!F486!A!!!!
S!GND!R6P5!2!@baseboard_fab2_lib.baseboard_fab2(sch_1):page103_i141@mstr_discrete.res(chips)!RES_0402-42.2,1.0%,1/16W,EMPTYA!!!F486!B!!!!
S!CLK_100M_CPU1_BCLK0_DN!R6P6!1!@baseboard_fab2_lib.baseboard_fab2(sch_1):page103_i143@mstr_discrete.res(chips)!RES_0402-42.2,1.0%,1/16W,EMPTYA!!!F485!A!!!!
S!GND!R6P6!2!@baseboard_fab2_lib.baseboard_fab2(sch_1):page103_i143@mstr_discrete.res(chips)!RES_0402-42.2,1.0%,1/16W,EMPTYA!!!F485!B!!!!
S!CLK_100M_CPU0_RC_REFCLK1_DP!R6P3!1!@baseboard_fab2_lib.baseboard_fab2(sch_1):page103_i145@mstr_discrete.res(chips)!RES_0402-42.2,1.0%,1/16W,EMPTYA!!!F488!A!!!!
S!GND!R6P3!2!@baseboard_fab2_lib.baseboard_fab2(sch_1):page103_i145@mstr_discrete.res(chips)!RES_0402-42.2,1.0%,1/16W,EMPTYA!!!F488!B!!!!
S!CLK_100M_CPU0_RC_REFCLK1_DN!R6P4!1!@baseboard_fab2_lib.baseboard_fab2(sch_1):page103_i147@mstr_discrete.res(chips)!RES_0402-42.2,1.0%,1/16W,EMPTYA!!!F487!A!!!!
S!GND!R6P4!2!@baseboard_fab2_lib.baseboard_fab2(sch_1):page103_i147@mstr_discrete.res(chips)!RES_0402-42.2,1.0%,1/16W,EMPTYA!!!F487!B!!!!
S!CLK_100M_CPU0_RC_REFCLK0_DP!R6P1!1!@baseboard_fab2_lib.baseboard_fab2(sch_1):page103_i149@mstr_discrete.res(chips)!RES_0402-42.2,1.0%,1/16W,EMPTYA!!!F490!A!!!!
S!GND!R6P1!2!@baseboard_fab2_lib.baseboard_fab2(sch_1):page103_i149@mstr_discrete.res(chips)!RES_0402-42.2,1.0%,1/16W,EMPTYA!!!F490!B!!!!
S!CLK_100M_CPU0_RC_REFCLK0_DN!R6P2!1!@baseboard_fab2_lib.baseboard_fab2(sch_1):page103_i151@mstr_discrete.res(chips)!RES_0402-42.2,1.0%,1/16W,EMPTYA!!!F489!A!!!!
S!GND!R6P2!2!@baseboard_fab2_lib.baseboard_fab2(sch_1):page103_i151@mstr_discrete.res(chips)!RES_0402-42.2,1.0%,1/16W,EMPTYA!!!F489!B!!!!
S!CLK_100M_CPU0_PE_REFCLK_DP!R6P11!1!@baseboard_fab2_lib.baseboard_fab2(sch_1):page103_i153@mstr_discrete.res(chips)!RES_0402-42.2,1.0%,1/16W,EMPTYA!!!F481!A!!!!
S!GND!R6P11!2!@baseboard_fab2_lib.baseboard_fab2(sch_1):page103_i153@mstr_discrete.res(chips)!RES_0402-42.2,1.0%,1/16W,EMPTYA!!!F481!B!!!!
S!CLK_100M_CPU0_PE_REFCLK_DN!R6P9!1!@baseboard_fab2_lib.baseboard_fab2(sch_1):page103_i155@mstr_discrete.res(chips)!RES_0402-42.2,1.0%,1/16W,EMPTYA!!!F482!A!!!!
S!GND!R6P9!2!@baseboard_fab2_lib.baseboard_fab2(sch_1):page103_i155@mstr_discrete.res(chips)!RES_0402-42.2,1.0%,1/16W,EMPTYA!!!F482!B!!!!
S!CLK_100M_CPU0_BCLK2_DP!R6P13!1!@baseboard_fab2_lib.baseboard_fab2(sch_1):page103_i157@mstr_discrete.res(chips)!RES_0402-42.2,1.0%,1/16W,EMPTYA!!!F479!A!!!!
S!GND!R6P13!2!@baseboard_fab2_lib.baseboard_fab2(sch_1):page103_i157@mstr_discrete.res(chips)!RES_0402-42.2,1.0%,1/16W,EMPTYA!!!F479!B!!!!
S!CLK_100M_CPU0_BCLK2_DN!R6P12!1!@baseboard_fab2_lib.baseboard_fab2(sch_1):page103_i159@mstr_discrete.res(chips)!RES_0402-42.2,1.0%,1/16W,EMPTYA!!!F480!A!!!!
S!GND!R6P12!2!@baseboard_fab2_lib.baseboard_fab2(sch_1):page103_i159@mstr_discrete.res(chips)!RES_0402-42.2,1.0%,1/16W,EMPTYA!!!F480!B!!!!
S!CLK_100M_CPU0_BCLK1_DP!R4D24!1!@baseboard_fab2_lib.baseboard_fab2(sch_1):page103_i161@mstr_discrete.res(chips)!RES_0402-42.2,1.0%,1/16W,EMPTYA!!!F491!A!!!!
S!GND!R4D24!2!@baseboard_fab2_lib.baseboard_fab2(sch_1):page103_i161@mstr_discrete.res(chips)!RES_0402-42.2,1.0%,1/16W,EMPTYA!!!F491!B!!!!
S!CLK_100M_CPU0_BCLK1_DN!R4D18!1!@baseboard_fab2_lib.baseboard_fab2(sch_1):page103_i163@mstr_discrete.res(chips)!RES_0402-42.2,1.0%,1/16W,EMPTYA!!!F492!A!!!!
S!GND!R4D18!2!@baseboard_fab2_lib.baseboard_fab2(sch_1):page103_i163@mstr_discrete.res(chips)!RES_0402-42.2,1.0%,1/16W,EMPTYA!!!F492!B!!!!
S!CLK_100M_CPU0_BCLK0_DP!R6P17!1!@baseboard_fab2_lib.baseboard_fab2(sch_1):page103_i165@mstr_discrete.res(chips)!RES_0402-42.2,1.0%,1/16W,EMPTYA!!!F477!A!!!!
S!GND!R6P17!2!@baseboard_fab2_lib.baseboard_fab2(sch_1):page103_i165@mstr_discrete.res(chips)!RES_0402-42.2,1.0%,1/16W,EMPTYA!!!F477!B!!!!
S!CLK_100M_CPU0_BCLK0_DN!R6P15!1!@baseboard_fab2_lib.baseboard_fab2(sch_1):page103_i167@mstr_discrete.res(chips)!RES_0402-42.2,1.0%,1/16W,EMPTYA!!!F478!A!!!!
S!GND!R6P15!2!@baseboard_fab2_lib.baseboard_fab2(sch_1):page103_i167@mstr_discrete.res(chips)!RES_0402-42.2,1.0%,1/16W,EMPTYA!!!F478!B!!!!
S!CLK_100M_CPU1_BCLK1_DP!R6P7!1!@baseboard_fab2_lib.baseboard_fab2(sch_1):page103_i137@mstr_discrete.res(chips)!RES_0402-42.2,1.0%,1/16W,EMPTYA!!!F484!A!!!!
S!GND!R6P7!2!@baseboard_fab2_lib.baseboard_fab2(sch_1):page103_i137@mstr_discrete.res(chips)!RES_0402-42.2,1.0%,1/16W,EMPTYA!!!F484!B!!!!
S!A_HSC_PWGIN!R9P24!1!@baseboard_fab2_lib.baseboard_fab2(sch_1):page199_i55@mstr_discrete.res(chips)!RES_0402-12.1K,1%,1/16W,CHIP,GA!!!F1107!A!!!!
S!AGND_HSC!R9P24!2!@baseboard_fab2_lib.baseboard_fab2(sch_1):page199_i55@mstr_discrete.res(chips)!RES_0402-12.1K,1%,1/16W,CHIP,GA!!!F1107!B!!!!
S!GND!R1D41!1!@baseboard_fab2_lib.baseboard_fab2(sch_1):page199_i19@mstr_discrete.res(chips)!RES_0805-0.0,5%,1/8W,CHIP,G221A!!!F255!A!!!!
S!AGND_HSC!R1D41!2!@baseboard_fab2_lib.baseboard_fab2(sch_1):page199_i19@mstr_discrete.res(chips)!RES_0805-0.0,5%,1/8W,CHIP,G221A!!!F255!B!!!!
S!VR_P3V3_STBY_PHASE!L8F1!1!@baseboard_fab2_lib.baseboard_fab2(sch_1):page240_i173@mstr_discrete.inductor(chips)!INDUCTOR_SM-1.00UH,IND,E98679-A!!!F2092!INA!!!!
S!P3V3_STBY!L8F1!2!@baseboard_fab2_lib.baseboard_fab2(sch_1):page240_i173@mstr_discrete.inductor(chips)!INDUCTOR_SM-1.00UH,IND,E98679-A!!!F2092!INB!!!!
S!VR_P5V_STBY_PHASE!L8E1!1!@baseboard_fab2_lib.baseboard_fab2(sch_1):page241_i90@mstr_discrete.inductor(chips)!INDUCTOR_SM-2.2UH,IND,E98761-0A!!!F2082!INA!!!!
S!P5V_STBY!L8E1!2!@baseboard_fab2_lib.baseboard_fab2(sch_1):page241_i90@mstr_discrete.inductor(chips)!INDUCTOR_SM-2.2UH,IND,E98761-0A!!!F2082!INB!!!!
S!VR_PVPP_ABC_SS!C7F10!1!@baseboard_fab2_lib.baseboard_fab2(sch_1):page231_i194@mstr_discrete.cap(chips)!CAP_0402-0.027UF,16V,10%,X7R,AA!!!F4087!A!!!!
S!AGND_PVPP_ABC!C7F10!2!@baseboard_fab2_lib.baseboard_fab2(sch_1):page231_i194@mstr_discrete.cap(chips)!CAP_0402-0.027UF,16V,10%,X7R,AA!!!F4087!B!!!!
S!VR_PVPP_DEF_SS!C7B11!1!@baseboard_fab2_lib.baseboard_fab2(sch_1):page232_i197@mstr_discrete.cap(chips)!CAP_0402-0.027UF,16V,10%,X7R,AA!!!F4088!A!!!!
S!AGND_PVPP_DEF!C7B11!2!@baseboard_fab2_lib.baseboard_fab2(sch_1):page232_i197@mstr_discrete.cap(chips)!CAP_0402-0.027UF,16V,10%,X7R,AA!!!F4088!B!!!!
S!VR_PVPP_GHJ_SS!C4G8!1!@baseboard_fab2_lib.baseboard_fab2(sch_1):page233_i194@mstr_discrete.cap(chips)!CAP_0402-0.027UF,16V,10%,X7R,AA!!!F4089!A!!!!
S!AGND_PVPP_GHJ!C4G8!2!@baseboard_fab2_lib.baseboard_fab2(sch_1):page233_i194@mstr_discrete.cap(chips)!CAP_0402-0.027UF,16V,10%,X7R,AA!!!F4089!B!!!!
S!VR_PVPP_KLM_SS!C4B6!1!@baseboard_fab2_lib.baseboard_fab2(sch_1):page234_i146@mstr_discrete.cap(chips)!CAP_0402-0.027UF,16V,10%,X7R,AA!!!F4090!A!!!!
S!AGND_PVPP_KLM!C4B6!2!@baseboard_fab2_lib.baseboard_fab2(sch_1):page234_i146@mstr_discrete.cap(chips)!CAP_0402-0.027UF,16V,10%,X7R,AA!!!F4090!B!!!!
S!VSENSE_P12V_ADM1085!R3P51!1!@baseboard_fab2_lib.baseboard_fab2(sch_1):page196_i75@mstr_discrete.res(chips)!RES_0402-6.34K,1%,1/16W,CHIP,GA!!!F369!A!!!!
S!GND!R3P51!2!@baseboard_fab2_lib.baseboard_fab2(sch_1):page196_i75@mstr_discrete.res(chips)!RES_0402-6.34K,1%,1/16W,CHIP,GA!!!F369!B!!!!
S!VR_FB_PVPP_ABC!R7F11!1!@baseboard_fab2_lib.baseboard_fab2(sch_1):page231_i166@mstr_discrete.res(chips)!RES_0402-6.34K,1%,1/16W,CHIP,GA!!!F365!A!!!!
S!AGND_PVPP_ABC!R7F11!2!@baseboard_fab2_lib.baseboard_fab2(sch_1):page231_i166@mstr_discrete.res(chips)!RES_0402-6.34K,1%,1/16W,CHIP,GA!!!F365!B!!!!
S!VR_FB_PVPP_DEF!R7B13!1!@baseboard_fab2_lib.baseboard_fab2(sch_1):page232_i304@mstr_discrete.res(chips)!RES_0402-6.34K,1%,1/16W,CHIP,GA!!!F366!A!!!!
S!AGND_PVPP_DEF!R7B13!2!@baseboard_fab2_lib.baseboard_fab2(sch_1):page232_i304@mstr_discrete.res(chips)!RES_0402-6.34K,1%,1/16W,CHIP,GA!!!F366!B!!!!
S!VR_FB_PVPP_GHJ!R4G9!1!@baseboard_fab2_lib.baseboard_fab2(sch_1):page233_i269@mstr_discrete.res(chips)!RES_0402-6.34K,1%,1/16W,CHIP,GA!!!F367!A!!!!
S!AGND_PVPP_GHJ!R4G9!2!@baseboard_fab2_lib.baseboard_fab2(sch_1):page233_i269@mstr_discrete.res(chips)!RES_0402-6.34K,1%,1/16W,CHIP,GA!!!F367!B!!!!
S!VR_FB_PVPP_KLM!R4B4!1!@baseboard_fab2_lib.baseboard_fab2(sch_1):page234_i216@mstr_discrete.res(chips)!RES_0402-6.34K,1%,1/16W,CHIP,GA!!!F368!A!!!!
S!AGND_PVPP_KLM!R4B4!2!@baseboard_fab2_lib.baseboard_fab2(sch_1):page234_i216@mstr_discrete.res(chips)!RES_0402-6.34K,1%,1/16W,CHIP,GA!!!F368!B!!!!
S!VR_P3V3_STBY_OCSELECT!R8F9!1!@baseboard_fab2_lib.baseboard_fab2(sch_1):page240_i106@mstr_discrete.res(chips)!RES_0402-64.9K,1%,1/16W,CHIP,GA!!!F358!A!!!!
S!AGND_P3V3_STBY!R8F9!2!@baseboard_fab2_lib.baseboard_fab2(sch_1):page240_i106@mstr_discrete.res(chips)!RES_0402-64.9K,1%,1/16W,CHIP,GA!!!F358!B!!!!
S!VR_PVPP_ABC_ISET!R7F15!1!@baseboard_fab2_lib.baseboard_fab2(sch_1):page231_i134@mstr_discrete.res(chips)!RES_0402-7.87K,1.0%,1/16W,CHIPA!!!F307!A!!!!
S!AGND_PVPP_ABC!R7F15!2!@baseboard_fab2_lib.baseboard_fab2(sch_1):page231_i134@mstr_discrete.res(chips)!RES_0402-7.87K,1.0%,1/16W,CHIPA!!!F307!B!!!!
S!VR_COMP_RC_PVPP_ABC!R7F18!1!@baseboard_fab2_lib.baseboard_fab2(sch_1):page231_i201@mstr_discrete.res(chips)!RES_0402-7.87K,1.0%,1/16W,CHIPA!!!F306!A!!!!
S!VR_FB_PVPP_ABC!R7F18!2!@baseboard_fab2_lib.baseboard_fab2(sch_1):page231_i201@mstr_discrete.res(chips)!RES_0402-7.87K,1.0%,1/16W,CHIPA!!!F306!B!!!!
S!VR_COMP_RC_PVPP_DEF!R7B16!1!@baseboard_fab2_lib.baseboard_fab2(sch_1):page232_i300@mstr_discrete.res(chips)!RES_0402-7.87K,1.0%,1/16W,CHIPA!!!F308!A!!!!
S!VR_FB_PVPP_DEF!R7B16!2!@baseboard_fab2_lib.baseboard_fab2(sch_1):page232_i300@mstr_discrete.res(chips)!RES_0402-7.87K,1.0%,1/16W,CHIPA!!!F308!B!!!!
S!VR_PVPP_DEF_ISET!R7B14!1!@baseboard_fab2_lib.baseboard_fab2(sch_1):page232_i193@mstr_discrete.res(chips)!RES_0402-7.87K,1.0%,1/16W,CHIPA!!!F309!A!!!!
S!AGND_PVPP_DEF!R7B14!2!@baseboard_fab2_lib.baseboard_fab2(sch_1):page232_i193@mstr_discrete.res(chips)!RES_0402-7.87K,1.0%,1/16W,CHIPA!!!F309!B!!!!
S!VR_PVPP_GHJ_ISET!R4G11!1!@baseboard_fab2_lib.baseboard_fab2(sch_1):page233_i184@mstr_discrete.res(chips)!RES_0402-7.87K,1.0%,1/16W,CHIPA!!!F311!A!!!!
S!AGND_PVPP_GHJ!R4G11!2!@baseboard_fab2_lib.baseboard_fab2(sch_1):page233_i184@mstr_discrete.res(chips)!RES_0402-7.87K,1.0%,1/16W,CHIPA!!!F311!B!!!!
S!VR_PVPP_KLM_ISET!R4B6!1!@baseboard_fab2_lib.baseboard_fab2(sch_1):page234_i140@mstr_discrete.res(chips)!RES_0402-7.87K,1.0%,1/16W,CHIPA!!!F313!A!!!!
S!AGND_PVPP_KLM!R4B6!2!@baseboard_fab2_lib.baseboard_fab2(sch_1):page234_i140@mstr_discrete.res(chips)!RES_0402-7.87K,1.0%,1/16W,CHIPA!!!F313!B!!!!
S!VR_COMP_RC_PVPP_GHJ!R4G13!1!@baseboard_fab2_lib.baseboard_fab2(sch_1):page233_i272@mstr_discrete.res(chips)!RES_0402-7.87K,1.0%,1/16W,CHIPA!!!F310!A!!!!
S!VR_FB_PVPP_GHJ!R4G13!2!@baseboard_fab2_lib.baseboard_fab2(sch_1):page233_i272@mstr_discrete.res(chips)!RES_0402-7.87K,1.0%,1/16W,CHIPA!!!F310!B!!!!
S!VR_COMP_RC_PVPP_KLM!R4B8!1!@baseboard_fab2_lib.baseboard_fab2(sch_1):page234_i213@mstr_discrete.res(chips)!RES_0402-7.87K,1.0%,1/16W,CHIPA!!!F312!A!!!!
S!VR_FB_PVPP_KLM!R4B8!2!@baseboard_fab2_lib.baseboard_fab2(sch_1):page234_i213@mstr_discrete.res(chips)!RES_0402-7.87K,1.0%,1/16W,CHIPA!!!F312!B!!!!
S!P12V_STBY!R9P7!1!@baseboard_fab2_lib.baseboard_fab2(sch_1):page200_i145@mstr_discrete.res(chips)!RES_0402-249K,1.0%,1/16W,CHIP,A!!!F806!A!!!!
S!A_P12V_STBY_ADR_TRIGGER!R9P7!2!@baseboard_fab2_lib.baseboard_fab2(sch_1):page200_i145@mstr_discrete.res(chips)!RES_0402-249K,1.0%,1/16W,CHIP,A!!!F806!B!!!!
S!P12V_STBY!R9P13!1!@baseboard_fab2_lib.baseboard_fab2(sch_1):page200_i107@mstr_discrete.res(chips)!RES_0402-274K,1.0%,1/16W,CHIP,A!!!F781!A!!!!
S!A_P12V_STBY_FP_TRIGGER!R9P13!2!@baseboard_fab2_lib.baseboard_fab2(sch_1):page200_i107@mstr_discrete.res(chips)!RES_0402-274K,1.0%,1/16W,CHIP,A!!!F781!B!!!!
S!P12V!J8G1!1!@baseboard_fab2_lib.baseboard_fab2(sch_1):page108_i258@mstr_sconn.sconn200_h68296001(chips)!SCONN200_H68296001_SM-CONN,H68A!!!F235!IO1!!!!
S!P12V!J8G1!10!@baseboard_fab2_lib.baseboard_fab2(sch_1):page108_i258@mstr_sconn.sconn200_h68296001(chips)!SCONN200_H68296001_SM-CONN,H68A!!!F235!IO10!!!!
S!P3E_CPU0_PE1_SS_R_RXP<7>!J8G1!100!@baseboard_fab2_lib.baseboard_fab2(sch_1):page108_i258@mstr_sconn.sconn200_h68296001(chips)!SCONN200_H68296001_SM-CONN,H68A!!!F235!IO100!!!!
S!P12V!J8G1!11!@baseboard_fab2_lib.baseboard_fab2(sch_1):page108_i258@mstr_sconn.sconn200_h68296001(chips)!SCONN200_H68296001_SM-CONN,H68A!!!F235!IO11!!!!
S!P12V!J8G1!12!@baseboard_fab2_lib.baseboard_fab2(sch_1):page108_i258@mstr_sconn.sconn200_h68296001(chips)!SCONN200_H68296001_SM-CONN,H68A!!!F235!IO12!!!!
S!GND!J8G1!13!@baseboard_fab2_lib.baseboard_fab2(sch_1):page108_i258@mstr_sconn.sconn200_h68296001(chips)!SCONN200_H68296001_SM-CONN,H68A!!!F235!IO13!!!!
S!GND!J8G1!14!@baseboard_fab2_lib.baseboard_fab2(sch_1):page108_i258@mstr_sconn.sconn200_h68296001(chips)!SCONN200_H68296001_SM-CONN,H68A!!!F235!IO14!!!!
S!SMB_SLOTX24_STBY_LVC3_SDA_R2!J8G1!15!@baseboard_fab2_lib.baseboard_fab2(sch_1):page108_i258@mstr_sconn.sconn200_h68296001(chips)!SCONN200_H68296001_SM-CONN,H68A!!!F235!IO15!!!!
S!IRQ_OOB_MGMT_RISER_ALERT_N!J8G1!16!@baseboard_fab2_lib.baseboard_fab2(sch_1):page108_i258@mstr_sconn.sconn200_h68296001(chips)!SCONN200_H68296001_SM-CONN,H68A!!!F235!IO16!!!!
S!SMB_SLOTX24_STBY_LVC3_SCL_R2!J8G1!17!@baseboard_fab2_lib.baseboard_fab2(sch_1):page108_i258@mstr_sconn.sconn200_h68296001(chips)!SCONN200_H68296001_SM-CONN,H68A!!!F235!IO17!!!!
S!FM_SLT_CFG1!J8G1!18!@baseboard_fab2_lib.baseboard_fab2(sch_1):page108_i258@mstr_sconn.sconn200_h68296001(chips)!SCONN200_H68296001_SM-CONN,H68A!!!F235!IO18!!!!
S!FM_SLT_CFG0!J8G1!19!@baseboard_fab2_lib.baseboard_fab2(sch_1):page108_i258@mstr_sconn.sconn200_h68296001(chips)!SCONN200_H68296001_SM-CONN,H68A!!!F235!IO19!!!!
S!P12V!J8G1!2!@baseboard_fab2_lib.baseboard_fab2(sch_1):page108_i258@mstr_sconn.sconn200_h68296001(chips)!SCONN200_H68296001_SM-CONN,H68A!!!F235!IO2!!!!
S!FM_PWRBRK_SLOT_N!J8G1!20!@baseboard_fab2_lib.baseboard_fab2(sch_1):page108_i258@mstr_sconn.sconn200_h68296001(chips)!SCONN200_H68296001_SM-CONN,H68A!!!F235!IO20!!!!
S!P3V3!J8G1!21!@baseboard_fab2_lib.baseboard_fab2(sch_1):page108_i258@mstr_sconn.sconn200_h68296001(chips)!SCONN200_H68296001_SM-CONN,H68A!!!F235!IO21!!!!
S!P3V3!J8G1!22!@baseboard_fab2_lib.baseboard_fab2(sch_1):page108_i258@mstr_sconn.sconn200_h68296001(chips)!SCONN200_H68296001_SM-CONN,H68A!!!F235!IO22!!!!
S!P3V3!J8G1!23!@baseboard_fab2_lib.baseboard_fab2(sch_1):page108_i258@mstr_sconn.sconn200_h68296001(chips)!SCONN200_H68296001_SM-CONN,H68A!!!F235!IO23!!!!
S!P3V3!J8G1!24!@baseboard_fab2_lib.baseboard_fab2(sch_1):page108_i258@mstr_sconn.sconn200_h68296001(chips)!SCONN200_H68296001_SM-CONN,H68A!!!F235!IO24!!!!
S!P3V3_STBY!J8G1!25!@baseboard_fab2_lib.baseboard_fab2(sch_1):page108_i258@mstr_sconn.sconn200_h68296001(chips)!SCONN200_H68296001_SM-CONN,H68A!!!F235!IO25!!!!
S!GND!J8G1!26!@baseboard_fab2_lib.baseboard_fab2(sch_1):page108_i258@mstr_sconn.sconn200_h68296001(chips)!SCONN200_H68296001_SM-CONN,H68A!!!F235!IO26!!!!
S!FM_PRSNT_2_1_N!J8G1!27!@baseboard_fab2_lib.baseboard_fab2(sch_1):page108_i258@mstr_sconn.sconn200_h68296001(chips)!SCONN200_H68296001_SM-CONN,H68A!!!F235!IO27!!!!
S!FM_PE_SLOTX24_WAKE_N!J8G1!28!@baseboard_fab2_lib.baseboard_fab2(sch_1):page108_i258@mstr_sconn.sconn200_h68296001(chips)!SCONN200_H68296001_SM-CONN,H68A!!!F235!IO28!!!!
S!RST_PCIE_RISER1_PERST_R_N!J8G1!29!@baseboard_fab2_lib.baseboard_fab2(sch_1):page108_i258@mstr_sconn.sconn200_h68296001(chips)!SCONN200_H68296001_SM-CONN,H68A!!!F235!IO29!!!!
S!P12V!J8G1!3!@baseboard_fab2_lib.baseboard_fab2(sch_1):page108_i258@mstr_sconn.sconn200_h68296001(chips)!SCONN200_H68296001_SM-CONN,H68A!!!F235!IO3!!!!
S!FM_PRSNT_2_2_N!J8G1!30!@baseboard_fab2_lib.baseboard_fab2(sch_1):page108_i258@mstr_sconn.sconn200_h68296001(chips)!SCONN200_H68296001_SM-CONN,H68A!!!F235!IO30!!!!
S!GND!J8G1!31!@baseboard_fab2_lib.baseboard_fab2(sch_1):page108_i258@mstr_sconn.sconn200_h68296001(chips)!SCONN200_H68296001_SM-CONN,H68A!!!F235!IO31!!!!
S!FM_PRSNT_2_3_N!J8G1!32!@baseboard_fab2_lib.baseboard_fab2(sch_1):page108_i258@mstr_sconn.sconn200_h68296001(chips)!SCONN200_H68296001_SM-CONN,H68A!!!F235!IO32!!!!
S!CLK_100M_PCH_SLOTX24_S0_DP!J8G1!33!@baseboard_fab2_lib.baseboard_fab2(sch_1):page108_i258@mstr_sconn.sconn200_h68296001(chips)!SCONN200_H68296001_SM-CONN,H68A!!!F235!IO33!!!!
S!GND!J8G1!34!@baseboard_fab2_lib.baseboard_fab2(sch_1):page108_i258@mstr_sconn.sconn200_h68296001(chips)!SCONN200_H68296001_SM-CONN,H68A!!!F235!IO34!!!!
S!CLK_100M_PCH_SLOTX24_S0_DN!J8G1!35!@baseboard_fab2_lib.baseboard_fab2(sch_1):page108_i258@mstr_sconn.sconn200_h68296001(chips)!SCONN200_H68296001_SM-CONN,H68A!!!F235!IO35!!!!
S!CLK_100M_PCH_SLOTX24_S1_DP!J8G1!36!@baseboard_fab2_lib.baseboard_fab2(sch_1):page108_i258@mstr_sconn.sconn200_h68296001(chips)!SCONN200_H68296001_SM-CONN,H68A!!!F235!IO36!!!!
S!GND!J8G1!37!@baseboard_fab2_lib.baseboard_fab2(sch_1):page108_i258@mstr_sconn.sconn200_h68296001(chips)!SCONN200_H68296001_SM-CONN,H68A!!!F235!IO37!!!!
S!CLK_100M_PCH_SLOTX24_S1_DN!J8G1!38!@baseboard_fab2_lib.baseboard_fab2(sch_1):page108_i258@mstr_sconn.sconn200_h68296001(chips)!SCONN200_H68296001_SM-CONN,H68A!!!F235!IO38!!!!
S!CLK_100M_PCH_SLOTX24_S2_DP!J8G1!39!@baseboard_fab2_lib.baseboard_fab2(sch_1):page108_i258@mstr_sconn.sconn200_h68296001(chips)!SCONN200_H68296001_SM-CONN,H68A!!!F235!IO39!!!!
S!P12V!J8G1!4!@baseboard_fab2_lib.baseboard_fab2(sch_1):page108_i258@mstr_sconn.sconn200_h68296001(chips)!SCONN200_H68296001_SM-CONN,H68A!!!F235!IO4!!!!
S!GND!J8G1!40!@baseboard_fab2_lib.baseboard_fab2(sch_1):page108_i258@mstr_sconn.sconn200_h68296001(chips)!SCONN200_H68296001_SM-CONN,H68A!!!F235!IO40!!!!
S!CLK_100M_PCH_SLOTX24_S2_DN!J8G1!41!@baseboard_fab2_lib.baseboard_fab2(sch_1):page108_i258@mstr_sconn.sconn200_h68296001(chips)!SCONN200_H68296001_SM-CONN,H68A!!!F235!IO41!!!!
S!CLK_100M_PCH_SLOTX24_S3_DP!J8G1!42!@baseboard_fab2_lib.baseboard_fab2(sch_1):page108_i258@mstr_sconn.sconn200_h68296001(chips)!SCONN200_H68296001_SM-CONN,H68A!!!F235!IO42!!!!
S!GND!J8G1!43!@baseboard_fab2_lib.baseboard_fab2(sch_1):page108_i258@mstr_sconn.sconn200_h68296001(chips)!SCONN200_H68296001_SM-CONN,H68A!!!F235!IO43!!!!
S!CLK_100M_PCH_SLOTX24_S3_DN!J8G1!44!@baseboard_fab2_lib.baseboard_fab2(sch_1):page108_i258@mstr_sconn.sconn200_h68296001(chips)!SCONN200_H68296001_SM-CONN,H68A!!!F235!IO44!!!!
S!CLK_100M_PCH_SLOTX24_S4_DP!J8G1!45!@baseboard_fab2_lib.baseboard_fab2(sch_1):page108_i258@mstr_sconn.sconn200_h68296001(chips)!SCONN200_H68296001_SM-CONN,H68A!!!F235!IO45!!!!
S!GND!J8G1!46!@baseboard_fab2_lib.baseboard_fab2(sch_1):page108_i258@mstr_sconn.sconn200_h68296001(chips)!SCONN200_H68296001_SM-CONN,H68A!!!F235!IO46!!!!
S!CLK_100M_PCH_SLOTX24_S4_DN!J8G1!47!@baseboard_fab2_lib.baseboard_fab2(sch_1):page108_i258@mstr_sconn.sconn200_h68296001(chips)!SCONN200_H68296001_SM-CONN,H68A!!!F235!IO47!!!!
S!CLK_100M_PCH_SLOTX24_S5_DP!J8G1!48!@baseboard_fab2_lib.baseboard_fab2(sch_1):page108_i258@mstr_sconn.sconn200_h68296001(chips)!SCONN200_H68296001_SM-CONN,H68A!!!F235!IO48!!!!
S!GND!J8G1!49!@baseboard_fab2_lib.baseboard_fab2(sch_1):page108_i258@mstr_sconn.sconn200_h68296001(chips)!SCONN200_H68296001_SM-CONN,H68A!!!F235!IO49!!!!
S!P12V!J8G1!5!@baseboard_fab2_lib.baseboard_fab2(sch_1):page108_i258@mstr_sconn.sconn200_h68296001(chips)!SCONN200_H68296001_SM-CONN,H68A!!!F235!IO5!!!!
S!CLK_100M_PCH_SLOTX24_S5_DN!J8G1!50!@baseboard_fab2_lib.baseboard_fab2(sch_1):page108_i258@mstr_sconn.sconn200_h68296001(chips)!SCONN200_H68296001_SM-CONN,H68A!!!F235!IO50!!!!
S!P3E_CPU0_PE1_SS_C_TXP<0>!J8G1!51!@baseboard_fab2_lib.baseboard_fab2(sch_1):page108_i258@mstr_sconn.sconn200_h68296001(chips)!SCONN200_H68296001_SM-CONN,H68A!!!F235!IO51!!!!
S!GND!J8G1!52!@baseboard_fab2_lib.baseboard_fab2(sch_1):page108_i258@mstr_sconn.sconn200_h68296001(chips)!SCONN200_H68296001_SM-CONN,H68A!!!F235!IO52!!!!
S!P3E_CPU0_PE1_SS_C_TXN<0>!J8G1!53!@baseboard_fab2_lib.baseboard_fab2(sch_1):page108_i258@mstr_sconn.sconn200_h68296001(chips)!SCONN200_H68296001_SM-CONN,H68A!!!F235!IO53!!!!
S!P3E_CPU0_PE1_SS_R_RXP<0>!J8G1!54!@baseboard_fab2_lib.baseboard_fab2(sch_1):page108_i258@mstr_sconn.sconn200_h68296001(chips)!SCONN200_H68296001_SM-CONN,H68A!!!F235!IO54!!!!
S!GND!J8G1!55!@baseboard_fab2_lib.baseboard_fab2(sch_1):page108_i258@mstr_sconn.sconn200_h68296001(chips)!SCONN200_H68296001_SM-CONN,H68A!!!F235!IO55!!!!
S!P3E_CPU0_PE1_SS_R_RXN<0>!J8G1!56!@baseboard_fab2_lib.baseboard_fab2(sch_1):page108_i258@mstr_sconn.sconn200_h68296001(chips)!SCONN200_H68296001_SM-CONN,H68A!!!F235!IO56!!!!
S!P3E_CPU0_PE1_SS_C_TXP<1>!J8G1!57!@baseboard_fab2_lib.baseboard_fab2(sch_1):page108_i258@mstr_sconn.sconn200_h68296001(chips)!SCONN200_H68296001_SM-CONN,H68A!!!F235!IO57!!!!
S!GND!J8G1!58!@baseboard_fab2_lib.baseboard_fab2(sch_1):page108_i258@mstr_sconn.sconn200_h68296001(chips)!SCONN200_H68296001_SM-CONN,H68A!!!F235!IO58!!!!
S!P3E_CPU0_PE1_SS_C_TXN<1>!J8G1!59!@baseboard_fab2_lib.baseboard_fab2(sch_1):page108_i258@mstr_sconn.sconn200_h68296001(chips)!SCONN200_H68296001_SM-CONN,H68A!!!F235!IO59!!!!
S!P12V!J8G1!6!@baseboard_fab2_lib.baseboard_fab2(sch_1):page108_i258@mstr_sconn.sconn200_h68296001(chips)!SCONN200_H68296001_SM-CONN,H68A!!!F235!IO6!!!!
S!P3E_CPU0_PE1_SS_R_RXP<1>!J8G1!60!@baseboard_fab2_lib.baseboard_fab2(sch_1):page108_i258@mstr_sconn.sconn200_h68296001(chips)!SCONN200_H68296001_SM-CONN,H68A!!!F235!IO60!!!!
S!GND!J8G1!61!@baseboard_fab2_lib.baseboard_fab2(sch_1):page108_i258@mstr_sconn.sconn200_h68296001(chips)!SCONN200_H68296001_SM-CONN,H68A!!!F235!IO61!!!!
S!P3E_CPU0_PE1_SS_R_RXN<1>!J8G1!62!@baseboard_fab2_lib.baseboard_fab2(sch_1):page108_i258@mstr_sconn.sconn200_h68296001(chips)!SCONN200_H68296001_SM-CONN,H68A!!!F235!IO62!!!!
S!FM_PRSNT_2_4_N!J8G1!63!@baseboard_fab2_lib.baseboard_fab2(sch_1):page108_i258@mstr_sconn.sconn200_h68296001(chips)!SCONN200_H68296001_SM-CONN,H68A!!!F235!IO63!!!!
S!GND!J8G1!64!@baseboard_fab2_lib.baseboard_fab2(sch_1):page108_i258@mstr_sconn.sconn200_h68296001(chips)!SCONN200_H68296001_SM-CONN,H68A!!!F235!IO64!!!!
S!GND!J8G1!65!@baseboard_fab2_lib.baseboard_fab2(sch_1):page108_i258@mstr_sconn.sconn200_h68296001(chips)!SCONN200_H68296001_SM-CONN,H68A!!!F235!IO65!!!!
S!FM_PRSNT_2_5_N!J8G1!66!@baseboard_fab2_lib.baseboard_fab2(sch_1):page108_i258@mstr_sconn.sconn200_h68296001(chips)!SCONN200_H68296001_SM-CONN,H68A!!!F235!IO66!!!!
S!P3E_CPU0_PE1_SS_C_TXP<2>!J8G1!67!@baseboard_fab2_lib.baseboard_fab2(sch_1):page108_i258@mstr_sconn.sconn200_h68296001(chips)!SCONN200_H68296001_SM-CONN,H68A!!!F235!IO67!!!!
S!GND!J8G1!68!@baseboard_fab2_lib.baseboard_fab2(sch_1):page108_i258@mstr_sconn.sconn200_h68296001(chips)!SCONN200_H68296001_SM-CONN,H68A!!!F235!IO68!!!!
S!P3E_CPU0_PE1_SS_C_TXN<2>!J8G1!69!@baseboard_fab2_lib.baseboard_fab2(sch_1):page108_i258@mstr_sconn.sconn200_h68296001(chips)!SCONN200_H68296001_SM-CONN,H68A!!!F235!IO69!!!!
S!P12V!J8G1!7!@baseboard_fab2_lib.baseboard_fab2(sch_1):page108_i258@mstr_sconn.sconn200_h68296001(chips)!SCONN200_H68296001_SM-CONN,H68A!!!F235!IO7!!!!
S!P3E_CPU0_PE1_SS_R_RXP<2>!J8G1!70!@baseboard_fab2_lib.baseboard_fab2(sch_1):page108_i258@mstr_sconn.sconn200_h68296001(chips)!SCONN200_H68296001_SM-CONN,H68A!!!F235!IO70!!!!
S!GND!J8G1!71!@baseboard_fab2_lib.baseboard_fab2(sch_1):page108_i258@mstr_sconn.sconn200_h68296001(chips)!SCONN200_H68296001_SM-CONN,H68A!!!F235!IO71!!!!
S!P3E_CPU0_PE1_SS_R_RXN<2>!J8G1!72!@baseboard_fab2_lib.baseboard_fab2(sch_1):page108_i258@mstr_sconn.sconn200_h68296001(chips)!SCONN200_H68296001_SM-CONN,H68A!!!F235!IO72!!!!
S!P3E_CPU0_PE1_SS_C_TXP<3>!J8G1!73!@baseboard_fab2_lib.baseboard_fab2(sch_1):page108_i258@mstr_sconn.sconn200_h68296001(chips)!SCONN200_H68296001_SM-CONN,H68A!!!F235!IO73!!!!
S!GND!J8G1!74!@baseboard_fab2_lib.baseboard_fab2(sch_1):page108_i258@mstr_sconn.sconn200_h68296001(chips)!SCONN200_H68296001_SM-CONN,H68A!!!F235!IO74!!!!
S!P3E_CPU0_PE1_SS_C_TXN<3>!J8G1!75!@baseboard_fab2_lib.baseboard_fab2(sch_1):page108_i258@mstr_sconn.sconn200_h68296001(chips)!SCONN200_H68296001_SM-CONN,H68A!!!F235!IO75!!!!
S!P3E_CPU0_PE1_SS_R_RXP<3>!J8G1!76!@baseboard_fab2_lib.baseboard_fab2(sch_1):page108_i258@mstr_sconn.sconn200_h68296001(chips)!SCONN200_H68296001_SM-CONN,H68A!!!F235!IO76!!!!
S!GND!J8G1!77!@baseboard_fab2_lib.baseboard_fab2(sch_1):page108_i258@mstr_sconn.sconn200_h68296001(chips)!SCONN200_H68296001_SM-CONN,H68A!!!F235!IO77!!!!
S!P3E_CPU0_PE1_SS_R_RXN<3>!J8G1!78!@baseboard_fab2_lib.baseboard_fab2(sch_1):page108_i258@mstr_sconn.sconn200_h68296001(chips)!SCONN200_H68296001_SM-CONN,H68A!!!F235!IO78!!!!
S!P3E_CPU0_PE1_SS_C_TXP<4>!J8G1!79!@baseboard_fab2_lib.baseboard_fab2(sch_1):page108_i258@mstr_sconn.sconn200_h68296001(chips)!SCONN200_H68296001_SM-CONN,H68A!!!F235!IO79!!!!
S!P12V!J8G1!8!@baseboard_fab2_lib.baseboard_fab2(sch_1):page108_i258@mstr_sconn.sconn200_h68296001(chips)!SCONN200_H68296001_SM-CONN,H68A!!!F235!IO8!!!!
S!GND!J8G1!80!@baseboard_fab2_lib.baseboard_fab2(sch_1):page108_i258@mstr_sconn.sconn200_h68296001(chips)!SCONN200_H68296001_SM-CONN,H68A!!!F235!IO80!!!!
S!P3E_CPU0_PE1_SS_C_TXN<4>!J8G1!81!@baseboard_fab2_lib.baseboard_fab2(sch_1):page108_i258@mstr_sconn.sconn200_h68296001(chips)!SCONN200_H68296001_SM-CONN,H68A!!!F235!IO81!!!!
S!P3E_CPU0_PE1_SS_R_RXP<4>!J8G1!82!@baseboard_fab2_lib.baseboard_fab2(sch_1):page108_i258@mstr_sconn.sconn200_h68296001(chips)!SCONN200_H68296001_SM-CONN,H68A!!!F235!IO82!!!!
S!GND!J8G1!83!@baseboard_fab2_lib.baseboard_fab2(sch_1):page108_i258@mstr_sconn.sconn200_h68296001(chips)!SCONN200_H68296001_SM-CONN,H68A!!!F235!IO83!!!!
S!P3E_CPU0_PE1_SS_R_RXN<4>!J8G1!84!@baseboard_fab2_lib.baseboard_fab2(sch_1):page108_i258@mstr_sconn.sconn200_h68296001(chips)!SCONN200_H68296001_SM-CONN,H68A!!!F235!IO84!!!!
S!P3E_CPU0_PE1_SS_C_TXP<5>!J8G1!85!@baseboard_fab2_lib.baseboard_fab2(sch_1):page108_i258@mstr_sconn.sconn200_h68296001(chips)!SCONN200_H68296001_SM-CONN,H68A!!!F235!IO85!!!!
S!GND!J8G1!86!@baseboard_fab2_lib.baseboard_fab2(sch_1):page108_i258@mstr_sconn.sconn200_h68296001(chips)!SCONN200_H68296001_SM-CONN,H68A!!!F235!IO86!!!!
S!P3E_CPU0_PE1_SS_C_TXN<5>!J8G1!87!@baseboard_fab2_lib.baseboard_fab2(sch_1):page108_i258@mstr_sconn.sconn200_h68296001(chips)!SCONN200_H68296001_SM-CONN,H68A!!!F235!IO87!!!!
S!P3E_CPU0_PE1_SS_R_RXP<5>!J8G1!88!@baseboard_fab2_lib.baseboard_fab2(sch_1):page108_i258@mstr_sconn.sconn200_h68296001(chips)!SCONN200_H68296001_SM-CONN,H68A!!!F235!IO88!!!!
S!GND!J8G1!89!@baseboard_fab2_lib.baseboard_fab2(sch_1):page108_i258@mstr_sconn.sconn200_h68296001(chips)!SCONN200_H68296001_SM-CONN,H68A!!!F235!IO89!!!!
S!P12V!J8G1!9!@baseboard_fab2_lib.baseboard_fab2(sch_1):page108_i258@mstr_sconn.sconn200_h68296001(chips)!SCONN200_H68296001_SM-CONN,H68A!!!F235!IO9!!!!
S!P3E_CPU0_PE1_SS_R_RXN<5>!J8G1!90!@baseboard_fab2_lib.baseboard_fab2(sch_1):page108_i258@mstr_sconn.sconn200_h68296001(chips)!SCONN200_H68296001_SM-CONN,H68A!!!F235!IO90!!!!
S!P3E_CPU0_PE1_SS_C_TXP<6>!J8G1!91!@baseboard_fab2_lib.baseboard_fab2(sch_1):page108_i258@mstr_sconn.sconn200_h68296001(chips)!SCONN200_H68296001_SM-CONN,H68A!!!F235!IO91!!!!
S!GND!J8G1!92!@baseboard_fab2_lib.baseboard_fab2(sch_1):page108_i258@mstr_sconn.sconn200_h68296001(chips)!SCONN200_H68296001_SM-CONN,H68A!!!F235!IO92!!!!
S!P3E_CPU0_PE1_SS_C_TXN<6>!J8G1!93!@baseboard_fab2_lib.baseboard_fab2(sch_1):page108_i258@mstr_sconn.sconn200_h68296001(chips)!SCONN200_H68296001_SM-CONN,H68A!!!F235!IO93!!!!
S!P3E_CPU0_PE1_SS_R_RXP<6>!J8G1!94!@baseboard_fab2_lib.baseboard_fab2(sch_1):page108_i258@mstr_sconn.sconn200_h68296001(chips)!SCONN200_H68296001_SM-CONN,H68A!!!F235!IO94!!!!
S!GND!J8G1!95!@baseboard_fab2_lib.baseboard_fab2(sch_1):page108_i258@mstr_sconn.sconn200_h68296001(chips)!SCONN200_H68296001_SM-CONN,H68A!!!F235!IO95!!!!
S!P3E_CPU0_PE1_SS_R_RXN<6>!J8G1!96!@baseboard_fab2_lib.baseboard_fab2(sch_1):page108_i258@mstr_sconn.sconn200_h68296001(chips)!SCONN200_H68296001_SM-CONN,H68A!!!F235!IO96!!!!
S!P3E_CPU0_PE1_SS_C_TXP<7>!J8G1!97!@baseboard_fab2_lib.baseboard_fab2(sch_1):page108_i258@mstr_sconn.sconn200_h68296001(chips)!SCONN200_H68296001_SM-CONN,H68A!!!F235!IO97!!!!
S!GND!J8G1!98!@baseboard_fab2_lib.baseboard_fab2(sch_1):page108_i258@mstr_sconn.sconn200_h68296001(chips)!SCONN200_H68296001_SM-CONN,H68A!!!F235!IO98!!!!
S!P3E_CPU0_PE1_SS_C_TXN<7>!J8G1!99!@baseboard_fab2_lib.baseboard_fab2(sch_1):page108_i258@mstr_sconn.sconn200_h68296001(chips)!SCONN200_H68296001_SM-CONN,H68A!!!F235!IO99!!!!
S!GND!J8G1!MH1!@baseboard_fab2_lib.baseboard_fab2(sch_1):page108_i258@mstr_sconn.sconn200_h68296001(chips)!SCONN200_H68296001_SM-CONN,H68A!!!F235!MH1!!!!
S!GND!J8G1!MH2!@baseboard_fab2_lib.baseboard_fab2(sch_1):page108_i258@mstr_sconn.sconn200_h68296001(chips)!SCONN200_H68296001_SM-CONN,H68A!!!F235!MH2!!!!
S!GND!J8G1!101!@baseboard_fab2_lib.baseboard_fab2(sch_1):page109_i243@mstr_sconn.sconn200_h68296001(chips)!SCONN200_H68296001_SM-CONN,H68A!!!F234!IO101!!!!
S!P3E_CPU0_PE1_SS_R_RXN<7>!J8G1!102!@baseboard_fab2_lib.baseboard_fab2(sch_1):page109_i243@mstr_sconn.sconn200_h68296001(chips)!SCONN200_H68296001_SM-CONN,H68A!!!F234!IO102!!!!
S!P3E_CPU0_PE2_SS_C_TXN<0>!J8G1!103!@baseboard_fab2_lib.baseboard_fab2(sch_1):page109_i243@mstr_sconn.sconn200_h68296001(chips)!SCONN200_H68296001_SM-CONN,H68A!!!F234!IO103!!!!
S!GND!J8G1!104!@baseboard_fab2_lib.baseboard_fab2(sch_1):page109_i243@mstr_sconn.sconn200_h68296001(chips)!SCONN200_H68296001_SM-CONN,H68A!!!F234!IO104!!!!
S!P3E_CPU0_PE2_SS_C_TXP<0>!J8G1!105!@baseboard_fab2_lib.baseboard_fab2(sch_1):page109_i243@mstr_sconn.sconn200_h68296001(chips)!SCONN200_H68296001_SM-CONN,H68A!!!F234!IO105!!!!
S!P3E_CPU0_PE2_SS_RXN<0>!J8G1!106!@baseboard_fab2_lib.baseboard_fab2(sch_1):page109_i243@mstr_sconn.sconn200_h68296001(chips)!SCONN200_H68296001_SM-CONN,H68A!!!F234!IO106!!!!
S!GND!J8G1!107!@baseboard_fab2_lib.baseboard_fab2(sch_1):page109_i243@mstr_sconn.sconn200_h68296001(chips)!SCONN200_H68296001_SM-CONN,H68A!!!F234!IO107!!!!
S!P3E_CPU0_PE2_SS_RXP<0>!J8G1!108!@baseboard_fab2_lib.baseboard_fab2(sch_1):page109_i243@mstr_sconn.sconn200_h68296001(chips)!SCONN200_H68296001_SM-CONN,H68A!!!F234!IO108!!!!
S!P3E_CPU0_PE2_SS_C_TXP<1>!J8G1!109!@baseboard_fab2_lib.baseboard_fab2(sch_1):page109_i243@mstr_sconn.sconn200_h68296001(chips)!SCONN200_H68296001_SM-CONN,H68A!!!F234!IO109!!!!
S!GND!J8G1!110!@baseboard_fab2_lib.baseboard_fab2(sch_1):page109_i243@mstr_sconn.sconn200_h68296001(chips)!SCONN200_H68296001_SM-CONN,H68A!!!F234!IO110!!!!
S!P3E_CPU0_PE2_SS_C_TXN<1>!J8G1!111!@baseboard_fab2_lib.baseboard_fab2(sch_1):page109_i243@mstr_sconn.sconn200_h68296001(chips)!SCONN200_H68296001_SM-CONN,H68A!!!F234!IO111!!!!
S!P3E_CPU0_PE2_SS_RXN<1>!J8G1!112!@baseboard_fab2_lib.baseboard_fab2(sch_1):page109_i243@mstr_sconn.sconn200_h68296001(chips)!SCONN200_H68296001_SM-CONN,H68A!!!F234!IO112!!!!
S!GND!J8G1!113!@baseboard_fab2_lib.baseboard_fab2(sch_1):page109_i243@mstr_sconn.sconn200_h68296001(chips)!SCONN200_H68296001_SM-CONN,H68A!!!F234!IO113!!!!
S!P3E_CPU0_PE2_SS_RXP<1>!J8G1!114!@baseboard_fab2_lib.baseboard_fab2(sch_1):page109_i243@mstr_sconn.sconn200_h68296001(chips)!SCONN200_H68296001_SM-CONN,H68A!!!F234!IO114!!!!
S!P3E_CPU0_PE2_SS_C_TXN<2>!J8G1!115!@baseboard_fab2_lib.baseboard_fab2(sch_1):page109_i243@mstr_sconn.sconn200_h68296001(chips)!SCONN200_H68296001_SM-CONN,H68A!!!F234!IO115!!!!
S!GND!J8G1!116!@baseboard_fab2_lib.baseboard_fab2(sch_1):page109_i243@mstr_sconn.sconn200_h68296001(chips)!SCONN200_H68296001_SM-CONN,H68A!!!F234!IO116!!!!
S!P3E_CPU0_PE2_SS_C_TXP<2>!J8G1!117!@baseboard_fab2_lib.baseboard_fab2(sch_1):page109_i243@mstr_sconn.sconn200_h68296001(chips)!SCONN200_H68296001_SM-CONN,H68A!!!F234!IO117!!!!
S!P3E_CPU0_PE2_SS_RXN<2>!J8G1!118!@baseboard_fab2_lib.baseboard_fab2(sch_1):page109_i243@mstr_sconn.sconn200_h68296001(chips)!SCONN200_H68296001_SM-CONN,H68A!!!F234!IO118!!!!
S!GND!J8G1!119!@baseboard_fab2_lib.baseboard_fab2(sch_1):page109_i243@mstr_sconn.sconn200_h68296001(chips)!SCONN200_H68296001_SM-CONN,H68A!!!F234!IO119!!!!
S!P3E_CPU0_PE2_SS_RXP<2>!J8G1!120!@baseboard_fab2_lib.baseboard_fab2(sch_1):page109_i243@mstr_sconn.sconn200_h68296001(chips)!SCONN200_H68296001_SM-CONN,H68A!!!F234!IO120!!!!
S!P3E_CPU0_PE2_SS_C_TXN<3>!J8G1!121!@baseboard_fab2_lib.baseboard_fab2(sch_1):page109_i243@mstr_sconn.sconn200_h68296001(chips)!SCONN200_H68296001_SM-CONN,H68A!!!F234!IO121!!!!
S!GND!J8G1!122!@baseboard_fab2_lib.baseboard_fab2(sch_1):page109_i243@mstr_sconn.sconn200_h68296001(chips)!SCONN200_H68296001_SM-CONN,H68A!!!F234!IO122!!!!
S!P3E_CPU0_PE2_SS_C_TXP<3>!J8G1!123!@baseboard_fab2_lib.baseboard_fab2(sch_1):page109_i243@mstr_sconn.sconn200_h68296001(chips)!SCONN200_H68296001_SM-CONN,H68A!!!F234!IO123!!!!
S!P3E_CPU0_PE2_SS_RXN<3>!J8G1!124!@baseboard_fab2_lib.baseboard_fab2(sch_1):page109_i243@mstr_sconn.sconn200_h68296001(chips)!SCONN200_H68296001_SM-CONN,H68A!!!F234!IO124!!!!
S!GND!J8G1!125!@baseboard_fab2_lib.baseboard_fab2(sch_1):page109_i243@mstr_sconn.sconn200_h68296001(chips)!SCONN200_H68296001_SM-CONN,H68A!!!F234!IO125!!!!
S!P3E_CPU0_PE2_SS_RXP<3>!J8G1!126!@baseboard_fab2_lib.baseboard_fab2(sch_1):page109_i243@mstr_sconn.sconn200_h68296001(chips)!SCONN200_H68296001_SM-CONN,H68A!!!F234!IO126!!!!
S!P3E_CPU0_PE2_SS_C_TXN<4>!J8G1!127!@baseboard_fab2_lib.baseboard_fab2(sch_1):page109_i243@mstr_sconn.sconn200_h68296001(chips)!SCONN200_H68296001_SM-CONN,H68A!!!F234!IO127!!!!
S!GND!J8G1!128!@baseboard_fab2_lib.baseboard_fab2(sch_1):page109_i243@mstr_sconn.sconn200_h68296001(chips)!SCONN200_H68296001_SM-CONN,H68A!!!F234!IO128!!!!
S!P3E_CPU0_PE2_SS_C_TXP<4>!J8G1!129!@baseboard_fab2_lib.baseboard_fab2(sch_1):page109_i243@mstr_sconn.sconn200_h68296001(chips)!SCONN200_H68296001_SM-CONN,H68A!!!F234!IO129!!!!
S!P3E_CPU0_PE2_SS_RXN<4>!J8G1!130!@baseboard_fab2_lib.baseboard_fab2(sch_1):page109_i243@mstr_sconn.sconn200_h68296001(chips)!SCONN200_H68296001_SM-CONN,H68A!!!F234!IO130!!!!
S!GND!J8G1!131!@baseboard_fab2_lib.baseboard_fab2(sch_1):page109_i243@mstr_sconn.sconn200_h68296001(chips)!SCONN200_H68296001_SM-CONN,H68A!!!F234!IO131!!!!
S!P3E_CPU0_PE2_SS_RXP<4>!J8G1!132!@baseboard_fab2_lib.baseboard_fab2(sch_1):page109_i243@mstr_sconn.sconn200_h68296001(chips)!SCONN200_H68296001_SM-CONN,H68A!!!F234!IO132!!!!
S!P3E_CPU0_PE2_SS_C_TXN<5>!J8G1!133!@baseboard_fab2_lib.baseboard_fab2(sch_1):page109_i243@mstr_sconn.sconn200_h68296001(chips)!SCONN200_H68296001_SM-CONN,H68A!!!F234!IO133!!!!
S!GND!J8G1!134!@baseboard_fab2_lib.baseboard_fab2(sch_1):page109_i243@mstr_sconn.sconn200_h68296001(chips)!SCONN200_H68296001_SM-CONN,H68A!!!F234!IO134!!!!
S!P3E_CPU0_PE2_SS_C_TXP<5>!J8G1!135!@baseboard_fab2_lib.baseboard_fab2(sch_1):page109_i243@mstr_sconn.sconn200_h68296001(chips)!SCONN200_H68296001_SM-CONN,H68A!!!F234!IO135!!!!
S!P3E_CPU0_PE2_SS_RXN<5>!J8G1!136!@baseboard_fab2_lib.baseboard_fab2(sch_1):page109_i243@mstr_sconn.sconn200_h68296001(chips)!SCONN200_H68296001_SM-CONN,H68A!!!F234!IO136!!!!
S!GND!J8G1!137!@baseboard_fab2_lib.baseboard_fab2(sch_1):page109_i243@mstr_sconn.sconn200_h68296001(chips)!SCONN200_H68296001_SM-CONN,H68A!!!F234!IO137!!!!
S!P3E_CPU0_PE2_SS_RXP<5>!J8G1!138!@baseboard_fab2_lib.baseboard_fab2(sch_1):page109_i243@mstr_sconn.sconn200_h68296001(chips)!SCONN200_H68296001_SM-CONN,H68A!!!F234!IO138!!!!
S!P3E_CPU0_PE2_SS_C_TXN<6>!J8G1!139!@baseboard_fab2_lib.baseboard_fab2(sch_1):page109_i243@mstr_sconn.sconn200_h68296001(chips)!SCONN200_H68296001_SM-CONN,H68A!!!F234!IO139!!!!
S!GND!J8G1!140!@baseboard_fab2_lib.baseboard_fab2(sch_1):page109_i243@mstr_sconn.sconn200_h68296001(chips)!SCONN200_H68296001_SM-CONN,H68A!!!F234!IO140!!!!
S!P3E_CPU0_PE2_SS_C_TXP<6>!J8G1!141!@baseboard_fab2_lib.baseboard_fab2(sch_1):page109_i243@mstr_sconn.sconn200_h68296001(chips)!SCONN200_H68296001_SM-CONN,H68A!!!F234!IO141!!!!
S!P3E_CPU0_PE2_SS_RXP<6>!J8G1!142!@baseboard_fab2_lib.baseboard_fab2(sch_1):page109_i243@mstr_sconn.sconn200_h68296001(chips)!SCONN200_H68296001_SM-CONN,H68A!!!F234!IO142!!!!
S!GND!J8G1!143!@baseboard_fab2_lib.baseboard_fab2(sch_1):page109_i243@mstr_sconn.sconn200_h68296001(chips)!SCONN200_H68296001_SM-CONN,H68A!!!F234!IO143!!!!
S!P3E_CPU0_PE2_SS_RXN<6>!J8G1!144!@baseboard_fab2_lib.baseboard_fab2(sch_1):page109_i243@mstr_sconn.sconn200_h68296001(chips)!SCONN200_H68296001_SM-CONN,H68A!!!F234!IO144!!!!
S!P3E_CPU0_PE2_SS_C_TXN<7>!J8G1!145!@baseboard_fab2_lib.baseboard_fab2(sch_1):page109_i243@mstr_sconn.sconn200_h68296001(chips)!SCONN200_H68296001_SM-CONN,H68A!!!F234!IO145!!!!
S!GND!J8G1!146!@baseboard_fab2_lib.baseboard_fab2(sch_1):page109_i243@mstr_sconn.sconn200_h68296001(chips)!SCONN200_H68296001_SM-CONN,H68A!!!F234!IO146!!!!
S!P3E_CPU0_PE2_SS_C_TXP<7>!J8G1!147!@baseboard_fab2_lib.baseboard_fab2(sch_1):page109_i243@mstr_sconn.sconn200_h68296001(chips)!SCONN200_H68296001_SM-CONN,H68A!!!F234!IO147!!!!
S!P3E_CPU0_PE2_SS_RXN<7>!J8G1!148!@baseboard_fab2_lib.baseboard_fab2(sch_1):page109_i243@mstr_sconn.sconn200_h68296001(chips)!SCONN200_H68296001_SM-CONN,H68A!!!F234!IO148!!!!
S!GND!J8G1!149!@baseboard_fab2_lib.baseboard_fab2(sch_1):page109_i243@mstr_sconn.sconn200_h68296001(chips)!SCONN200_H68296001_SM-CONN,H68A!!!F234!IO149!!!!
S!P3E_CPU0_PE2_SS_RXP<7>!J8G1!150!@baseboard_fab2_lib.baseboard_fab2(sch_1):page109_i243@mstr_sconn.sconn200_h68296001(chips)!SCONN200_H68296001_SM-CONN,H68A!!!F234!IO150!!!!
S!P3E_CPU0_PE2_SS_C_TXN<8>!J8G1!151!@baseboard_fab2_lib.baseboard_fab2(sch_1):page109_i243@mstr_sconn.sconn200_h68296001(chips)!SCONN200_H68296001_SM-CONN,H68A!!!F234!IO151!!!!
S!GND!J8G1!152!@baseboard_fab2_lib.baseboard_fab2(sch_1):page109_i243@mstr_sconn.sconn200_h68296001(chips)!SCONN200_H68296001_SM-CONN,H68A!!!F234!IO152!!!!
S!P3E_CPU0_PE2_SS_C_TXP<8>!J8G1!153!@baseboard_fab2_lib.baseboard_fab2(sch_1):page109_i243@mstr_sconn.sconn200_h68296001(chips)!SCONN200_H68296001_SM-CONN,H68A!!!F234!IO153!!!!
S!P3E_CPU0_PE2_SS_RXN<8>!J8G1!154!@baseboard_fab2_lib.baseboard_fab2(sch_1):page109_i243@mstr_sconn.sconn200_h68296001(chips)!SCONN200_H68296001_SM-CONN,H68A!!!F234!IO154!!!!
S!GND!J8G1!155!@baseboard_fab2_lib.baseboard_fab2(sch_1):page109_i243@mstr_sconn.sconn200_h68296001(chips)!SCONN200_H68296001_SM-CONN,H68A!!!F234!IO155!!!!
S!P3E_CPU0_PE2_SS_RXP<8>!J8G1!156!@baseboard_fab2_lib.baseboard_fab2(sch_1):page109_i243@mstr_sconn.sconn200_h68296001(chips)!SCONN200_H68296001_SM-CONN,H68A!!!F234!IO156!!!!
S!P3E_CPU0_PE2_SS_C_TXN<9>!J8G1!157!@baseboard_fab2_lib.baseboard_fab2(sch_1):page109_i243@mstr_sconn.sconn200_h68296001(chips)!SCONN200_H68296001_SM-CONN,H68A!!!F234!IO157!!!!
S!GND!J8G1!158!@baseboard_fab2_lib.baseboard_fab2(sch_1):page109_i243@mstr_sconn.sconn200_h68296001(chips)!SCONN200_H68296001_SM-CONN,H68A!!!F234!IO158!!!!
S!P3E_CPU0_PE2_SS_C_TXP<9>!J8G1!159!@baseboard_fab2_lib.baseboard_fab2(sch_1):page109_i243@mstr_sconn.sconn200_h68296001(chips)!SCONN200_H68296001_SM-CONN,H68A!!!F234!IO159!!!!
S!P3E_CPU0_PE2_SS_RXN<9>!J8G1!160!@baseboard_fab2_lib.baseboard_fab2(sch_1):page109_i243@mstr_sconn.sconn200_h68296001(chips)!SCONN200_H68296001_SM-CONN,H68A!!!F234!IO160!!!!
S!GND!J8G1!161!@baseboard_fab2_lib.baseboard_fab2(sch_1):page109_i243@mstr_sconn.sconn200_h68296001(chips)!SCONN200_H68296001_SM-CONN,H68A!!!F234!IO161!!!!
S!P3E_CPU0_PE2_SS_RXP<9>!J8G1!162!@baseboard_fab2_lib.baseboard_fab2(sch_1):page109_i243@mstr_sconn.sconn200_h68296001(chips)!SCONN200_H68296001_SM-CONN,H68A!!!F234!IO162!!!!
S!P3E_CPU0_PE2_SS_C_TXN<10>!J8G1!163!@baseboard_fab2_lib.baseboard_fab2(sch_1):page109_i243@mstr_sconn.sconn200_h68296001(chips)!SCONN200_H68296001_SM-CONN,H68A!!!F234!IO163!!!!
S!GND!J8G1!164!@baseboard_fab2_lib.baseboard_fab2(sch_1):page109_i243@mstr_sconn.sconn200_h68296001(chips)!SCONN200_H68296001_SM-CONN,H68A!!!F234!IO164!!!!
S!P3E_CPU0_PE2_SS_C_TXP<10>!J8G1!165!@baseboard_fab2_lib.baseboard_fab2(sch_1):page109_i243@mstr_sconn.sconn200_h68296001(chips)!SCONN200_H68296001_SM-CONN,H68A!!!F234!IO165!!!!
S!P3E_CPU0_PE2_SS_RXN<10>!J8G1!166!@baseboard_fab2_lib.baseboard_fab2(sch_1):page109_i243@mstr_sconn.sconn200_h68296001(chips)!SCONN200_H68296001_SM-CONN,H68A!!!F234!IO166!!!!
S!GND!J8G1!167!@baseboard_fab2_lib.baseboard_fab2(sch_1):page109_i243@mstr_sconn.sconn200_h68296001(chips)!SCONN200_H68296001_SM-CONN,H68A!!!F234!IO167!!!!
S!P3E_CPU0_PE2_SS_RXP<10>!J8G1!168!@baseboard_fab2_lib.baseboard_fab2(sch_1):page109_i243@mstr_sconn.sconn200_h68296001(chips)!SCONN200_H68296001_SM-CONN,H68A!!!F234!IO168!!!!
S!P3E_CPU0_PE2_SS_C_TXP<11>!J8G1!169!@baseboard_fab2_lib.baseboard_fab2(sch_1):page109_i243@mstr_sconn.sconn200_h68296001(chips)!SCONN200_H68296001_SM-CONN,H68A!!!F234!IO169!!!!
S!GND!J8G1!170!@baseboard_fab2_lib.baseboard_fab2(sch_1):page109_i243@mstr_sconn.sconn200_h68296001(chips)!SCONN200_H68296001_SM-CONN,H68A!!!F234!IO170!!!!
S!P3E_CPU0_PE2_SS_C_TXN<11>!J8G1!171!@baseboard_fab2_lib.baseboard_fab2(sch_1):page109_i243@mstr_sconn.sconn200_h68296001(chips)!SCONN200_H68296001_SM-CONN,H68A!!!F234!IO171!!!!
S!P3E_CPU0_PE2_SS_RXN<11>!J8G1!172!@baseboard_fab2_lib.baseboard_fab2(sch_1):page109_i243@mstr_sconn.sconn200_h68296001(chips)!SCONN200_H68296001_SM-CONN,H68A!!!F234!IO172!!!!
S!GND!J8G1!173!@baseboard_fab2_lib.baseboard_fab2(sch_1):page109_i243@mstr_sconn.sconn200_h68296001(chips)!SCONN200_H68296001_SM-CONN,H68A!!!F234!IO173!!!!
S!P3E_CPU0_PE2_SS_RXP<11>!J8G1!174!@baseboard_fab2_lib.baseboard_fab2(sch_1):page109_i243@mstr_sconn.sconn200_h68296001(chips)!SCONN200_H68296001_SM-CONN,H68A!!!F234!IO174!!!!
S!P3E_CPU0_PE2_SS_C_TXN<12>!J8G1!175!@baseboard_fab2_lib.baseboard_fab2(sch_1):page109_i243@mstr_sconn.sconn200_h68296001(chips)!SCONN200_H68296001_SM-CONN,H68A!!!F234!IO175!!!!
S!GND!J8G1!176!@baseboard_fab2_lib.baseboard_fab2(sch_1):page109_i243@mstr_sconn.sconn200_h68296001(chips)!SCONN200_H68296001_SM-CONN,H68A!!!F234!IO176!!!!
S!P3E_CPU0_PE2_SS_C_TXP<12>!J8G1!177!@baseboard_fab2_lib.baseboard_fab2(sch_1):page109_i243@mstr_sconn.sconn200_h68296001(chips)!SCONN200_H68296001_SM-CONN,H68A!!!F234!IO177!!!!
S!P3E_CPU0_PE2_SS_RXN<12>!J8G1!178!@baseboard_fab2_lib.baseboard_fab2(sch_1):page109_i243@mstr_sconn.sconn200_h68296001(chips)!SCONN200_H68296001_SM-CONN,H68A!!!F234!IO178!!!!
S!GND!J8G1!179!@baseboard_fab2_lib.baseboard_fab2(sch_1):page109_i243@mstr_sconn.sconn200_h68296001(chips)!SCONN200_H68296001_SM-CONN,H68A!!!F234!IO179!!!!
S!P3E_CPU0_PE2_SS_RXP<12>!J8G1!180!@baseboard_fab2_lib.baseboard_fab2(sch_1):page109_i243@mstr_sconn.sconn200_h68296001(chips)!SCONN200_H68296001_SM-CONN,H68A!!!F234!IO180!!!!
S!P3E_CPU0_PE2_SS_C_TXN<13>!J8G1!181!@baseboard_fab2_lib.baseboard_fab2(sch_1):page109_i243@mstr_sconn.sconn200_h68296001(chips)!SCONN200_H68296001_SM-CONN,H68A!!!F234!IO181!!!!
S!GND!J8G1!182!@baseboard_fab2_lib.baseboard_fab2(sch_1):page109_i243@mstr_sconn.sconn200_h68296001(chips)!SCONN200_H68296001_SM-CONN,H68A!!!F234!IO182!!!!
S!P3E_CPU0_PE2_SS_C_TXP<13>!J8G1!183!@baseboard_fab2_lib.baseboard_fab2(sch_1):page109_i243@mstr_sconn.sconn200_h68296001(chips)!SCONN200_H68296001_SM-CONN,H68A!!!F234!IO183!!!!
S!P3E_CPU0_PE2_SS_RXP<13>!J8G1!184!@baseboard_fab2_lib.baseboard_fab2(sch_1):page109_i243@mstr_sconn.sconn200_h68296001(chips)!SCONN200_H68296001_SM-CONN,H68A!!!F234!IO184!!!!
S!GND!J8G1!185!@baseboard_fab2_lib.baseboard_fab2(sch_1):page109_i243@mstr_sconn.sconn200_h68296001(chips)!SCONN200_H68296001_SM-CONN,H68A!!!F234!IO185!!!!
S!P3E_CPU0_PE2_SS_RXN<13>!J8G1!186!@baseboard_fab2_lib.baseboard_fab2(sch_1):page109_i243@mstr_sconn.sconn200_h68296001(chips)!SCONN200_H68296001_SM-CONN,H68A!!!F234!IO186!!!!
S!P3E_CPU0_PE2_SS_C_TXP<14>!J8G1!187!@baseboard_fab2_lib.baseboard_fab2(sch_1):page109_i243@mstr_sconn.sconn200_h68296001(chips)!SCONN200_H68296001_SM-CONN,H68A!!!F234!IO187!!!!
S!GND!J8G1!188!@baseboard_fab2_lib.baseboard_fab2(sch_1):page109_i243@mstr_sconn.sconn200_h68296001(chips)!SCONN200_H68296001_SM-CONN,H68A!!!F234!IO188!!!!
S!P3E_CPU0_PE2_SS_C_TXN<14>!J8G1!189!@baseboard_fab2_lib.baseboard_fab2(sch_1):page109_i243@mstr_sconn.sconn200_h68296001(chips)!SCONN200_H68296001_SM-CONN,H68A!!!F234!IO189!!!!
S!P3E_CPU0_PE2_SS_RXN<14>!J8G1!190!@baseboard_fab2_lib.baseboard_fab2(sch_1):page109_i243@mstr_sconn.sconn200_h68296001(chips)!SCONN200_H68296001_SM-CONN,H68A!!!F234!IO190!!!!
S!GND!J8G1!191!@baseboard_fab2_lib.baseboard_fab2(sch_1):page109_i243@mstr_sconn.sconn200_h68296001(chips)!SCONN200_H68296001_SM-CONN,H68A!!!F234!IO191!!!!
S!P3E_CPU0_PE2_SS_RXP<14>!J8G1!192!@baseboard_fab2_lib.baseboard_fab2(sch_1):page109_i243@mstr_sconn.sconn200_h68296001(chips)!SCONN200_H68296001_SM-CONN,H68A!!!F234!IO192!!!!
S!P3E_CPU0_PE2_SS_C_TXN<15>!J8G1!193!@baseboard_fab2_lib.baseboard_fab2(sch_1):page109_i243@mstr_sconn.sconn200_h68296001(chips)!SCONN200_H68296001_SM-CONN,H68A!!!F234!IO193!!!!
S!GND!J8G1!194!@baseboard_fab2_lib.baseboard_fab2(sch_1):page109_i243@mstr_sconn.sconn200_h68296001(chips)!SCONN200_H68296001_SM-CONN,H68A!!!F234!IO194!!!!
S!P3E_CPU0_PE2_SS_C_TXP<15>!J8G1!195!@baseboard_fab2_lib.baseboard_fab2(sch_1):page109_i243@mstr_sconn.sconn200_h68296001(chips)!SCONN200_H68296001_SM-CONN,H68A!!!F234!IO195!!!!
S!P3E_CPU0_PE2_SS_RXN<15>!J8G1!196!@baseboard_fab2_lib.baseboard_fab2(sch_1):page109_i243@mstr_sconn.sconn200_h68296001(chips)!SCONN200_H68296001_SM-CONN,H68A!!!F234!IO196!!!!
S!GND!J8G1!197!@baseboard_fab2_lib.baseboard_fab2(sch_1):page109_i243@mstr_sconn.sconn200_h68296001(chips)!SCONN200_H68296001_SM-CONN,H68A!!!F234!IO197!!!!
S!P3E_CPU0_PE2_SS_RXP<15>!J8G1!198!@baseboard_fab2_lib.baseboard_fab2(sch_1):page109_i243@mstr_sconn.sconn200_h68296001(chips)!SCONN200_H68296001_SM-CONN,H68A!!!F234!IO198!!!!
S!FM_PRSNT_2_6_N!J8G1!199!@baseboard_fab2_lib.baseboard_fab2(sch_1):page109_i243@mstr_sconn.sconn200_h68296001(chips)!SCONN200_H68296001_SM-CONN,H68A!!!F234!IO199!!!!
S!GND!J8G1!200!@baseboard_fab2_lib.baseboard_fab2(sch_1):page109_i243@mstr_sconn.sconn200_h68296001(chips)!SCONN200_H68296001_SM-CONN,H68A!!!F234!IO200!!!!
S!GND!U8D8!5!@baseboard_fab2_lib.baseboard_fab2(sch_1):page196_i104@mstr_vreg.tps3700(chips)!TPS3700_SM-IC,H69492-001!!!F49!GND!!!!
S!A_PG_P12V_MAIN!U8D8!4!@baseboard_fab2_lib.baseboard_fab2(sch_1):page196_i104@mstr_vreg.tps3700(chips)!TPS3700_SM-IC,H69492-001!!!F49!INAP!!!!
S!A_PG_P5V!U8D8!3!@baseboard_fab2_lib.baseboard_fab2(sch_1):page196_i104@mstr_vreg.tps3700(chips)!TPS3700_SM-IC,H69492-001!!!F49!INBN!!!!
S!PWRGD_P12V_MAIN_R!U8D8!6!@baseboard_fab2_lib.baseboard_fab2(sch_1):page196_i104@mstr_vreg.tps3700(chips)!TPS3700_SM-IC,H69492-001!!!F49!OUTA!!!!
S!PWRGD_P5V_N!U8D8!1!@baseboard_fab2_lib.baseboard_fab2(sch_1):page196_i104@mstr_vreg.tps3700(chips)!TPS3700_SM-IC,H69492-001!!!F49!OUTB!!!!
S!P3V3_STBY!U8D8!2!@baseboard_fab2_lib.baseboard_fab2(sch_1):page196_i104@mstr_vreg.tps3700(chips)!TPS3700_SM-IC,H69492-001!!!F49!VDD!!!!
S!GND!U9P2!5!@baseboard_fab2_lib.baseboard_fab2(sch_1):page200_i200@mstr_vreg.tps3700(chips)!TPS3700_SM-IC,H69492-001!!!F47!GND!!!!
S!A_HSC_INAP!U9P2!4!@baseboard_fab2_lib.baseboard_fab2(sch_1):page200_i200@mstr_vreg.tps3700(chips)!TPS3700_SM-IC,H69492-001!!!F47!INAP!!!!
S!A_HSC_TIMER_R!U9P2!3!@baseboard_fab2_lib.baseboard_fab2(sch_1):page200_i200@mstr_vreg.tps3700(chips)!TPS3700_SM-IC,H69492-001!!!F47!INBN!!!!
S!PWRGD_DSW_PWROK!U9P2!6!@baseboard_fab2_lib.baseboard_fab2(sch_1):page200_i200@mstr_vreg.tps3700(chips)!TPS3700_SM-IC,H69492-001!!!F47!OUTA!!!!
S!FM_HSC_TIMER_EXP_N!U9P2!1!@baseboard_fab2_lib.baseboard_fab2(sch_1):page200_i200@mstr_vreg.tps3700(chips)!TPS3700_SM-IC,H69492-001!!!F47!OUTB!!!!
S!P3V3_STBY!U9P2!2!@baseboard_fab2_lib.baseboard_fab2(sch_1):page200_i200@mstr_vreg.tps3700(chips)!TPS3700_SM-IC,H69492-001!!!F47!VDD!!!!
S!GND!U1D2!5!@baseboard_fab2_lib.baseboard_fab2(sch_1):page200_i170@mstr_vreg.tps3700(chips)!TPS3700_SM-IC,H69492-001!!!F50!GND!!!!
S!A_HSC_LOW!U1D2!4!@baseboard_fab2_lib.baseboard_fab2(sch_1):page200_i170@mstr_vreg.tps3700(chips)!TPS3700_SM-IC,H69492-001!!!F50!INAP!!!!
S!A_HSC_HIGH!U1D2!3!@baseboard_fab2_lib.baseboard_fab2(sch_1):page200_i170@mstr_vreg.tps3700(chips)!TPS3700_SM-IC,H69492-001!!!F50!INBN!!!!
S!A_HSC_LOW_GATE!U1D2!6!@baseboard_fab2_lib.baseboard_fab2(sch_1):page200_i170@mstr_vreg.tps3700(chips)!TPS3700_SM-IC,H69492-001!!!F50!OUTA!!!!
S!IRQ_OC_DETECT_N!U1D2!1!@baseboard_fab2_lib.baseboard_fab2(sch_1):page200_i170@mstr_vreg.tps3700(chips)!TPS3700_SM-IC,H69492-001!!!F50!OUTB!!!!
S!P12V_STBY!U1D2!2!@baseboard_fab2_lib.baseboard_fab2(sch_1):page200_i170@mstr_vreg.tps3700(chips)!TPS3700_SM-IC,H69492-001!!!F50!VDD!!!!
S!GND!U9P1!5!@baseboard_fab2_lib.baseboard_fab2(sch_1):page200_i163@mstr_vreg.tps3700(chips)!TPS3700_SM-IC,H69492-001!!!F48!GND!!!!
S!A_P12V_STBY_ADR_TRIGGER!U9P1!4!@baseboard_fab2_lib.baseboard_fab2(sch_1):page200_i163@mstr_vreg.tps3700(chips)!TPS3700_SM-IC,H69492-001!!!F48!INAP!!!!
S!A_P12V_STBY_FP_TRIGGER!U9P1!3!@baseboard_fab2_lib.baseboard_fab2(sch_1):page200_i163@mstr_vreg.tps3700(chips)!TPS3700_SM-IC,H69492-001!!!F48!INBN!!!!
S!FM_UV_ADR_TRIGGER_N!U9P1!6!@baseboard_fab2_lib.baseboard_fab2(sch_1):page200_i163@mstr_vreg.tps3700(chips)!TPS3700_SM-IC,H69492-001!!!F48!OUTA!!!!
S!A_P12V_STBY_FPH_GATE!U9P1!1!@baseboard_fab2_lib.baseboard_fab2(sch_1):page200_i163@mstr_vreg.tps3700(chips)!TPS3700_SM-IC,H69492-001!!!F48!OUTB!!!!
S!P12V_STBY!U9P1!2!@baseboard_fab2_lib.baseboard_fab2(sch_1):page200_i163@mstr_vreg.tps3700(chips)!TPS3700_SM-IC,H69492-001!!!F48!VDD!!!!
S!GND!VR1D1!2!@baseboard_fab2_lib.baseboard_fab2(sch_1):page199_i99@mstr_discrete.zener(chips)!ZENER_SM-13V,IC,H69095-001!!!F0!A!!!!
S!P12V_PSU!VR1D1!1!@baseboard_fab2_lib.baseboard_fab2(sch_1):page199_i99@mstr_discrete.zener(chips)!ZENER_SM-13V,IC,H69095-001!!!F0!C!!!!
S!!DS9A1!3!!LED_1NC-BLUE,IC,C96565-012!!!!!!!!
S!FP_ID_LED_XOR_R!DS9A1!2!@baseboard_fab2_lib.baseboard_fab2(sch_1):page175_i50@mstr_discrete.led(chips)!LED_1NC-BLUE,IC,C96565-012!!!F2038!A!!!!
S!FP_ID_LED_P5V_STBY_N!DS9A1!1!@baseboard_fab2_lib.baseboard_fab2(sch_1):page175_i50@mstr_discrete.led(chips)!LED_1NC-BLUE,IC,C96565-012!!!F2038!C!!!!
S!!DS9A3!3!!LED_1NCLF-YELLOW,IC,C96565-003!!!!!!!!
S!FM_BEEP_LED_P!DS9A3!2!@baseboard_fab2_lib.baseboard_fab2(sch_1):page175_i67@mstr_discrete.led(chips)!LED_1NCLF-YELLOW,IC,C96565-003!!!F2036!A!!!!
S!FM_SPEAKER_PCH_N!DS9A3!1!@baseboard_fab2_lib.baseboard_fab2(sch_1):page175_i67@mstr_discrete.led(chips)!LED_1NCLF-YELLOW,IC,C96565-003!!!F2036!C!!!!
S!IRQ_SML1_PMBUS_ALERT_N!C8D3!1!@baseboard_fab2_lib.baseboard_fab2(sch_1):page170_i42@mstr_discrete.cap(chips)!CAP_0402LF-470PF,50V,10%,EMPTYA!!!F3098!A!!!!
S!GND!C8D3!2!@baseboard_fab2_lib.baseboard_fab2(sch_1):page170_i42@mstr_discrete.cap(chips)!CAP_0402LF-470PF,50V,10%,EMPTYA!!!F3098!B!!!!
S!FM_PS_EN!C2R6!1!@baseboard_fab2_lib.baseboard_fab2(sch_1):page181_i224@mstr_discrete.cap(chips)!CAP_0402LF-470PF,50V,10%,EMPTYA!!!F3099!A!!!!
S!GND!C2R6!2!@baseboard_fab2_lib.baseboard_fab2(sch_1):page181_i224@mstr_discrete.cap(chips)!CAP_0402LF-470PF,50V,10%,EMPTYA!!!F3099!B!!!!
S!H_PMSYNC_CLK_24M!R8B21!1!@baseboard_fab2_lib.baseboard_fab2(sch_1):page114_i124@mstr_discrete.res(chips)!RES_0402-49.9,1%,1/16W,EMPTY,GA!!!F400!A!!!!
S!GND!R8B21!2!@baseboard_fab2_lib.baseboard_fab2(sch_1):page114_i124@mstr_discrete.res(chips)!RES_0402-49.9,1%,1/16W,EMPTY,GA!!!F400!B!!!!
S!H_PM_SYNC_GTL!R3N14!1!@baseboard_fab2_lib.baseboard_fab2(sch_1):page118_i67@mstr_discrete.res(chips)!RES_0402-49.9,1%,1/16W,EMPTY,GA!!!F403!A!!!!
S!GND!R3N14!2!@baseboard_fab2_lib.baseboard_fab2(sch_1):page118_i67@mstr_discrete.res(chips)!RES_0402-49.9,1%,1/16W,EMPTY,GA!!!F403!B!!!!
S!PVCCIO_CPU0!R3T11!1!@baseboard_fab2_lib.baseboard_fab2(sch_1):page215_i330@mstr_discrete.res(chips)!RES_0402-49.9,1%,1/16W,EMPTY,GA!!!F401!A!!!!
S!SVID_CLK1_CPU0_R!R3T11!2!@baseboard_fab2_lib.baseboard_fab2(sch_1):page215_i330@mstr_discrete.res(chips)!RES_0402-49.9,1%,1/16W,EMPTY,GA!!!F401!B!!!!
S!PVCCIO_CPU1!R9U4!1!@baseboard_fab2_lib.baseboard_fab2(sch_1):page223_i50@mstr_discrete.res(chips)!RES_0402-49.9,1%,1/16W,EMPTY,GA!!!F399!A!!!!
S!SVID_CLK1_CPU1_R!R9U4!2!@baseboard_fab2_lib.baseboard_fab2(sch_1):page223_i50@mstr_discrete.res(chips)!RES_0402-49.9,1%,1/16W,EMPTY,GA!!!F399!B!!!!
S!PVCCIO_CPU0!R3P17!1!@baseboard_fab2_lib.baseboard_fab2(sch_1):page211_i28@mstr_discrete.res(chips)!RES_0402-49.9,1%,1/16W,EMPTY,GA!!!F402!A!!!!
S!SVID_CLK0_CPU0_R!R3P17!2!@baseboard_fab2_lib.baseboard_fab2(sch_1):page211_i28@mstr_discrete.res(chips)!RES_0402-49.9,1%,1/16W,EMPTY,GA!!!F402!B!!!!
S!GND!XBT8G1!3!@baseboard_fab2_lib.baseboard_fab2(sch_1):page196_i51@mstr_discrete.vert_batt_3pin(chips)!VERT_BATT_3PIN_TH-3PVERT,C6861A!!!F4!N!!!!
S!P3V_BAT_SOURCE!XBT8G1!1!@baseboard_fab2_lib.baseboard_fab2(sch_1):page196_i51@mstr_discrete.vert_batt_3pin(chips)!VERT_BATT_3PIN_TH-3PVERT,C6861A!!!F4!P1!!!!
S!P3V_BAT_SOURCE!XBT8G1!2!@baseboard_fab2_lib.baseboard_fab2(sch_1):page196_i51@mstr_discrete.vert_batt_3pin(chips)!VERT_BATT_3PIN_TH-3PVERT,C6861A!!!F4!P2!!!!
S!P3V3_STBY!CR3U1!2!@baseboard_fab2_lib.baseboard_fab2(sch_1):page189_i49@mstr_discrete.diode(chips)!DIODE_SMLF-1N5819HW,IC,D55839-A!!!F2209!A!!!!
S!P3V3_STBY_PLD_D!CR3U1!1!@baseboard_fab2_lib.baseboard_fab2(sch_1):page189_i49@mstr_discrete.diode(chips)!DIODE_SMLF-1N5819HW,IC,D55839-A!!!F2209!C!!!!
S!A_HSC_CSOUT!R1D20!1!@baseboard_fab2_lib.baseboard_fab2(sch_1):page200_i172@mstr_discrete.res(chips)!RES_0402-150.0K,1%,1/16W,CHIP,A!!!F1067!A!!!!
S!A_HSC_HIGH!R1D20!2!@baseboard_fab2_lib.baseboard_fab2(sch_1):page200_i172@mstr_discrete.res(chips)!RES_0402-150.0K,1%,1/16W,CHIP,A!!!F1067!B!!!!
S!FM_P12V_HSC_ADR1!R9P17!1!@baseboard_fab2_lib.baseboard_fab2(sch_1):page199_i33@mstr_discrete.res(chips)!RES_0402-150.0K,1%,1/16W,CHIP,A!!!F1066!A!!!!
S!AGND_HSC!R9P17!2!@baseboard_fab2_lib.baseboard_fab2(sch_1):page199_i33@mstr_discrete.res(chips)!RES_0402-150.0K,1%,1/16W,CHIP,A!!!F1066!B!!!!
S!GND!S8E1!1!@baseboard_fab2_lib.baseboard_fab2(sch_1):page157_i351@mstr_misc.switch_d90553001(chips)!SWITCH_D90553001_SMLF-IC,D9055A!!!F64!A!!!!
S!FP_NMI_BTN_OUT_R_N!S8E1!2!@baseboard_fab2_lib.baseboard_fab2(sch_1):page157_i351@mstr_misc.switch_d90553001(chips)!SWITCH_D90553001_SMLF-IC,D9055A!!!F64!B!!!!
S!PVPP_ABC!C6F4!1!@baseboard_fab2_lib.baseboard_fab2(sch_1):page231_i180@mstr_discrete.capp(chips)!CAPP_7343LF-330UF,6.3V,20%,POSA!!!F4099!A!!!!
S!GND!C6F4!2!@baseboard_fab2_lib.baseboard_fab2(sch_1):page231_i180@mstr_discrete.capp(chips)!CAPP_7343LF-330UF,6.3V,20%,POSA!!!F4099!B!!!!
S!PVPP_DEF!C6B7!1!@baseboard_fab2_lib.baseboard_fab2(sch_1):page232_i229@mstr_discrete.capp(chips)!CAPP_7343LF-330UF,6.3V,20%,POSA!!!F4100!A!!!!
S!GND!C6B7!2!@baseboard_fab2_lib.baseboard_fab2(sch_1):page232_i229@mstr_discrete.capp(chips)!CAPP_7343LF-330UF,6.3V,20%,POSA!!!F4100!B!!!!
S!PVPP_GHJ!C4F7!1!@baseboard_fab2_lib.baseboard_fab2(sch_1):page233_i217@mstr_discrete.capp(chips)!CAPP_7343LF-330UF,6.3V,20%,POSA!!!F4101!A!!!!
S!GND!C4F7!2!@baseboard_fab2_lib.baseboard_fab2(sch_1):page233_i217@mstr_discrete.capp(chips)!CAPP_7343LF-330UF,6.3V,20%,POSA!!!F4101!B!!!!
S!PVPP_KLM!C3B3!1!@baseboard_fab2_lib.baseboard_fab2(sch_1):page234_i167@mstr_discrete.capp(chips)!CAPP_7343LF-330UF,6.3V,20%,POSA!!!F4102!A!!!!
S!GND!C3B3!2!@baseboard_fab2_lib.baseboard_fab2(sch_1):page234_i167@mstr_discrete.capp(chips)!CAPP_7343LF-330UF,6.3V,20%,POSA!!!F4102!B!!!!
S!P3V3_STBY!C8F14!1!@baseboard_fab2_lib.baseboard_fab2(sch_1):page240_i154@mstr_discrete.capp(chips)!CAPP_3018-470UF,6.3V,20%,POSCAA!!!F4128!A!!!!
S!GND!C8F14!2!@baseboard_fab2_lib.baseboard_fab2(sch_1):page240_i154@mstr_discrete.capp(chips)!CAPP_3018-470UF,6.3V,20%,POSCAA!!!F4128!B!!!!
S!P3V3_STBY!C8F8!1!@baseboard_fab2_lib.baseboard_fab2(sch_1):page240_i155@mstr_discrete.capp(chips)!CAPP_3018-470UF,6.3V,20%,POSCAA!!!F4129!A!!!!
S!GND!C8F8!2!@baseboard_fab2_lib.baseboard_fab2(sch_1):page240_i155@mstr_discrete.capp(chips)!CAPP_3018-470UF,6.3V,20%,POSCAA!!!F4129!B!!!!
S!P5V_STBY!C8E4!1!@baseboard_fab2_lib.baseboard_fab2(sch_1):page241_i8@mstr_discrete.capp(chips)!CAPP_3018-470UF,6.3V,20%,POSCAA!!!F4130!A!!!!
S!GND!C8E4!2!@baseboard_fab2_lib.baseboard_fab2(sch_1):page241_i8@mstr_discrete.capp(chips)!CAPP_3018-470UF,6.3V,20%,POSCAA!!!F4130!B!!!!
S!UART_MUX_OUT_R!U9F2!7!@baseboard_fab2_lib.baseboard_fab2(sch_1):page158_i74@mstr_analog.fsa3357(chips)!FSA3357_SM-IC,C63273-001!!!F2129!A!!!!
S!SP2_BMC_CM_UART_TX!U9F2!1!@baseboard_fab2_lib.baseboard_fab2(sch_1):page158_i74@mstr_analog.fsa3357(chips)!FSA3357_SM-IC,C63273-001!!!F2129!B0!!!!
S!UART_BMC_TXD5!U9F2!2!@baseboard_fab2_lib.baseboard_fab2(sch_1):page158_i74@mstr_analog.fsa3357(chips)!FSA3357_SM-IC,C63273-001!!!F2129!B1!!!!
S!SP1_BMC_HOST_UART_TX!U9F2!3!@baseboard_fab2_lib.baseboard_fab2(sch_1):page158_i74@mstr_analog.fsa3357(chips)!FSA3357_SM-IC,C63273-001!!!F2129!B2!!!!
S!GND!U9F2!4!@baseboard_fab2_lib.baseboard_fab2(sch_1):page158_i74@mstr_analog.fsa3357(chips)!FSA3357_SM-IC,C63273-001!!!F2129!GND!!!!
S!FM_UARTSW_LSB_N!U9F2!6!@baseboard_fab2_lib.baseboard_fab2(sch_1):page158_i74@mstr_analog.fsa3357(chips)!FSA3357_SM-IC,C63273-001!!!F2129!S1!!!!
S!FM_UARTSW_MSB_N!U9F2!5!@baseboard_fab2_lib.baseboard_fab2(sch_1):page158_i74@mstr_analog.fsa3357(chips)!FSA3357_SM-IC,C63273-001!!!F2129!S2!!!!
S!P3V3_STBY!U9F2!8!@baseboard_fab2_lib.baseboard_fab2(sch_1):page158_i74@mstr_analog.fsa3357(chips)!FSA3357_SM-IC,C63273-001!!!F2129!VCC!!!!
S!UART_MUX_IN_R!U9F1!7!@baseboard_fab2_lib.baseboard_fab2(sch_1):page158_i75@mstr_analog.fsa3357(chips)!FSA3357_SM-IC,C63273-001!!!F2130!A!!!!
S!SP2_BMC_CM_UART_RX!U9F1!1!@baseboard_fab2_lib.baseboard_fab2(sch_1):page158_i75@mstr_analog.fsa3357(chips)!FSA3357_SM-IC,C63273-001!!!F2130!B0!!!!
S!UART_BMC_RXD5!U9F1!2!@baseboard_fab2_lib.baseboard_fab2(sch_1):page158_i75@mstr_analog.fsa3357(chips)!FSA3357_SM-IC,C63273-001!!!F2130!B1!!!!
S!SP1_BMC_HOST_UART_RX!U9F1!3!@baseboard_fab2_lib.baseboard_fab2(sch_1):page158_i75@mstr_analog.fsa3357(chips)!FSA3357_SM-IC,C63273-001!!!F2130!B2!!!!
S!GND!U9F1!4!@baseboard_fab2_lib.baseboard_fab2(sch_1):page158_i75@mstr_analog.fsa3357(chips)!FSA3357_SM-IC,C63273-001!!!F2130!GND!!!!
S!FM_UARTSW_LSB_N!U9F1!6!@baseboard_fab2_lib.baseboard_fab2(sch_1):page158_i75@mstr_analog.fsa3357(chips)!FSA3357_SM-IC,C63273-001!!!F2130!S1!!!!
S!FM_UARTSW_MSB_N!U9F1!5!@baseboard_fab2_lib.baseboard_fab2(sch_1):page158_i75@mstr_analog.fsa3357(chips)!FSA3357_SM-IC,C63273-001!!!F2130!S2!!!!
S!P3V3_STBY!U9F1!8!@baseboard_fab2_lib.baseboard_fab2(sch_1):page158_i75@mstr_analog.fsa3357(chips)!FSA3357_SM-IC,C63273-001!!!F2130!VCC!!!!
S!GND!TC1A1!1!@baseboard_fab2_lib.baseboard_fab2(sch_1):page110_i7@mstr_misc.rcc_dfx1940(chips)!RCC_DFX1940_ID4-EMPTY,N_A!!!F1967!GND!!!!
S!RCC_DFX_1940_1!TC1A1!2!@baseboard_fab2_lib.baseboard_fab2(sch_1):page110_i7@mstr_misc.rcc_dfx1940(chips)!RCC_DFX1940_ID4-EMPTY,N_A!!!F1967!IO1!!!!
S!RCC_DFX_1940_1!TC1A1!3!@baseboard_fab2_lib.baseboard_fab2(sch_1):page110_i7@mstr_misc.rcc_dfx1940(chips)!RCC_DFX1940_ID4-EMPTY,N_A!!!F1967!IO2!!!!
S!GND!TC9A1!1!@baseboard_fab2_lib.baseboard_fab2(sch_1):page110_i9@mstr_misc.rcc_dfx1940(chips)!RCC_DFX1940_ID4-EMPTY,N_A!!!F1965!GND!!!!
S!RCC_DFX_1940_2!TC9A1!2!@baseboard_fab2_lib.baseboard_fab2(sch_1):page110_i9@mstr_misc.rcc_dfx1940(chips)!RCC_DFX1940_ID4-EMPTY,N_A!!!F1965!IO1!!!!
S!RCC_DFX_1940_2!TC9A1!3!@baseboard_fab2_lib.baseboard_fab2(sch_1):page110_i9@mstr_misc.rcc_dfx1940(chips)!RCC_DFX1940_ID4-EMPTY,N_A!!!F1965!IO2!!!!
S!GND!TC1G1!1!@baseboard_fab2_lib.baseboard_fab2(sch_1):page110_i3@mstr_misc.rcc_dfx1940(chips)!RCC_DFX1940_ID4-EMPTY,N_A!!!F1966!GND!!!!
S!RCC_DFX_1940_4!TC1G1!2!@baseboard_fab2_lib.baseboard_fab2(sch_1):page110_i3@mstr_misc.rcc_dfx1940(chips)!RCC_DFX1940_ID4-EMPTY,N_A!!!F1966!IO1!!!!
S!RCC_DFX_1940_4!TC1G1!3!@baseboard_fab2_lib.baseboard_fab2(sch_1):page110_i3@mstr_misc.rcc_dfx1940(chips)!RCC_DFX1940_ID4-EMPTY,N_A!!!F1966!IO2!!!!
S!GND!TC9F1!1!@baseboard_fab2_lib.baseboard_fab2(sch_1):page110_i1@mstr_misc.rcc_dfx1940(chips)!RCC_DFX1940_ID4-EMPTY,N_A!!!F1964!GND!!!!
S!RCC_DFX_1940_3!TC9F1!2!@baseboard_fab2_lib.baseboard_fab2(sch_1):page110_i1@mstr_misc.rcc_dfx1940(chips)!RCC_DFX1940_ID4-EMPTY,N_A!!!F1964!IO1!!!!
S!RCC_DFX_1940_3!TC9F1!3!@baseboard_fab2_lib.baseboard_fab2(sch_1):page110_i1@mstr_misc.rcc_dfx1940(chips)!RCC_DFX1940_ID4-EMPTY,N_A!!!F1964!IO2!!!!
S!FP_PWR_BTN_R_N!S9A2!1!@baseboard_fab2_lib.baseboard_fab2(sch_1):page175_i84@mstr_misc.sw_h67881001(chips)!SW_H67881001_SM-IC,H67881-001!!!F63!IO1!!!!
S!FP_PWR_BTN_R_N!S9A2!2!@baseboard_fab2_lib.baseboard_fab2(sch_1):page175_i84@mstr_misc.sw_h67881001(chips)!SW_H67881001_SM-IC,H67881-001!!!F63!IO2!!!!
S!GND!S9A2!3!@baseboard_fab2_lib.baseboard_fab2(sch_1):page175_i84@mstr_misc.sw_h67881001(chips)!SW_H67881001_SM-IC,H67881-001!!!F63!IO3!!!!
S!GND!S9A2!4!@baseboard_fab2_lib.baseboard_fab2(sch_1):page175_i84@mstr_misc.sw_h67881001(chips)!SW_H67881001_SM-IC,H67881-001!!!F63!IO4!!!!
S!FM_USB_P0_EN_BOOT_BIOS_STRAP_N!U1M3!4!@baseboard_fab2_lib.baseboard_fab2(sch_1):page176_i100@mstr_vreg.tps2061(chips)!TPS2061_SM-IC,H66405-001!!!F51!EN_N!!!!
S!GND!U1M3!2!@baseboard_fab2_lib.baseboard_fab2(sch_1):page176_i100@mstr_vreg.tps2061(chips)!TPS2061_SM-IC,H66405-001!!!F51!GND!!!!
S!P5V!U1M3!5!@baseboard_fab2_lib.baseboard_fab2(sch_1):page176_i100@mstr_vreg.tps2061(chips)!TPS2061_SM-IC,H66405-001!!!F51!\in\!!!!
S!FM_OC0_USB_N!U1M3!3!@baseboard_fab2_lib.baseboard_fab2(sch_1):page176_i100@mstr_vreg.tps2061(chips)!TPS2061_SM-IC,H66405-001!!!F51!OC_N!!!!
S!P5V_USB!U1M3!1!@baseboard_fab2_lib.baseboard_fab2(sch_1):page176_i100@mstr_vreg.tps2061(chips)!TPS2061_SM-IC,H66405-001!!!F51!\out\!!!!
S!NIC_SER_N_MDI_3_DN!C9G12!1!@baseboard_fab2_lib.baseboard_fab2(sch_1):page141_i100@mstr_discrete.cap(chips)!CAP_0402LF-4700PF,50V,10%,EMPTA!!!F3102!A!!!!
S!NIC_MDI_MNG_RX_DN!C9G12!2!@baseboard_fab2_lib.baseboard_fab2(sch_1):page141_i100@mstr_discrete.cap(chips)!CAP_0402LF-4700PF,50V,10%,EMPTA!!!F3102!B!!!!
S!NIC_SET_N_MDI_2_DN!C9G13!1!@baseboard_fab2_lib.baseboard_fab2(sch_1):page141_i102@mstr_discrete.cap(chips)!CAP_0402LF-4700PF,50V,10%,EMPTA!!!F3101!A!!!!
S!NIC_MDI_MNG_TX_DN!C9G13!2!@baseboard_fab2_lib.baseboard_fab2(sch_1):page141_i102@mstr_discrete.cap(chips)!CAP_0402LF-4700PF,50V,10%,EMPTA!!!F3101!B!!!!
S!NIC_SER_P_MDI_3_DP!C9G9!1!@baseboard_fab2_lib.baseboard_fab2(sch_1):page141_i99@mstr_discrete.cap(chips)!CAP_0402LF-4700PF,50V,10%,EMPTA!!!F3103!A!!!!
S!NIC_MDI_MNG_RX_DP!C9G9!2!@baseboard_fab2_lib.baseboard_fab2(sch_1):page141_i99@mstr_discrete.cap(chips)!CAP_0402LF-4700PF,50V,10%,EMPTA!!!F3103!B!!!!
S!NIC_SET_P_MDI_2_DP!C9G16!1!@baseboard_fab2_lib.baseboard_fab2(sch_1):page141_i101@mstr_discrete.cap(chips)!CAP_0402LF-4700PF,50V,10%,EMPTA!!!F3100!A!!!!
S!NIC_MDI_MNG_TX_DP!C9G16!2!@baseboard_fab2_lib.baseboard_fab2(sch_1):page141_i101@mstr_discrete.cap(chips)!CAP_0402LF-4700PF,50V,10%,EMPTA!!!F3100!B!!!!
S!PVDDQ_ABC!C4T4!1!@baseboard_fab2_lib.baseboard_fab2(sch_1):page217_i91@mstr_discrete.cap(chips)!CAP_0805-100UF,4V,20%,X5R,6024A!!!F2584!A!!!!
S!GND!C4T4!2!@baseboard_fab2_lib.baseboard_fab2(sch_1):page217_i91@mstr_discrete.cap(chips)!CAP_0805-100UF,4V,20%,X5R,6024A!!!F2584!B!!!!
S!PVDDQ_ABC!C5U10!1!@baseboard_fab2_lib.baseboard_fab2(sch_1):page217_i83@mstr_discrete.cap(chips)!CAP_0805-100UF,4V,20%,X5R,6024A!!!F2572!A!!!!
S!GND!C5U10!2!@baseboard_fab2_lib.baseboard_fab2(sch_1):page217_i83@mstr_discrete.cap(chips)!CAP_0805-100UF,4V,20%,X5R,6024A!!!F2572!B!!!!
S!PVDDQ_ABC!C5U14!1!@baseboard_fab2_lib.baseboard_fab2(sch_1):page217_i89@mstr_discrete.cap(chips)!CAP_0805-100UF,4V,20%,X5R,6024A!!!F2570!A!!!!
S!GND!C5U14!2!@baseboard_fab2_lib.baseboard_fab2(sch_1):page217_i89@mstr_discrete.cap(chips)!CAP_0805-100UF,4V,20%,X5R,6024A!!!F2570!B!!!!
S!PVDDQ_ABC!C5U1!1!@baseboard_fab2_lib.baseboard_fab2(sch_1):page217_i88@mstr_discrete.cap(chips)!CAP_0805-100UF,4V,20%,X5R,6024A!!!F2573!A!!!!
S!GND!C5U1!2!@baseboard_fab2_lib.baseboard_fab2(sch_1):page217_i88@mstr_discrete.cap(chips)!CAP_0805-100UF,4V,20%,X5R,6024A!!!F2573!B!!!!
S!PVDDQ_ABC!C5U13!1!@baseboard_fab2_lib.baseboard_fab2(sch_1):page217_i82@mstr_discrete.cap(chips)!CAP_0805-100UF,4V,20%,X5R,6024A!!!F2571!A!!!!
S!GND!C5U13!2!@baseboard_fab2_lib.baseboard_fab2(sch_1):page217_i82@mstr_discrete.cap(chips)!CAP_0805-100UF,4V,20%,X5R,6024A!!!F2571!B!!!!
S!PVDDQ_ABC!C5U15!1!@baseboard_fab2_lib.baseboard_fab2(sch_1):page217_i90@mstr_discrete.cap(chips)!CAP_0805-100UF,4V,20%,X5R,6024A!!!F2569!A!!!!
S!GND!C5U15!2!@baseboard_fab2_lib.baseboard_fab2(sch_1):page217_i90@mstr_discrete.cap(chips)!CAP_0805-100UF,4V,20%,X5R,6024A!!!F2569!B!!!!
S!PVDDQ_ABC!C5G9!1!@baseboard_fab2_lib.baseboard_fab2(sch_1):page217_i92@mstr_discrete.cap(chips)!CAP_0805-100UF,4V,20%,X5R,6024A!!!F2581!A!!!!
S!GND!C5G9!2!@baseboard_fab2_lib.baseboard_fab2(sch_1):page217_i92@mstr_discrete.cap(chips)!CAP_0805-100UF,4V,20%,X5R,6024A!!!F2581!B!!!!
S!PVDDQ_ABC!C5G20!1!@baseboard_fab2_lib.baseboard_fab2(sch_1):page217_i110@mstr_discrete.cap(chips)!CAP_0805-100UF,4V,20%,X5R,6024A!!!F2580!A!!!!
S!GND!C5G20!2!@baseboard_fab2_lib.baseboard_fab2(sch_1):page217_i110@mstr_discrete.cap(chips)!CAP_0805-100UF,4V,20%,X5R,6024A!!!F2580!B!!!!
S!PVDDQ_GHJ!C2G16!1!@baseboard_fab2_lib.baseboard_fab2(sch_1):page225_i110@mstr_discrete.cap(chips)!CAP_0805-100UF,4V,20%,X5R,6024A!!!F2585!A!!!!
S!GND!C2G16!2!@baseboard_fab2_lib.baseboard_fab2(sch_1):page225_i110@mstr_discrete.cap(chips)!CAP_0805-100UF,4V,20%,X5R,6024A!!!F2585!B!!!!
S!PVDDQ_GHJ!C2G7!1!@baseboard_fab2_lib.baseboard_fab2(sch_1):page225_i92@mstr_discrete.cap(chips)!CAP_0805-100UF,4V,20%,X5R,6024A!!!F2586!A!!!!
S!GND!C2G7!2!@baseboard_fab2_lib.baseboard_fab2(sch_1):page225_i92@mstr_discrete.cap(chips)!CAP_0805-100UF,4V,20%,X5R,6024A!!!F2586!B!!!!
S!PVDDQ_GHJ!C7U7!1!@baseboard_fab2_lib.baseboard_fab2(sch_1):page225_i91@mstr_discrete.cap(chips)!CAP_0805-100UF,4V,20%,X5R,6024A!!!F2566!A!!!!
S!GND!C7U7!2!@baseboard_fab2_lib.baseboard_fab2(sch_1):page225_i91@mstr_discrete.cap(chips)!CAP_0805-100UF,4V,20%,X5R,6024A!!!F2566!B!!!!
S!PVDDQ_GHJ!C7T1!1!@baseboard_fab2_lib.baseboard_fab2(sch_1):page225_i90@mstr_discrete.cap(chips)!CAP_0805-100UF,4V,20%,X5R,6024A!!!F2567!A!!!!
S!GND!C7T1!2!@baseboard_fab2_lib.baseboard_fab2(sch_1):page225_i90@mstr_discrete.cap(chips)!CAP_0805-100UF,4V,20%,X5R,6024A!!!F2567!B!!!!
S!PVDDQ_GHJ!C8U11!1!@baseboard_fab2_lib.baseboard_fab2(sch_1):page225_i89@mstr_discrete.cap(chips)!CAP_0805-100UF,4V,20%,X5R,6024A!!!F2558!A!!!!
S!GND!C8U11!2!@baseboard_fab2_lib.baseboard_fab2(sch_1):page225_i89@mstr_discrete.cap(chips)!CAP_0805-100UF,4V,20%,X5R,6024A!!!F2558!B!!!!
S!PVDDQ_GHJ!C8U12!1!@baseboard_fab2_lib.baseboard_fab2(sch_1):page225_i88@mstr_discrete.cap(chips)!CAP_0805-100UF,4V,20%,X5R,6024A!!!F2557!A!!!!
S!GND!C8U12!2!@baseboard_fab2_lib.baseboard_fab2(sch_1):page225_i88@mstr_discrete.cap(chips)!CAP_0805-100UF,4V,20%,X5R,6024A!!!F2557!B!!!!
S!PVDDQ_GHJ!C8U8!1!@baseboard_fab2_lib.baseboard_fab2(sch_1):page225_i83@mstr_discrete.cap(chips)!CAP_0805-100UF,4V,20%,X5R,6024A!!!F2559!A!!!!
S!GND!C8U8!2!@baseboard_fab2_lib.baseboard_fab2(sch_1):page225_i83@mstr_discrete.cap(chips)!CAP_0805-100UF,4V,20%,X5R,6024A!!!F2559!B!!!!
S!PVDDQ_GHJ!C8U1!1!@baseboard_fab2_lib.baseboard_fab2(sch_1):page225_i82@mstr_discrete.cap(chips)!CAP_0805-100UF,4V,20%,X5R,6024A!!!F2560!A!!!!
S!GND!C8U1!2!@baseboard_fab2_lib.baseboard_fab2(sch_1):page225_i82@mstr_discrete.cap(chips)!CAP_0805-100UF,4V,20%,X5R,6024A!!!F2560!B!!!!
S!PVDDQ_KLM!C8L1!1!@baseboard_fab2_lib.baseboard_fab2(sch_1):page228_i110@mstr_discrete.cap(chips)!CAP_0805-100UF,4V,20%,X5R,6024A!!!F2565!A!!!!
S!GND!C8L1!2!@baseboard_fab2_lib.baseboard_fab2(sch_1):page228_i110@mstr_discrete.cap(chips)!CAP_0805-100UF,4V,20%,X5R,6024A!!!F2565!B!!!!
S!PVDDQ_KLM!C7L1!1!@baseboard_fab2_lib.baseboard_fab2(sch_1):page228_i92@mstr_discrete.cap(chips)!CAP_0805-100UF,4V,20%,X5R,6024A!!!F2568!A!!!!
S!GND!C7L1!2!@baseboard_fab2_lib.baseboard_fab2(sch_1):page228_i92@mstr_discrete.cap(chips)!CAP_0805-100UF,4V,20%,X5R,6024A!!!F2568!B!!!!
S!PVDDQ_KLM!C8M11!1!@baseboard_fab2_lib.baseboard_fab2(sch_1):page228_i91@mstr_discrete.cap(chips)!CAP_0805-100UF,4V,20%,X5R,6024A!!!F2561!A!!!!
S!GND!C8M11!2!@baseboard_fab2_lib.baseboard_fab2(sch_1):page228_i91@mstr_discrete.cap(chips)!CAP_0805-100UF,4V,20%,X5R,6024A!!!F2561!B!!!!
S!PVDDQ_KLM!C8M7!1!@baseboard_fab2_lib.baseboard_fab2(sch_1):page228_i90@mstr_discrete.cap(chips)!CAP_0805-100UF,4V,20%,X5R,6024A!!!F2562!A!!!!
S!GND!C8M7!2!@baseboard_fab2_lib.baseboard_fab2(sch_1):page228_i90@mstr_discrete.cap(chips)!CAP_0805-100UF,4V,20%,X5R,6024A!!!F2562!B!!!!
S!PVDDQ_KLM!C2A16!1!@baseboard_fab2_lib.baseboard_fab2(sch_1):page228_i89@mstr_discrete.cap(chips)!CAP_0805-100UF,4V,20%,X5R,6024A!!!F2587!A!!!!
S!GND!C2A16!2!@baseboard_fab2_lib.baseboard_fab2(sch_1):page228_i89@mstr_discrete.cap(chips)!CAP_0805-100UF,4V,20%,X5R,6024A!!!F2587!B!!!!
S!PVDDQ_KLM!C8L11!1!@baseboard_fab2_lib.baseboard_fab2(sch_1):page228_i88@mstr_discrete.cap(chips)!CAP_0805-100UF,4V,20%,X5R,6024A!!!F2563!A!!!!
S!GND!C8L11!2!@baseboard_fab2_lib.baseboard_fab2(sch_1):page228_i88@mstr_discrete.cap(chips)!CAP_0805-100UF,4V,20%,X5R,6024A!!!F2563!B!!!!
S!PVDDQ_KLM!C8L2!1!@baseboard_fab2_lib.baseboard_fab2(sch_1):page228_i83@mstr_discrete.cap(chips)!CAP_0805-100UF,4V,20%,X5R,6024A!!!F2564!A!!!!
S!GND!C8L2!2!@baseboard_fab2_lib.baseboard_fab2(sch_1):page228_i83@mstr_discrete.cap(chips)!CAP_0805-100UF,4V,20%,X5R,6024A!!!F2564!B!!!!
S!PVDDQ_KLM!C2A8!1!@baseboard_fab2_lib.baseboard_fab2(sch_1):page228_i82@mstr_discrete.cap(chips)!CAP_0805-100UF,4V,20%,X5R,6024A!!!F2588!A!!!!
S!GND!C2A8!2!@baseboard_fab2_lib.baseboard_fab2(sch_1):page228_i82@mstr_discrete.cap(chips)!CAP_0805-100UF,4V,20%,X5R,6024A!!!F2588!B!!!!
S!PVDDQ_DEF!C5A10!1!@baseboard_fab2_lib.baseboard_fab2(sch_1):page220_i110@mstr_discrete.cap(chips)!CAP_0805-100UF,4V,20%,X5R,6024A!!!F2583!A!!!!
S!GND!C5A10!2!@baseboard_fab2_lib.baseboard_fab2(sch_1):page220_i110@mstr_discrete.cap(chips)!CAP_0805-100UF,4V,20%,X5R,6024A!!!F2583!B!!!!
S!PVDDQ_DEF!C5L1!1!@baseboard_fab2_lib.baseboard_fab2(sch_1):page220_i91@mstr_discrete.cap(chips)!CAP_0805-100UF,4V,20%,X5R,6024A!!!F2579!A!!!!
S!GND!C5L1!2!@baseboard_fab2_lib.baseboard_fab2(sch_1):page220_i91@mstr_discrete.cap(chips)!CAP_0805-100UF,4V,20%,X5R,6024A!!!F2579!B!!!!
S!PVDDQ_DEF!C5L3!1!@baseboard_fab2_lib.baseboard_fab2(sch_1):page220_i89@mstr_discrete.cap(chips)!CAP_0805-100UF,4V,20%,X5R,6024A!!!F2577!A!!!!
S!GND!C5L3!2!@baseboard_fab2_lib.baseboard_fab2(sch_1):page220_i89@mstr_discrete.cap(chips)!CAP_0805-100UF,4V,20%,X5R,6024A!!!F2577!B!!!!
S!PVDDQ_DEF!C5L14!1!@baseboard_fab2_lib.baseboard_fab2(sch_1):page220_i83@mstr_discrete.cap(chips)!CAP_0805-100UF,4V,20%,X5R,6024A!!!F2576!A!!!!
S!GND!C5L14!2!@baseboard_fab2_lib.baseboard_fab2(sch_1):page220_i83@mstr_discrete.cap(chips)!CAP_0805-100UF,4V,20%,X5R,6024A!!!F2576!B!!!!
S!PVDDQ_DEF!C5M8!1!@baseboard_fab2_lib.baseboard_fab2(sch_1):page220_i82@mstr_discrete.cap(chips)!CAP_0805-100UF,4V,20%,X5R,6024A!!!F2575!A!!!!
S!GND!C5M8!2!@baseboard_fab2_lib.baseboard_fab2(sch_1):page220_i82@mstr_discrete.cap(chips)!CAP_0805-100UF,4V,20%,X5R,6024A!!!F2575!B!!!!
S!PVDDQ_DEF!C5A20!1!@baseboard_fab2_lib.baseboard_fab2(sch_1):page220_i92@mstr_discrete.cap(chips)!CAP_0805-100UF,4V,20%,X5R,6024A!!!F2582!A!!!!
S!GND!C5A20!2!@baseboard_fab2_lib.baseboard_fab2(sch_1):page220_i92@mstr_discrete.cap(chips)!CAP_0805-100UF,4V,20%,X5R,6024A!!!F2582!B!!!!
S!PVDDQ_DEF!C5L2!1!@baseboard_fab2_lib.baseboard_fab2(sch_1):page220_i90@mstr_discrete.cap(chips)!CAP_0805-100UF,4V,20%,X5R,6024A!!!F2578!A!!!!
S!GND!C5L2!2!@baseboard_fab2_lib.baseboard_fab2(sch_1):page220_i90@mstr_discrete.cap(chips)!CAP_0805-100UF,4V,20%,X5R,6024A!!!F2578!B!!!!
S!PVDDQ_DEF!C5M12!1!@baseboard_fab2_lib.baseboard_fab2(sch_1):page220_i88@mstr_discrete.cap(chips)!CAP_0805-100UF,4V,20%,X5R,6024A!!!F2574!A!!!!
S!GND!C5M12!2!@baseboard_fab2_lib.baseboard_fab2(sch_1):page220_i88@mstr_discrete.cap(chips)!CAP_0805-100UF,4V,20%,X5R,6024A!!!F2574!B!!!!
S!XTAL_24MHZ_PI7C9X1172_IN!Y9F1!1!@baseboard_fab2_lib.baseboard_fab2(sch_1):page183_i19@mstr_discrete.crystal(chips)!CRYSTAL_SM-24.000MHZ,IC,D95126A!!!F2228!A!!!!
S!XTAL_24MHZ_PI7C9X1172_OUT!Y9F1!2!@baseboard_fab2_lib.baseboard_fab2(sch_1):page183_i19@mstr_discrete.crystal(chips)!CRYSTAL_SM-24.000MHZ,IC,D95126A!!!F2228!B!!!!
S!VSENSE_P3V3_STBY!R8E31!1!@baseboard_fab2_lib.baseboard_fab2(sch_1):page240_i143@mstr_discrete.res(chips)!RES_0402-23.2K,1%,1/16W,CHIP,GA!!!F845!A!!!!
S!VSENSE_VOUT_P3V3_STBY!R8E31!2!@baseboard_fab2_lib.baseboard_fab2(sch_1):page240_i143@mstr_discrete.res(chips)!RES_0402-23.2K,1%,1/16W,CHIP,GA!!!F845!B!!!!
S!VR_P3V3_STBY_LGATE!EU8E1!4!@baseboard_fab2_lib.baseboard_fab2(sch_1):page240_i170@mstr_discrete.csd87384m(chips)!CSD87384M_SM-IC,H66258-001!!!F2226!BG!!!!
S!GND!EU8E1!3!@baseboard_fab2_lib.baseboard_fab2(sch_1):page240_i170@mstr_discrete.csd87384m(chips)!CSD87384M_SM-IC,H66258-001!!!F2226!PGND!!!!
S!VR_P3V3_STBY_UGATE!EU8E1!1!@baseboard_fab2_lib.baseboard_fab2(sch_1):page240_i170@mstr_discrete.csd87384m(chips)!CSD87384M_SM-IC,H66258-001!!!F2226!TG!!!!
S!VR_FET_SW_P12V_STBY_P3V3_STBY!EU8E1!2!@baseboard_fab2_lib.baseboard_fab2(sch_1):page240_i170@mstr_discrete.csd87384m(chips)!CSD87384M_SM-IC,H66258-001!!!F2226!VIN!!!!
S!VR_P3V3_STBY_PHASE!EU8E1!5!@baseboard_fab2_lib.baseboard_fab2(sch_1):page240_i170@mstr_discrete.csd87384m(chips)!CSD87384M_SM-IC,H66258-001!!!F2226!VSW!!!!
S!FM_PI7C9X1172_A0!EU9F3!30!@baseboard_fab2_lib.baseboard_fab2(sch_1):page183_i1@mstr_controller.pi7c9x1172(chips)!PI7C9X1172_QFN-IC,H66899-001!!!F1979!A0_CS_N!!!!
S!FM_PI7C9X1172_A1!EU9F3!31!@baseboard_fab2_lib.baseboard_fab2(sch_1):page183_i1@mstr_controller.pi7c9x1172(chips)!PI7C9X1172_QFN-IC,H66899-001!!!F1979!A1_S1!!!!
S!GND!EU9F3!25!@baseboard_fab2_lib.baseboard_fab2(sch_1):page183_i1@mstr_controller.pi7c9x1172(chips)!PI7C9X1172_QFN-IC,H66899-001!!!F1979!CTSA_N!!!!
S!GND!EU9F3!16!@baseboard_fab2_lib.baseboard_fab2(sch_1):page183_i1@mstr_controller.pi7c9x1172(chips)!PI7C9X1172_QFN-IC,H66899-001!!!F1979!CTSB_N!!!!
S!TP_PI7C9X1172_EN485_N!EU9F3!19!@baseboard_fab2_lib.baseboard_fab2(sch_1):page183_i1@mstr_controller.pi7c9x1172(chips)!PI7C9X1172_QFN-IC,H66899-001!!!F1979!EN485_N!!!!
S!TP_PI7C9X1172_ENIR_N!EU9F3!18!@baseboard_fab2_lib.baseboard_fab2(sch_1):page183_i1@mstr_controller.pi7c9x1172(chips)!PI7C9X1172_QFN-IC,H66899-001!!!F1979!ENIR_N!!!!
S!GND!EU9F3!12!@baseboard_fab2_lib.baseboard_fab2(sch_1):page183_i1@mstr_controller.pi7c9x1172(chips)!PI7C9X1172_QFN-IC,H66899-001!!!F1979!GND!!!!
S!TP_GPIO0_DSRB_N!EU9F3!13!@baseboard_fab2_lib.baseboard_fab2(sch_1):page183_i1@mstr_controller.pi7c9x1172(chips)!PI7C9X1172_QFN-IC,H66899-001!!!F1979!GPIO0_DSRB_N!!!!
S!TP_GPIO1_DTRB_N!EU9F3!23!@baseboard_fab2_lib.baseboard_fab2(sch_1):page183_i1@mstr_controller.pi7c9x1172(chips)!PI7C9X1172_QFN-IC,H66899-001!!!F1979!GPIO1_DTRB_N!!!!
S!TP_GPIO2_CDB_N!EU9F3!11!@baseboard_fab2_lib.baseboard_fab2(sch_1):page183_i1@mstr_controller.pi7c9x1172(chips)!PI7C9X1172_QFN-IC,H66899-001!!!F1979!GPIO2_CDB_N!!!!
S!TP_GPIO3_RIB_N!EU9F3!14!@baseboard_fab2_lib.baseboard_fab2(sch_1):page183_i1@mstr_controller.pi7c9x1172(chips)!PI7C9X1172_QFN-IC,H66899-001!!!F1979!GPIO3_RIB_N!!!!
S!TP_GPIO4_DSRA_N!EU9F3!26!@baseboard_fab2_lib.baseboard_fab2(sch_1):page183_i1@mstr_controller.pi7c9x1172(chips)!PI7C9X1172_QFN-IC,H66899-001!!!F1979!GPIO4_DSRA_N!!!!
S!TP_GPIO5_DTRA_N!EU9F3!22!@baseboard_fab2_lib.baseboard_fab2(sch_1):page183_i1@mstr_controller.pi7c9x1172(chips)!PI7C9X1172_QFN-IC,H66899-001!!!F1979!GPIO5_DTRA_N!!!!
S!TP_GPIO6_CDA_N!EU9F3!27!@baseboard_fab2_lib.baseboard_fab2(sch_1):page183_i1@mstr_controller.pi7c9x1172(chips)!PI7C9X1172_QFN-IC,H66899-001!!!F1979!GPIO6_CDA_N!!!!
S!TP_GPIO7_RIA_N!EU9F3!28!@baseboard_fab2_lib.baseboard_fab2(sch_1):page183_i1@mstr_controller.pi7c9x1172(chips)!PI7C9X1172_QFN-IC,H66899-001!!!F1979!GPIO7_RIA_N!!!!
S!PU_PI7C9X1172_I2C_SPI_N!EU9F3!32!@baseboard_fab2_lib.baseboard_fab2(sch_1):page183_i1@mstr_controller.pi7c9x1172(chips)!PI7C9X1172_QFN-IC,H66899-001!!!F1979!I2C_SPI_N!!!!
S!FM_UART_ALERT_N!EU9F3!20!@baseboard_fab2_lib.baseboard_fab2(sch_1):page183_i1@mstr_controller.pi7c9x1172(chips)!PI7C9X1172_QFN-IC,H66899-001!!!F1979!IRQ_N!!!!
S!NC_PI7C9X1172_1!EU9F3!1!@baseboard_fab2_lib.baseboard_fab2(sch_1):page183_i1@mstr_controller.pi7c9x1172(chips)!PI7C9X1172_QFN-IC,H66899-001!!!F1979!NC(0)!!!!
S!NC_PI7C9X1172_8!EU9F3!8!@baseboard_fab2_lib.baseboard_fab2(sch_1):page183_i1@mstr_controller.pi7c9x1172(chips)!PI7C9X1172_QFN-IC,H66899-001!!!F1979!NC(1)!!!!
S!PWRGD_DSW_PWROK!EU9F3!24!@baseboard_fab2_lib.baseboard_fab2(sch_1):page183_i1@mstr_controller.pi7c9x1172(chips)!PI7C9X1172_QFN-IC,H66899-001!!!F1979!RESET_N!!!!
S!TP_PI7C9X1172_RTSA_N!EU9F3!21!@baseboard_fab2_lib.baseboard_fab2(sch_1):page183_i1@mstr_controller.pi7c9x1172(chips)!PI7C9X1172_QFN-IC,H66899-001!!!F1979!RTSA_N!!!!
S!TP_PI7C9X1172_RTSB_N!EU9F3!15!@baseboard_fab2_lib.baseboard_fab2(sch_1):page183_i1@mstr_controller.pi7c9x1172(chips)!PI7C9X1172_QFN-IC,H66899-001!!!F1979!RTSB_N!!!!
S!SP1_HOST_BRIDGE_UART_RX!EU9F3!5!@baseboard_fab2_lib.baseboard_fab2(sch_1):page183_i1@mstr_controller.pi7c9x1172(chips)!PI7C9X1172_QFN-IC,H66899-001!!!F1979!RXA!!!!
S!UART_BRIDGE_RXD5!EU9F3!4!@baseboard_fab2_lib.baseboard_fab2(sch_1):page183_i1@mstr_controller.pi7c9x1172(chips)!PI7C9X1172_QFN-IC,H66899-001!!!F1979!RXB!!!!
S!SMB_SLOTX24_PCH_STBY_LVC3_SCL!EU9F3!17!@baseboard_fab2_lib.baseboard_fab2(sch_1):page183_i1@mstr_controller.pi7c9x1172(chips)!PI7C9X1172_QFN-IC,H66899-001!!!F1979!SCL!!!!
S!SMB_SLOTX24_PCH_STBY_LVC3_SDA!EU9F3!3!@baseboard_fab2_lib.baseboard_fab2(sch_1):page183_i1@mstr_controller.pi7c9x1172(chips)!PI7C9X1172_QFN-IC,H66899-001!!!F1979!SDA!!!!
S!TP_PI7C9X1172_SO!EU9F3!2!@baseboard_fab2_lib.baseboard_fab2(sch_1):page183_i1@mstr_controller.pi7c9x1172(chips)!PI7C9X1172_QFN-IC,H66899-001!!!F1979!SO!!!!
S!GND!EU9F3!33!@baseboard_fab2_lib.baseboard_fab2(sch_1):page183_i1@mstr_controller.pi7c9x1172(chips)!PI7C9X1172_QFN-IC,H66899-001!!!F1979!THPAD!!!!
S!SP1_HOST_BRIDGE_UART_TX!EU9F3!6!@baseboard_fab2_lib.baseboard_fab2(sch_1):page183_i1@mstr_controller.pi7c9x1172(chips)!PI7C9X1172_QFN-IC,H66899-001!!!F1979!TXA!!!!
S!UART_BRIDGE_TXD5!EU9F3!7!@baseboard_fab2_lib.baseboard_fab2(sch_1):page183_i1@mstr_controller.pi7c9x1172(chips)!PI7C9X1172_QFN-IC,H66899-001!!!F1979!TXB!!!!
S!P3V3_STBY!EU9F3!29!@baseboard_fab2_lib.baseboard_fab2(sch_1):page183_i1@mstr_controller.pi7c9x1172(chips)!PI7C9X1172_QFN-IC,H66899-001!!!F1979!VDD!!!!
S!XTAL_24MHZ_IN_R!EU9F3!9!@baseboard_fab2_lib.baseboard_fab2(sch_1):page183_i1@mstr_controller.pi7c9x1172(chips)!PI7C9X1172_QFN-IC,H66899-001!!!F1979!XTAL1!!!!
S!XTAL_24MHZ_OUT_R!EU9F3!10!@baseboard_fab2_lib.baseboard_fab2(sch_1):page183_i1@mstr_controller.pi7c9x1172(chips)!PI7C9X1172_QFN-IC,H66899-001!!!F1979!XTAL2!!!!
S!VR_P3V3_STBY_BOOT!EU8F1!4!@baseboard_fab2_lib.baseboard_fab2(sch_1):page240_i125@mstr_vreg.rt8240(chips)!RT8240_QFN-IC,H66262-001!!!F246!BOOT!!!!
S!VR_P3V3_STBY_OCSELECT!EU8F1!10!@baseboard_fab2_lib.baseboard_fab2(sch_1):page240_i125@mstr_vreg.rt8240(chips)!RT8240_QFN-IC,H66262-001!!!F246!CS!!!!
S!VR_P3V3_STBY_EN!EU8F1!8!@baseboard_fab2_lib.baseboard_fab2(sch_1):page240_i125@mstr_vreg.rt8240(chips)!RT8240_QFN-IC,H66262-001!!!F246!EN!!!!
S!AGND_P3V3_STBY!EU8F1!11!@baseboard_fab2_lib.baseboard_fab2(sch_1):page240_i125@mstr_vreg.rt8240(chips)!RT8240_QFN-IC,H66262-001!!!F246!G0!!!!
S!AGND_P3V3_STBY!EU8F1!12!@baseboard_fab2_lib.baseboard_fab2(sch_1):page240_i125@mstr_vreg.rt8240(chips)!RT8240_QFN-IC,H66262-001!!!F246!GND(0)!!!!
S!AGND_P3V3_STBY!EU8F1!13!@baseboard_fab2_lib.baseboard_fab2(sch_1):page240_i125@mstr_vreg.rt8240(chips)!RT8240_QFN-IC,H66262-001!!!F246!GND(1)!!!!
S!VR_P3V3_STBY_LGATE!EU8F1!1!@baseboard_fab2_lib.baseboard_fab2(sch_1):page240_i125@mstr_vreg.rt8240(chips)!RT8240_QFN-IC,H66262-001!!!F246!LGATE!!!!
S!PWRGD_P3V3_STBY_R!EU8F1!9!@baseboard_fab2_lib.baseboard_fab2(sch_1):page240_i125@mstr_vreg.rt8240(chips)!RT8240_QFN-IC,H66262-001!!!F246!PGOOD!!!!
S!VR_P3V3_STBY_PHASE!EU8F1!2!@baseboard_fab2_lib.baseboard_fab2(sch_1):page240_i125@mstr_vreg.rt8240(chips)!RT8240_QFN-IC,H66262-001!!!F246!PHASE!!!!
S!VSENSE_RGND_P3V3_STBY!EU8F1!7!@baseboard_fab2_lib.baseboard_fab2(sch_1):page240_i125@mstr_vreg.rt8240(chips)!RT8240_QFN-IC,H66262-001!!!F246!RGND!!!!
S!VR_P3V3_STBY_UGATE!EU8F1!3!@baseboard_fab2_lib.baseboard_fab2(sch_1):page240_i125@mstr_vreg.rt8240(chips)!RT8240_QFN-IC,H66262-001!!!F246!UGATE!!!!
S!P5V_STBY!EU8F1!5!@baseboard_fab2_lib.baseboard_fab2(sch_1):page240_i125@mstr_vreg.rt8240(chips)!RT8240_QFN-IC,H66262-001!!!F246!VCC!!!!
S!VSENSE_VOUT_P3V3_STBY!EU8F1!6!@baseboard_fab2_lib.baseboard_fab2(sch_1):page240_i125@mstr_vreg.rt8240(chips)!RT8240_QFN-IC,H66262-001!!!F246!VOUT!!!!
S!SPI_PCH_TPM_CLK_R!J8E1!1!@baseboard_fab2_lib.baseboard_fab2(sch_1):page184_i87@mstr_sconn.sconn11_h67026001(chips)!SCONN11_H67026001_SM-CONN,H670A!!!F241!IO1!!!!
S!SMB_SENSOR_STBY_LVC3_SCL!J8E1!10!@baseboard_fab2_lib.baseboard_fab2(sch_1):page184_i87@mstr_sconn.sconn11_h67026001(chips)!SCONN11_H67026001_SM-CONN,H670A!!!F241!IO10!!!!
S!GND!J8E1!11!@baseboard_fab2_lib.baseboard_fab2(sch_1):page184_i87@mstr_sconn.sconn11_h67026001(chips)!SCONN11_H67026001_SM-CONN,H670A!!!F241!IO11!!!!
S!RST_PLTRST_BUF_N!J8E1!2!@baseboard_fab2_lib.baseboard_fab2(sch_1):page184_i87@mstr_sconn.sconn11_h67026001(chips)!SCONN11_H67026001_SM-CONN,H670A!!!F241!IO2!!!!
S!SPI_PCH_TPM_MOSI_R!J8E1!3!@baseboard_fab2_lib.baseboard_fab2(sch_1):page184_i87@mstr_sconn.sconn11_h67026001(chips)!SCONN11_H67026001_SM-CONN,H670A!!!F241!IO3!!!!
S!SPI_PCH_TPM_MISO_R!J8E1!4!@baseboard_fab2_lib.baseboard_fab2(sch_1):page184_i87@mstr_sconn.sconn11_h67026001(chips)!SCONN11_H67026001_SM-CONN,H670A!!!F241!IO4!!!!
S!SPI_PCH_TPM_CS_R_N!J8E1!5!@baseboard_fab2_lib.baseboard_fab2(sch_1):page184_i87@mstr_sconn.sconn11_h67026001(chips)!SCONN11_H67026001_SM-CONN,H670A!!!F241!IO5!!!!
S!SMB_SENSOR_STBY_LVC3_SDA!J8E1!6!@baseboard_fab2_lib.baseboard_fab2(sch_1):page184_i87@mstr_sconn.sconn11_h67026001(chips)!SCONN11_H67026001_SM-CONN,H670A!!!F241!IO6!!!!
S!P3V3_STBY!J8E1!7!@baseboard_fab2_lib.baseboard_fab2(sch_1):page184_i87@mstr_sconn.sconn11_h67026001(chips)!SCONN11_H67026001_SM-CONN,H670A!!!F241!IO7!!!!
S!FM_TPM_PRES_N!J8E1!8!@baseboard_fab2_lib.baseboard_fab2(sch_1):page184_i87@mstr_sconn.sconn11_h67026001(chips)!SCONN11_H67026001_SM-CONN,H670A!!!F241!IO8!!!!
S!IRQ_SPI_TPM_N_R!J8E1!9!@baseboard_fab2_lib.baseboard_fab2(sch_1):page184_i87@mstr_sconn.sconn11_h67026001(chips)!SCONN11_H67026001_SM-CONN,H670A!!!F241!IO9!!!!
S!GND!J8E1!MP1!@baseboard_fab2_lib.baseboard_fab2(sch_1):page184_i87@mstr_sconn.sconn11_h67026001(chips)!SCONN11_H67026001_SM-CONN,H670A!!!F241!MP1!!!!
S!GND!J8E1!MP2!@baseboard_fab2_lib.baseboard_fab2(sch_1):page184_i87@mstr_sconn.sconn11_h67026001(chips)!SCONN11_H67026001_SM-CONN,H670A!!!F241!MP2!!!!
S!GND!J8B1!1!@baseboard_fab2_lib.baseboard_fab2(sch_1):page91_i1@mstr_sconn.sconn24_h46321001(chips)!SCONN24_H46321001_SM-SCONN,H46A!!!F233!IO1!!!!
S!SMB_HFI1_CPU0_LVC2_SCL!J8B1!10!@baseboard_fab2_lib.baseboard_fab2(sch_1):page91_i1@mstr_sconn.sconn24_h46321001(chips)!SCONN24_H46321001_SM-SCONN,H46A!!!F233!IO10!!!!
S!FM_MODPRST_HFI1_CPU0_LVT2_N!J8B1!11!@baseboard_fab2_lib.baseboard_fab2(sch_1):page91_i1@mstr_sconn.sconn24_h46321001(chips)!SCONN24_H46321001_SM-SCONN,H46A!!!F233!IO11!!!!
S!SMB_HFI1_CPU0_LVC2_SDA!J8B1!12!@baseboard_fab2_lib.baseboard_fab2(sch_1):page91_i1@mstr_sconn.sconn24_h46321001(chips)!SCONN24_H46321001_SM-SCONN,H46A!!!F233!IO12!!!!
S!LED_HFI1_CPU0_N!J8B1!13!@baseboard_fab2_lib.baseboard_fab2(sch_1):page91_i1@mstr_sconn.sconn24_h46321001(chips)!SCONN24_H46321001_SM-SCONN,H46A!!!F233!IO13!!!!
S!RST_HFI1_CPU0_LVT2_N!J8B1!14!@baseboard_fab2_lib.baseboard_fab2(sch_1):page91_i1@mstr_sconn.sconn24_h46321001(chips)!SCONN24_H46321001_SM-SCONN,H46A!!!F233!IO14!!!!
S!GND!J8B1!15!@baseboard_fab2_lib.baseboard_fab2(sch_1):page91_i1@mstr_sconn.sconn24_h46321001(chips)!SCONN24_H46321001_SM-SCONN,H46A!!!F233!IO15!!!!
S!IRQ_HFI1_CPU0_LVT2_N!J8B1!16!@baseboard_fab2_lib.baseboard_fab2(sch_1):page91_i1@mstr_sconn.sconn24_h46321001(chips)!SCONN24_H46321001_SM-SCONN,H46A!!!F233!IO16!!!!
S!TP_HFI_IO_CONN0_RSVD_17!J8B1!17!@baseboard_fab2_lib.baseboard_fab2(sch_1):page91_i1@mstr_sconn.sconn24_h46321001(chips)!SCONN24_H46321001_SM-SCONN,H46A!!!F233!IO17!!!!
S!P3V3!J8B1!18!@baseboard_fab2_lib.baseboard_fab2(sch_1):page91_i1@mstr_sconn.sconn24_h46321001(chips)!SCONN24_H46321001_SM-SCONN,H46A!!!F233!IO18!!!!
S!PWRGD_PVPP_ABC!J8B1!19!@baseboard_fab2_lib.baseboard_fab2(sch_1):page91_i1@mstr_sconn.sconn24_h46321001(chips)!SCONN24_H46321001_SM-SCONN,H46A!!!F233!IO19!!!!
S!SMB_HFI0_CPU0_LVC2_SCL!J8B1!2!@baseboard_fab2_lib.baseboard_fab2(sch_1):page91_i1@mstr_sconn.sconn24_h46321001(chips)!SCONN24_H46321001_SM-SCONN,H46A!!!F233!IO2!!!!
S!P3V3!J8B1!20!@baseboard_fab2_lib.baseboard_fab2(sch_1):page91_i1@mstr_sconn.sconn24_h46321001(chips)!SCONN24_H46321001_SM-SCONN,H46A!!!F233!IO20!!!!
S!PVPP_ABC!J8B1!21!@baseboard_fab2_lib.baseboard_fab2(sch_1):page91_i1@mstr_sconn.sconn24_h46321001(chips)!SCONN24_H46321001_SM-SCONN,H46A!!!F233!IO21!!!!
S!SMB_OCP_FRU_STBY_LVC3_SCL!J8B1!22!@baseboard_fab2_lib.baseboard_fab2(sch_1):page91_i1@mstr_sconn.sconn24_h46321001(chips)!SCONN24_H46321001_SM-SCONN,H46A!!!F233!IO22!!!!
S!GND!J8B1!23!@baseboard_fab2_lib.baseboard_fab2(sch_1):page91_i1@mstr_sconn.sconn24_h46321001(chips)!SCONN24_H46321001_SM-SCONN,H46A!!!F233!IO23!!!!
S!SMB_OCP_FRU_STBY_LVC3_SDA!J8B1!24!@baseboard_fab2_lib.baseboard_fab2(sch_1):page91_i1@mstr_sconn.sconn24_h46321001(chips)!SCONN24_H46321001_SM-SCONN,H46A!!!F233!IO24!!!!
S!FM_MODPRST_HFI0_CPU0_LVT2_N!J8B1!3!@baseboard_fab2_lib.baseboard_fab2(sch_1):page91_i1@mstr_sconn.sconn24_h46321001(chips)!SCONN24_H46321001_SM-SCONN,H46A!!!F233!IO3!!!!
S!SMB_HFI0_CPU0_LVC2_SDA!J8B1!4!@baseboard_fab2_lib.baseboard_fab2(sch_1):page91_i1@mstr_sconn.sconn24_h46321001(chips)!SCONN24_H46321001_SM-SCONN,H46A!!!F233!IO4!!!!
S!LED_HFI0_CPU0_N!J8B1!5!@baseboard_fab2_lib.baseboard_fab2(sch_1):page91_i1@mstr_sconn.sconn24_h46321001(chips)!SCONN24_H46321001_SM-SCONN,H46A!!!F233!IO5!!!!
S!RST_HFI0_CPU0_LVT2_N!J8B1!6!@baseboard_fab2_lib.baseboard_fab2(sch_1):page91_i1@mstr_sconn.sconn24_h46321001(chips)!SCONN24_H46321001_SM-SCONN,H46A!!!F233!IO6!!!!
S!GND!J8B1!7!@baseboard_fab2_lib.baseboard_fab2(sch_1):page91_i1@mstr_sconn.sconn24_h46321001(chips)!SCONN24_H46321001_SM-SCONN,H46A!!!F233!IO7!!!!
S!IRQ_HFI0_CPU0_LVT2_N!J8B1!8!@baseboard_fab2_lib.baseboard_fab2(sch_1):page91_i1@mstr_sconn.sconn24_h46321001(chips)!SCONN24_H46321001_SM-SCONN,H46A!!!F233!IO8!!!!
S!GND!J8B1!9!@baseboard_fab2_lib.baseboard_fab2(sch_1):page91_i1@mstr_sconn.sconn24_h46321001(chips)!SCONN24_H46321001_SM-SCONN,H46A!!!F233!IO9!!!!
S!GND!J8B1!MP1!@baseboard_fab2_lib.baseboard_fab2(sch_1):page91_i1@mstr_sconn.sconn24_h46321001(chips)!SCONN24_H46321001_SM-SCONN,H46A!!!F233!MP1!!!!
S!GND!J8B1!MP2!@baseboard_fab2_lib.baseboard_fab2(sch_1):page91_i1@mstr_sconn.sconn24_h46321001(chips)!SCONN24_H46321001_SM-SCONN,H46A!!!F233!MP2!!!!
S!FM_PVCCIO_CPU1_EN!U8D7!T7!@baseboard_fab2_lib.baseboard_fab2(sch_1):page190_i179@mstr_memory.lcmxo2(chips)!LCMXO2_256BGA-IC,H63395-001!!!F2041!PB11A_PCLKT2_0!!!!
S!TP_CPLD1_PB11B_PCLKC2_0!U8D7!R8!@baseboard_fab2_lib.baseboard_fab2(sch_1):page190_i179@mstr_memory.lcmxo2(chips)!LCMXO2_256BGA-IC,H63395-001!!!F2041!PB11B_PCLKC2_0!!!!
S!PWRGD_PVPP_DEF!U8D7!M6!@baseboard_fab2_lib.baseboard_fab2(sch_1):page190_i179@mstr_memory.lcmxo2(chips)!LCMXO2_256BGA-IC,H63395-001!!!F2041!PB11C!!!!
S!PWRGD_PVCCIO_CPU0!U8D7!L8!@baseboard_fab2_lib.baseboard_fab2(sch_1):page190_i179@mstr_memory.lcmxo2(chips)!LCMXO2_256BGA-IC,H63395-001!!!F2041!PB11D!!!!
S!PWRGD_PVNN_P1V05_PCH!U8D7!P8!@baseboard_fab2_lib.baseboard_fab2(sch_1):page190_i179@mstr_memory.lcmxo2(chips)!LCMXO2_256BGA-IC,H63395-001!!!F2041!PB12A!!!!
S!FM_CPLD_DBG_PWR_EN_N!U8D7!T8!@baseboard_fab2_lib.baseboard_fab2(sch_1):page190_i179@mstr_memory.lcmxo2(chips)!LCMXO2_256BGA-IC,H63395-001!!!F2041!PB12B!!!!
S!FM_156M_CPU1_BRD_OSC_EN!U8D7!N8!@baseboard_fab2_lib.baseboard_fab2(sch_1):page190_i179@mstr_memory.lcmxo2(chips)!LCMXO2_256BGA-IC,H63395-001!!!F2041!PB12C!!!!
S!FM_IE_DISABLE_N!U8D7!L9!@baseboard_fab2_lib.baseboard_fab2(sch_1):page190_i179@mstr_memory.lcmxo2(chips)!LCMXO2_256BGA-IC,H63395-001!!!F2041!PB12D!!!!
S!TP_CPLD1_PB16A_PCLKT2_1!U8D7!T9!@baseboard_fab2_lib.baseboard_fab2(sch_1):page190_i179@mstr_memory.lcmxo2(chips)!LCMXO2_256BGA-IC,H63395-001!!!F2041!PB16A_PCLKT2_1!!!!
S!TP_CPLD1_PB16B_PCLKC2_1!U8D7!P9!@baseboard_fab2_lib.baseboard_fab2(sch_1):page190_i179@mstr_memory.lcmxo2(chips)!LCMXO2_256BGA-IC,H63395-001!!!F2041!PB16B_PCLKC2_1!!!!
S!FM_PVCCMCP_CPU1_EN!U8D7!M8!@baseboard_fab2_lib.baseboard_fab2(sch_1):page190_i179@mstr_memory.lcmxo2(chips)!LCMXO2_256BGA-IC,H63395-001!!!F2041!PB16C!!!!
S!FM_CPLD_BMC_PWRDN_N!U8D7!N9!@baseboard_fab2_lib.baseboard_fab2(sch_1):page190_i179@mstr_memory.lcmxo2(chips)!LCMXO2_256BGA-IC,H63395-001!!!F2041!PB16D!!!!
S!FM_UARTSW_LSB_N!U8D7!R9!@baseboard_fab2_lib.baseboard_fab2(sch_1):page190_i179@mstr_memory.lcmxo2(chips)!LCMXO2_256BGA-IC,H63395-001!!!F2041!PB18A!!!!
S!FM_156M_CPU0_BRD_OSC_EN!U8D7!T10!@baseboard_fab2_lib.baseboard_fab2(sch_1):page190_i179@mstr_memory.lcmxo2(chips)!LCMXO2_256BGA-IC,H63395-001!!!F2041!PB18B!!!!
S!FM_CPLD_UART_CH_LOCK_N!U8D7!M9!@baseboard_fab2_lib.baseboard_fab2(sch_1):page190_i179@mstr_memory.lcmxo2(chips)!LCMXO2_256BGA-IC,H63395-001!!!F2041!PB18C!!!!
S!FM_SOL_UART_CH_SEL!U8D7!L10!@baseboard_fab2_lib.baseboard_fab2(sch_1):page190_i179@mstr_memory.lcmxo2(chips)!LCMXO2_256BGA-IC,H63395-001!!!F2041!PB18D!!!!
S!RST_CD_CPU1_POR_N!U8D7!P10!@baseboard_fab2_lib.baseboard_fab2(sch_1):page190_i179@mstr_memory.lcmxo2(chips)!LCMXO2_256BGA-IC,H63395-001!!!F2041!PB19A!!!!
S!RST_CPU0_LVC3_R1_N!U8D7!R10!@baseboard_fab2_lib.baseboard_fab2(sch_1):page190_i179@mstr_memory.lcmxo2(chips)!LCMXO2_256BGA-IC,H63395-001!!!F2041!PB19B!!!!
S!RST_CPU1_LVC3_R1_N!U8D7!N10!@baseboard_fab2_lib.baseboard_fab2(sch_1):page190_i179@mstr_memory.lcmxo2(chips)!LCMXO2_256BGA-IC,H63395-001!!!F2041!PB19C!!!!
S!XDP_PWRGD_RST_N!U8D7!M11!@baseboard_fab2_lib.baseboard_fab2(sch_1):page190_i179@mstr_memory.lcmxo2(chips)!LCMXO2_256BGA-IC,H63395-001!!!F2041!PB19D!!!!
S!FM_CPU1_PKGID2!U8D7!T11!@baseboard_fab2_lib.baseboard_fab2(sch_1):page190_i179@mstr_memory.lcmxo2(chips)!LCMXO2_256BGA-IC,H63395-001!!!F2041!PB21A!!!!
S!FM_UARTSW_MSB_N!U8D7!P11!@baseboard_fab2_lib.baseboard_fab2(sch_1):page190_i179@mstr_memory.lcmxo2(chips)!LCMXO2_256BGA-IC,H63395-001!!!F2041!PB21B!!!!
S!PWRGD_CPU1_LVC3!U8D7!M10!@baseboard_fab2_lib.baseboard_fab2(sch_1):page190_i179@mstr_memory.lcmxo2(chips)!LCMXO2_256BGA-IC,H63395-001!!!F2041!PB21C!!!!
S!XDP_SYSPWROK!U8D7!N11!@baseboard_fab2_lib.baseboard_fab2(sch_1):page190_i179@mstr_memory.lcmxo2(chips)!LCMXO2_256BGA-IC,H63395-001!!!F2041!PB21D!!!!
S!FM_DB1200ZL_BCLKS_EN_N!U8D7!R11!@baseboard_fab2_lib.baseboard_fab2(sch_1):page190_i179@mstr_memory.lcmxo2(chips)!LCMXO2_256BGA-IC,H63395-001!!!F2041!PB22A!!!!
S!FM_CPU1_SKTOCC_LVT3_N!U8D7!T12!@baseboard_fab2_lib.baseboard_fab2(sch_1):page190_i179@mstr_memory.lcmxo2(chips)!LCMXO2_256BGA-IC,H63395-001!!!F2041!PB22B!!!!
S!FM_CPU0_VRM_OSC_EN!U8D7!R13!@baseboard_fab2_lib.baseboard_fab2(sch_1):page190_i179@mstr_memory.lcmxo2(chips)!LCMXO2_256BGA-IC,H63395-001!!!F2041!PB22C!!!!
S!FM_CPU0_SKTOCC_LVT3_N!U8D7!T14!@baseboard_fab2_lib.baseboard_fab2(sch_1):page190_i179@mstr_memory.lcmxo2(chips)!LCMXO2_256BGA-IC,H63395-001!!!F2041!PB22D!!!!
S!FM_CPU1_PKGID1!U8D7!P12!@baseboard_fab2_lib.baseboard_fab2(sch_1):page190_i179@mstr_memory.lcmxo2(chips)!LCMXO2_256BGA-IC,H63395-001!!!F2041!PB24A!!!!
S!FM_CPU_MSMI_LVT3_N!U8D7!T13!@baseboard_fab2_lib.baseboard_fab2(sch_1):page190_i179@mstr_memory.lcmxo2(chips)!LCMXO2_256BGA-IC,H63395-001!!!F2041!PB24B!!!!
S!FM_CPU1_PKGID0!U8D7!R12!@baseboard_fab2_lib.baseboard_fab2(sch_1):page190_i179@mstr_memory.lcmxo2(chips)!LCMXO2_256BGA-IC,H63395-001!!!F2041!PB25A_SN!!!!
S!TP_CPLD1_PB25B_SI_SISPI!U8D7!P13!@baseboard_fab2_lib.baseboard_fab2(sch_1):page190_i179@mstr_memory.lcmxo2(chips)!LCMXO2_256BGA-IC,H63395-001!!!F2041!PB25B_SI_SISPI!!!!
S!PWRGD_DRAMPWRGD!U8D7!T15!@baseboard_fab2_lib.baseboard_fab2(sch_1):page190_i179@mstr_memory.lcmxo2(chips)!LCMXO2_256BGA-IC,H63395-001!!!F2041!PB25C!!!!
S!FM_CPU_CATERR_LVT3_N!U8D7!R14!@baseboard_fab2_lib.baseboard_fab2(sch_1):page190_i179@mstr_memory.lcmxo2(chips)!LCMXO2_256BGA-IC,H63395-001!!!F2041!PB25D!!!!
S!FM_CPU1_RC_EN!U8D7!P4!@baseboard_fab2_lib.baseboard_fab2(sch_1):page190_i179@mstr_memory.lcmxo2(chips)!LCMXO2_256BGA-IC,H63395-001!!!F2041!PB3A!!!!
S!PWRGD_PVSA_CPU1!U8D7!T4!@baseboard_fab2_lib.baseboard_fab2(sch_1):page190_i179@mstr_memory.lcmxo2(chips)!LCMXO2_256BGA-IC,H63395-001!!!F2041!PB3B!!!!
S!FM_ADR_MODE_SEL!U8D7!T2!@baseboard_fab2_lib.baseboard_fab2(sch_1):page190_i179@mstr_memory.lcmxo2(chips)!LCMXO2_256BGA-IC,H63395-001!!!F2041!PB3C!!!!
S!FM_CPU0_RC_EN!U8D7!R3!@baseboard_fab2_lib.baseboard_fab2(sch_1):page190_i179@mstr_memory.lcmxo2(chips)!LCMXO2_256BGA-IC,H63395-001!!!F2041!PB3D!!!!
S!TP_CPLD1_PB5A_CSSPIN!U8D7!R5!@baseboard_fab2_lib.baseboard_fab2(sch_1):page190_i179@mstr_memory.lcmxo2(chips)!LCMXO2_256BGA-IC,H63395-001!!!F2041!PB5A_CSSPIN!!!!
S!PWRGD_PVCCMCP_CPU0!U8D7!P5!@baseboard_fab2_lib.baseboard_fab2(sch_1):page190_i179@mstr_memory.lcmxo2(chips)!LCMXO2_256BGA-IC,H63395-001!!!F2041!PB5B!!!!
S!PWRGD_PVCCIOMCP_CPU1!U8D7!T5!@baseboard_fab2_lib.baseboard_fab2(sch_1):page190_i179@mstr_memory.lcmxo2(chips)!LCMXO2_256BGA-IC,H63395-001!!!F2041!PB6A!!!!
S!RST_PCIE_M2_DEV_N!U8D7!R6!@baseboard_fab2_lib.baseboard_fab2(sch_1):page190_i179@mstr_memory.lcmxo2(chips)!LCMXO2_256BGA-IC,H63395-001!!!F2041!PB6B!!!!
S!FM_DIS_ADR_DLY!U8D7!T3!@baseboard_fab2_lib.baseboard_fab2(sch_1):page190_i179@mstr_memory.lcmxo2(chips)!LCMXO2_256BGA-IC,H63395-001!!!F2041!PB6C!!!!
S!FM_BMC_CPLD_MP_RST_N!U8D7!R4!@baseboard_fab2_lib.baseboard_fab2(sch_1):page190_i179@mstr_memory.lcmxo2(chips)!LCMXO2_256BGA-IC,H63395-001!!!F2041!PB6D!!!!
S!TP_CPLD1_PB8A_MCLK_CCLK!U8D7!P6!@baseboard_fab2_lib.baseboard_fab2(sch_1):page190_i179@mstr_memory.lcmxo2(chips)!LCMXO2_256BGA-IC,H63395-001!!!F2041!PB8A_MCLK_CCLK!!!!
S!TP_CPLD1_PB8B_SO_SPISO!U8D7!T6!@baseboard_fab2_lib.baseboard_fab2(sch_1):page190_i179@mstr_memory.lcmxo2(chips)!LCMXO2_256BGA-IC,H63395-001!!!F2041!PB8B_SO_SPISO!!!!
S!PWRGD_PVCCIOMCP_CPU0!U8D7!N6!@baseboard_fab2_lib.baseboard_fab2(sch_1):page190_i179@mstr_memory.lcmxo2(chips)!LCMXO2_256BGA-IC,H63395-001!!!F2041!PB8C!!!!
S!TP_CPLD1_PB8D!U8D7!L7!@baseboard_fab2_lib.baseboard_fab2(sch_1):page190_i179@mstr_memory.lcmxo2(chips)!LCMXO2_256BGA-IC,H63395-001!!!F2041!PB8D!!!!
S!PWRGD_PVTT_CPU1!U8D7!R7!@baseboard_fab2_lib.baseboard_fab2(sch_1):page190_i179@mstr_memory.lcmxo2(chips)!LCMXO2_256BGA-IC,H63395-001!!!F2041!PB9A!!!!
S!FM_PVCCIOMCP_CPU1_EN!U8D7!P7!@baseboard_fab2_lib.baseboard_fab2(sch_1):page190_i179@mstr_memory.lcmxo2(chips)!LCMXO2_256BGA-IC,H63395-001!!!F2041!PB9B!!!!
S!FM_PVCCIO_CPU0_EN!U8D7!M7!@baseboard_fab2_lib.baseboard_fab2(sch_1):page190_i179@mstr_memory.lcmxo2(chips)!LCMXO2_256BGA-IC,H63395-001!!!F2041!PB9C!!!!
S!PWRGD_PVPP_ABC!U8D7!N7!@baseboard_fab2_lib.baseboard_fab2(sch_1):page190_i179@mstr_memory.lcmxo2(chips)!LCMXO2_256BGA-IC,H63395-001!!!F2041!PB9D!!!!
S!SP1_BMC_HOST_UART_RX!U8D7!K3!@baseboard_fab2_lib.baseboard_fab2(sch_1):page190_i179@mstr_memory.lcmxo2(chips)!LCMXO2_256BGA-IC,H63395-001!!!F2041!PL10A!!!!
S!SP1_BMC_HOST_UART_TX!U8D7!K2!@baseboard_fab2_lib.baseboard_fab2(sch_1):page190_i179@mstr_memory.lcmxo2(chips)!LCMXO2_256BGA-IC,H63395-001!!!F2041!PL10B!!!!
S!UART_BMC_RXD5!U8D7!J5!@baseboard_fab2_lib.baseboard_fab2(sch_1):page190_i179@mstr_memory.lcmxo2(chips)!LCMXO2_256BGA-IC,H63395-001!!!F2041!PL10C!!!!
S!UART_BMC_TXD5!U8D7!K6!@baseboard_fab2_lib.baseboard_fab2(sch_1):page190_i179@mstr_memory.lcmxo2(chips)!LCMXO2_256BGA-IC,H63395-001!!!F2041!PL10D!!!!
S!PWRGD_PVSA_CPU0!U8D7!L1!@baseboard_fab2_lib.baseboard_fab2(sch_1):page190_i179@mstr_memory.lcmxo2(chips)!LCMXO2_256BGA-IC,H63395-001!!!F2041!PL11A!!!!
S!RST_RSMRST_DLY!U8D7!L3!@baseboard_fab2_lib.baseboard_fab2(sch_1):page190_i179@mstr_memory.lcmxo2(chips)!LCMXO2_256BGA-IC,H63395-001!!!F2041!PL11B!!!!
S!SGPIO_BMC_LD_N!U8D7!K4!@baseboard_fab2_lib.baseboard_fab2(sch_1):page190_i179@mstr_memory.lcmxo2(chips)!LCMXO2_256BGA-IC,H63395-001!!!F2041!PL11C!!!!
S!PWRGD_CPU0_LVC3!U8D7!L5!@baseboard_fab2_lib.baseboard_fab2(sch_1):page190_i179@mstr_memory.lcmxo2(chips)!LCMXO2_256BGA-IC,H63395-001!!!F2041!PL11D!!!!
S!CLK_25M_CPLD!U8D7!L2!@baseboard_fab2_lib.baseboard_fab2(sch_1):page190_i179@mstr_memory.lcmxo2(chips)!LCMXO2_256BGA-IC,H63395-001!!!F2041!PL12A_PCLKT3_0!!!!
S!TP_CPLD1_PL12B_PCLKC3_0!U8D7!M1!@baseboard_fab2_lib.baseboard_fab2(sch_1):page190_i179@mstr_memory.lcmxo2(chips)!LCMXO2_256BGA-IC,H63395-001!!!F2041!PL12B_PCLKC3_0!!!!
S!PWRGD_PVCCIN_CPU0!U8D7!K5!@baseboard_fab2_lib.baseboard_fab2(sch_1):page190_i179@mstr_memory.lcmxo2(chips)!LCMXO2_256BGA-IC,H63395-001!!!F2041!PL12C!!!!
S!PWRGD_PVCCMCP_CPU1!U8D7!L4!@baseboard_fab2_lib.baseboard_fab2(sch_1):page190_i179@mstr_memory.lcmxo2(chips)!LCMXO2_256BGA-IC,H63395-001!!!F2041!PL12D!!!!
S!RST_PCIE_RISER1_PERST_N!U8D7!M3!@baseboard_fab2_lib.baseboard_fab2(sch_1):page190_i179@mstr_memory.lcmxo2(chips)!LCMXO2_256BGA-IC,H63395-001!!!F2041!PL13A!!!!
S!PWRGD_PVCCIN_CPU1!U8D7!N1!@baseboard_fab2_lib.baseboard_fab2(sch_1):page190_i179@mstr_memory.lcmxo2(chips)!LCMXO2_256BGA-IC,H63395-001!!!F2041!PL13B!!!!
S!PWRGD_PVPP_KLM!U8D7!N2!@baseboard_fab2_lib.baseboard_fab2(sch_1):page190_i179@mstr_memory.lcmxo2(chips)!LCMXO2_256BGA-IC,H63395-001!!!F2041!PL13C!!!!
S!FM_GLOBAL_RST_WARN_N!U8D7!P1!@baseboard_fab2_lib.baseboard_fab2(sch_1):page190_i179@mstr_memory.lcmxo2(chips)!LCMXO2_256BGA-IC,H63395-001!!!F2041!PL13D!!!!
S!PWRGD_PVPP_GHJ!U8D7!M2!@baseboard_fab2_lib.baseboard_fab2(sch_1):page190_i179@mstr_memory.lcmxo2(chips)!LCMXO2_256BGA-IC,H63395-001!!!F2041!PL14A!!!!
S!RST_CD_CPU0_POR_N!U8D7!N3!@baseboard_fab2_lib.baseboard_fab2(sch_1):page190_i179@mstr_memory.lcmxo2(chips)!LCMXO2_256BGA-IC,H63395-001!!!F2041!PL14B!!!!
S!FM_BMC_CPLD_GPO!U8D7!R1!@baseboard_fab2_lib.baseboard_fab2(sch_1):page190_i179@mstr_memory.lcmxo2(chips)!LCMXO2_256BGA-IC,H63395-001!!!F2041!PL14C!!!!
S!FM_UART_ALERT_N!U8D7!P2!@baseboard_fab2_lib.baseboard_fab2(sch_1):page190_i179@mstr_memory.lcmxo2(chips)!LCMXO2_256BGA-IC,H63395-001!!!F2041!PL14D!!!!
S!TP_CPLD1_PL1A_L_GPLLT_FB!U8D7!D3!@baseboard_fab2_lib.baseboard_fab2(sch_1):page190_i179@mstr_memory.lcmxo2(chips)!LCMXO2_256BGA-IC,H63395-001!!!F2041!PL1A_L_GPLLT_FB!!!!
S!TP_CPLD1_PL1B_L_GPLLC_FB!U8D7!D1!@baseboard_fab2_lib.baseboard_fab2(sch_1):page190_i179@mstr_memory.lcmxo2(chips)!LCMXO2_256BGA-IC,H63395-001!!!F2041!PL1B_L_GPLLC_FB!!!!
S!RST_PCIE_PCH_PERST_N!U8D7!B1!@baseboard_fab2_lib.baseboard_fab2(sch_1):page190_i179@mstr_memory.lcmxo2(chips)!LCMXO2_256BGA-IC,H63395-001!!!F2041!PL1C!!!!
S!FM_PCH_PLD_DATA!U8D7!C2!@baseboard_fab2_lib.baseboard_fab2(sch_1):page190_i179@mstr_memory.lcmxo2(chips)!LCMXO2_256BGA-IC,H63395-001!!!F2041!PL1D!!!!
S!FM_CPU_CATERR_DLY_LVT3_N!U8D7!E2!@baseboard_fab2_lib.baseboard_fab2(sch_1):page190_i179@mstr_memory.lcmxo2(chips)!LCMXO2_256BGA-IC,H63395-001!!!F2041!PL2A_L_GPLLT_IN!!!!
S!TP_CPLD1_PL2B_L_GPLLC_IN!U8D7!E3!@baseboard_fab2_lib.baseboard_fab2(sch_1):page190_i179@mstr_memory.lcmxo2(chips)!LCMXO2_256BGA-IC,H63395-001!!!F2041!PL2B_L_GPLLC_IN!!!!
S!RST_PCIE_CPU_DEV1_N!U8D7!C1!@baseboard_fab2_lib.baseboard_fab2(sch_1):page190_i179@mstr_memory.lcmxo2(chips)!LCMXO2_256BGA-IC,H63395-001!!!F2041!PL2C!!!!
S!FM_MEM_EVENT_FUNC!U8D7!D2!@baseboard_fab2_lib.baseboard_fab2(sch_1):page190_i179@mstr_memory.lcmxo2(chips)!LCMXO2_256BGA-IC,H63395-001!!!F2041!PL2D!!!!
S!CLK_32K_SUSCLK_PLD!U8D7!E1!@baseboard_fab2_lib.baseboard_fab2(sch_1):page190_i179@mstr_memory.lcmxo2(chips)!LCMXO2_256BGA-IC,H63395-001!!!F2041!PL3A_PCLKT5_0!!!!
S!FM_CPU0_PKGID0!U8D7!F2!@baseboard_fab2_lib.baseboard_fab2(sch_1):page190_i179@mstr_memory.lcmxo2(chips)!LCMXO2_256BGA-IC,H63395-001!!!F2041!PL3B_PCLKC5_0!!!!
S!PU_RST_PERST_BIT0!U8D7!F4!@baseboard_fab2_lib.baseboard_fab2(sch_1):page190_i179@mstr_memory.lcmxo2(chips)!LCMXO2_256BGA-IC,H63395-001!!!F2041!PL3C!!!!
S!FM_PWR_BTN_N!U8D7!G6!@baseboard_fab2_lib.baseboard_fab2(sch_1):page190_i179@mstr_memory.lcmxo2(chips)!LCMXO2_256BGA-IC,H63395-001!!!F2041!PL3D!!!!
S!FM_CPU0_PROC_ID1!U8D7!F3!@baseboard_fab2_lib.baseboard_fab2(sch_1):page190_i179@mstr_memory.lcmxo2(chips)!LCMXO2_256BGA-IC,H63395-001!!!F2041!PL4A!!!!
S!FM_CPU0_PROC_ID0!U8D7!F1!@baseboard_fab2_lib.baseboard_fab2(sch_1):page190_i179@mstr_memory.lcmxo2(chips)!LCMXO2_256BGA-IC,H63395-001!!!F2041!PL4B!!!!
S!FM_DEBUG_RST_BTN_N!U8D7!G5!@baseboard_fab2_lib.baseboard_fab2(sch_1):page190_i179@mstr_memory.lcmxo2(chips)!LCMXO2_256BGA-IC,H63395-001!!!F2041!PL4C!!!!
S!RST_RSMRST_R_N!U8D7!G4!@baseboard_fab2_lib.baseboard_fab2(sch_1):page190_i179@mstr_memory.lcmxo2(chips)!LCMXO2_256BGA-IC,H63395-001!!!F2041!PL4D!!!!
S!FM_CPU0_PKGID2!U8D7!G2!@baseboard_fab2_lib.baseboard_fab2(sch_1):page190_i179@mstr_memory.lcmxo2(chips)!LCMXO2_256BGA-IC,H63395-001!!!F2041!PL5A!!!!
S!FM_CPU0_PKGID1!U8D7!G3!@baseboard_fab2_lib.baseboard_fab2(sch_1):page190_i179@mstr_memory.lcmxo2(chips)!LCMXO2_256BGA-IC,H63395-001!!!F2041!PL5B!!!!
S!FM_CPU0_FIVR_FAULT_LVT3_N!U8D7!F5!@baseboard_fab2_lib.baseboard_fab2(sch_1):page190_i179@mstr_memory.lcmxo2(chips)!LCMXO2_256BGA-IC,H63395-001!!!F2041!PL5C!!!!
S!PWRGD_P3V3!U8D7!H6!@baseboard_fab2_lib.baseboard_fab2(sch_1):page190_i179@mstr_memory.lcmxo2(chips)!LCMXO2_256BGA-IC,H63395-001!!!F2041!PL5D!!!!
S!FM_SLPS3_N!U8D7!G1!@baseboard_fab2_lib.baseboard_fab2(sch_1):page190_i179@mstr_memory.lcmxo2(chips)!LCMXO2_256BGA-IC,H63395-001!!!F2041!PL6A!!!!
S!FM_PVCCMCP_CPU0_EN!U8D7!H2!@baseboard_fab2_lib.baseboard_fab2(sch_1):page190_i179@mstr_memory.lcmxo2(chips)!LCMXO2_256BGA-IC,H63395-001!!!F2041!PL6B!!!!
S!FM_MP_PS_FAIL_N!U8D7!H4!@baseboard_fab2_lib.baseboard_fab2(sch_1):page190_i179@mstr_memory.lcmxo2(chips)!LCMXO2_256BGA-IC,H63395-001!!!F2041!PL6C!!!!
S!PWRGD_P5V!U8D7!J6!@baseboard_fab2_lib.baseboard_fab2(sch_1):page190_i179@mstr_memory.lcmxo2(chips)!LCMXO2_256BGA-IC,H63395-001!!!F2041!PL6D!!!!
S!RST_PCIE_CPU_DEV2_N!U8D7!H3!@baseboard_fab2_lib.baseboard_fab2(sch_1):page190_i179@mstr_memory.lcmxo2(chips)!LCMXO2_256BGA-IC,H63395-001!!!F2041!PL7A!!!!
S!RST_PCIE_CPU_DEV3_N!U8D7!H1!@baseboard_fab2_lib.baseboard_fab2(sch_1):page190_i179@mstr_memory.lcmxo2(chips)!LCMXO2_256BGA-IC,H63395-001!!!F2041!PL7B!!!!
S!SGPIO_BMC_CLK!U8D7!J1!@baseboard_fab2_lib.baseboard_fab2(sch_1):page190_i179@mstr_memory.lcmxo2(chips)!LCMXO2_256BGA-IC,H63395-001!!!F2041!PL7C_PCLKT4_0!!!!
S!TP_CPLD1_PL7D_PCLKT4_0!U8D7!J3!@baseboard_fab2_lib.baseboard_fab2(sch_1):page190_i179@mstr_memory.lcmxo2(chips)!LCMXO2_256BGA-IC,H63395-001!!!F2041!PL7D_PCLKC4_0!!!!
S!SGPIO_BMC_DOUT!U8D7!J2!@baseboard_fab2_lib.baseboard_fab2(sch_1):page190_i179@mstr_memory.lcmxo2(chips)!LCMXO2_256BGA-IC,H63395-001!!!F2041!PL9A!!!!
S!FM_PVCCIOMCP_CPU0_EN!U8D7!K1!@baseboard_fab2_lib.baseboard_fab2(sch_1):page190_i179@mstr_memory.lcmxo2(chips)!LCMXO2_256BGA-IC,H63395-001!!!F2041!PL9B!!!!
S!SMB_SLOTX24_PCH_STBY_LVC3_SCL!U8D7!H5!@baseboard_fab2_lib.baseboard_fab2(sch_1):page190_i179@mstr_memory.lcmxo2(chips)!LCMXO2_256BGA-IC,H63395-001!!!F2041!PL9C!!!!
S!SMB_SLOTX24_PCH_STBY_LVC3_SDA!U8D7!J4!@baseboard_fab2_lib.baseboard_fab2(sch_1):page190_i179@mstr_memory.lcmxo2(chips)!LCMXO2_256BGA-IC,H63395-001!!!F2041!PL9D!!!!
S!FM_PVDDQ_ABC_EN!U8D7!K14!@baseboard_fab2_lib.baseboard_fab2(sch_1):page191_i59@mstr_memory.lcmxo2(chips)!LCMXO2_256BGA-IC,H63395-001!!!F2040!PR10A!!!!
S!FM_PVDDQ_DEF_EN!U8D7!K15!@baseboard_fab2_lib.baseboard_fab2(sch_1):page191_i59@mstr_memory.lcmxo2(chips)!LCMXO2_256BGA-IC,H63395-001!!!F2040!PR10B!!!!
S!TP_CPLD1_PR10C!U8D7!J11!@baseboard_fab2_lib.baseboard_fab2(sch_1):page191_i59@mstr_memory.lcmxo2(chips)!LCMXO2_256BGA-IC,H63395-001!!!F2040!PR10C!!!!
S!PWRGD_P3V3_STBY!U8D7!L12!@baseboard_fab2_lib.baseboard_fab2(sch_1):page191_i59@mstr_memory.lcmxo2(chips)!LCMXO2_256BGA-IC,H63395-001!!!F2040!PR10D!!!!
S!PWRGD_PVCCIO_CPU1!U8D7!L16!@baseboard_fab2_lib.baseboard_fab2(sch_1):page191_i59@mstr_memory.lcmxo2(chips)!LCMXO2_256BGA-IC,H63395-001!!!F2040!PR11A!!!!
S!TP_CPLD1_PR11B!U8D7!L14!@baseboard_fab2_lib.baseboard_fab2(sch_1):page191_i59@mstr_memory.lcmxo2(chips)!LCMXO2_256BGA-IC,H63395-001!!!F2040!PR11B!!!!
S!FM_MEM_THERM_EVENT_LVT3_N!U8D7!K13!@baseboard_fab2_lib.baseboard_fab2(sch_1):page191_i59@mstr_memory.lcmxo2(chips)!LCMXO2_256BGA-IC,H63395-001!!!F2040!PR11C!!!!
S!FM_MEM_THERM_EVENT_PCH_N!U8D7!K12!@baseboard_fab2_lib.baseboard_fab2(sch_1):page191_i59@mstr_memory.lcmxo2(chips)!LCMXO2_256BGA-IC,H63395-001!!!F2040!PR11D!!!!
S!FM_THERMTRIP_DLY!U8D7!L15!@baseboard_fab2_lib.baseboard_fab2(sch_1):page191_i59@mstr_memory.lcmxo2(chips)!LCMXO2_256BGA-IC,H63395-001!!!F2040!PR12A!!!!
S!FM_CPU0_FIVR_FAULT_LVT3!U8D7!M16!@baseboard_fab2_lib.baseboard_fab2(sch_1):page191_i59@mstr_memory.lcmxo2(chips)!LCMXO2_256BGA-IC,H63395-001!!!F2040!PR12B!!!!
S!RST_PLTRST_BUF_N!U8D7!K11!@baseboard_fab2_lib.baseboard_fab2(sch_1):page191_i59@mstr_memory.lcmxo2(chips)!LCMXO2_256BGA-IC,H63395-001!!!F2040!PR12C!!!!
S!TP_CPLD1_PR12D!U8D7!L13!@baseboard_fab2_lib.baseboard_fab2(sch_1):page191_i59@mstr_memory.lcmxo2(chips)!LCMXO2_256BGA-IC,H63395-001!!!F2040!PR12D!!!!
S!FM_CPU1_PROC_ID1!U8D7!M14!@baseboard_fab2_lib.baseboard_fab2(sch_1):page191_i59@mstr_memory.lcmxo2(chips)!LCMXO2_256BGA-IC,H63395-001!!!F2040!PR13A!!!!
S!FM_CPU1_PROC_ID0!U8D7!M15!@baseboard_fab2_lib.baseboard_fab2(sch_1):page191_i59@mstr_memory.lcmxo2(chips)!LCMXO2_256BGA-IC,H63395-001!!!F2040!PR13B!!!!
S!FM_CPU0_THERMTRIP_LVT3_N!U8D7!N15!@baseboard_fab2_lib.baseboard_fab2(sch_1):page191_i59@mstr_memory.lcmxo2(chips)!LCMXO2_256BGA-IC,H63395-001!!!F2040!PR13C!!!!
S!FM_PVPP_CPU1_EN!U8D7!P16!@baseboard_fab2_lib.baseboard_fab2(sch_1):page191_i59@mstr_memory.lcmxo2(chips)!LCMXO2_256BGA-IC,H63395-001!!!F2040!PR13D!!!!
S!FM_PVCCIN_PVCCSA_CPU1_EN_LVC1!U8D7!N16!@baseboard_fab2_lib.baseboard_fab2(sch_1):page191_i59@mstr_memory.lcmxo2(chips)!LCMXO2_256BGA-IC,H63395-001!!!F2040!PR14A!!!!
S!FM_CPU1_VRM_OSC_EN!U8D7!N14!@baseboard_fab2_lib.baseboard_fab2(sch_1):page191_i59@mstr_memory.lcmxo2(chips)!LCMXO2_256BGA-IC,H63395-001!!!F2040!PR14B!!!!
S!FM_PVPP_CPU0_EN!U8D7!P15!@baseboard_fab2_lib.baseboard_fab2(sch_1):page191_i59@mstr_memory.lcmxo2(chips)!LCMXO2_256BGA-IC,H63395-001!!!F2040!PR14C!!!!
S!FM_P12V_MAIN_SW_EN!U8D7!R16!@baseboard_fab2_lib.baseboard_fab2(sch_1):page191_i59@mstr_memory.lcmxo2(chips)!LCMXO2_256BGA-IC,H63395-001!!!F2040!PR14D!!!!
S!PWRGD_SYS_PWROK!U8D7!D14!@baseboard_fab2_lib.baseboard_fab2(sch_1):page191_i59@mstr_memory.lcmxo2(chips)!LCMXO2_256BGA-IC,H63395-001!!!F2040!PR1A!!!!
S!RST_PLTRST_N!U8D7!E15!@baseboard_fab2_lib.baseboard_fab2(sch_1):page191_i59@mstr_memory.lcmxo2(chips)!LCMXO2_256BGA-IC,H63395-001!!!F2040!PR1B!!!!
S!FM_DB1200_PWRGD!U8D7!C15!@baseboard_fab2_lib.baseboard_fab2(sch_1):page191_i59@mstr_memory.lcmxo2(chips)!LCMXO2_256BGA-IC,H63395-001!!!F2040!PR1C!!!!
S!FM_ADR_COMPLETE_DLY!U8D7!B16!@baseboard_fab2_lib.baseboard_fab2(sch_1):page191_i59@mstr_memory.lcmxo2(chips)!LCMXO2_256BGA-IC,H63395-001!!!F2040!PR1D!!!!
S!PWRGD_P1V8MCP_CPU1!U8D7!D16!@baseboard_fab2_lib.baseboard_fab2(sch_1):page191_i59@mstr_memory.lcmxo2(chips)!LCMXO2_256BGA-IC,H63395-001!!!F2040!PR2A!!!!
S!FM_CPLD_ADR_TRIGGER_N!U8D7!E14!@baseboard_fab2_lib.baseboard_fab2(sch_1):page191_i59@mstr_memory.lcmxo2(chips)!LCMXO2_256BGA-IC,H63395-001!!!F2040!PR2B!!!!
S!PWRGD_PCH_PWROK!U8D7!C16!@baseboard_fab2_lib.baseboard_fab2(sch_1):page191_i59@mstr_memory.lcmxo2(chips)!LCMXO2_256BGA-IC,H63395-001!!!F2040!PR2C!!!!
S!PWRGD_P1V8MCP_CPU0!U8D7!D15!@baseboard_fab2_lib.baseboard_fab2(sch_1):page191_i59@mstr_memory.lcmxo2(chips)!LCMXO2_256BGA-IC,H63395-001!!!F2040!PR2D!!!!
S!FM_P1V8MCP_CPU0_EN!U8D7!E16!@baseboard_fab2_lib.baseboard_fab2(sch_1):page191_i59@mstr_memory.lcmxo2(chips)!LCMXO2_256BGA-IC,H63395-001!!!F2040!PR3A!!!!
S!FM_CPU0_MCP_CLK_EN_N!U8D7!F15!@baseboard_fab2_lib.baseboard_fab2(sch_1):page191_i59@mstr_memory.lcmxo2(chips)!LCMXO2_256BGA-IC,H63395-001!!!F2040!PR3B!!!!
S!PWRGD_CPUPWRGD!U8D7!F13!@baseboard_fab2_lib.baseboard_fab2(sch_1):page191_i59@mstr_memory.lcmxo2(chips)!LCMXO2_256BGA-IC,H63395-001!!!F2040!PR3C!!!!
S!FM_CPU0_THERMTRIP_LATCH_LVT3_N!U8D7!G12!@baseboard_fab2_lib.baseboard_fab2(sch_1):page191_i59@mstr_memory.lcmxo2(chips)!LCMXO2_256BGA-IC,H63395-001!!!F2040!PR3D!!!!
S!RST_BMC_SYSRST_BTN_OUT_B_N!U8D7!F14!@baseboard_fab2_lib.baseboard_fab2(sch_1):page191_i59@mstr_memory.lcmxo2(chips)!LCMXO2_256BGA-IC,H63395-001!!!F2040!PR4A!!!!
S!FM_CPU1_MCP_CLK_EN_N!U8D7!F16!@baseboard_fab2_lib.baseboard_fab2(sch_1):page191_i59@mstr_memory.lcmxo2(chips)!LCMXO2_256BGA-IC,H63395-001!!!F2040!PR4B!!!!
S!FM_P1V8MCP_CPU1_EN!U8D7!F12!@baseboard_fab2_lib.baseboard_fab2(sch_1):page191_i59@mstr_memory.lcmxo2(chips)!LCMXO2_256BGA-IC,H63395-001!!!F2040!PR4C!!!!
S!FM_CPU1_FIVR_FAULT_LVT3!U8D7!G13!@baseboard_fab2_lib.baseboard_fab2(sch_1):page191_i59@mstr_memory.lcmxo2(chips)!LCMXO2_256BGA-IC,H63395-001!!!F2040!PR4D!!!!
S!FM_UV_ADR_TRIGGER_N!U8D7!G15!@baseboard_fab2_lib.baseboard_fab2(sch_1):page191_i59@mstr_memory.lcmxo2(chips)!LCMXO2_256BGA-IC,H63395-001!!!F2040!PR5A!!!!
S!FM_CPU1_THERMTRIP_LVT3_N!U8D7!G14!@baseboard_fab2_lib.baseboard_fab2(sch_1):page191_i59@mstr_memory.lcmxo2(chips)!LCMXO2_256BGA-IC,H63395-001!!!F2040!PR5B!!!!
S!FM_WBG_PRSNT_N!U8D7!G11!@baseboard_fab2_lib.baseboard_fab2(sch_1):page191_i59@mstr_memory.lcmxo2(chips)!LCMXO2_256BGA-IC,H63395-001!!!F2040!PR5C!!!!
S!FM_UV_ADR_TRIGGER_EN!U8D7!H12!@baseboard_fab2_lib.baseboard_fab2(sch_1):page191_i59@mstr_memory.lcmxo2(chips)!LCMXO2_256BGA-IC,H63395-001!!!F2040!PR5D!!!!
S!FM_FAST_PROCHOT_THROTTLE_IN_N!U8D7!G16!@baseboard_fab2_lib.baseboard_fab2(sch_1):page191_i59@mstr_memory.lcmxo2(chips)!LCMXO2_256BGA-IC,H63395-001!!!F2040!PR6A!!!!
S!FM_PVDDQ_KLM_EN!U8D7!H15!@baseboard_fab2_lib.baseboard_fab2(sch_1):page191_i59@mstr_memory.lcmxo2(chips)!LCMXO2_256BGA-IC,H63395-001!!!F2040!PR6B!!!!
S!FM_PVDDQ_GHJ_EN!U8D7!H13!@baseboard_fab2_lib.baseboard_fab2(sch_1):page191_i59@mstr_memory.lcmxo2(chips)!LCMXO2_256BGA-IC,H63395-001!!!F2040!PR6C!!!!
S!FM_FAST_PROCHOT_THROTTLE_DLY_N!U8D7!J12!@baseboard_fab2_lib.baseboard_fab2(sch_1):page191_i59@mstr_memory.lcmxo2(chips)!LCMXO2_256BGA-IC,H63395-001!!!F2040!PR6D!!!!
S!TP_CPLD1_PR7A_PCLKT1_0!U8D7!H14!@baseboard_fab2_lib.baseboard_fab2(sch_1):page191_i59@mstr_memory.lcmxo2(chips)!LCMXO2_256BGA-IC,H63395-001!!!F2040!PR7A_PCLKT1_0!!!!
S!TP_CPLD1_PR7B_PCLKC1_0!U8D7!H16!@baseboard_fab2_lib.baseboard_fab2(sch_1):page191_i59@mstr_memory.lcmxo2(chips)!LCMXO2_256BGA-IC,H63395-001!!!F2040!PR7B_PCLKC1_0!!!!
S!TP_CPLD1_PR7C!U8D7!J16!@baseboard_fab2_lib.baseboard_fab2(sch_1):page191_i59@mstr_memory.lcmxo2(chips)!LCMXO2_256BGA-IC,H63395-001!!!F2040!PR7C!!!!
S!TP_CPLD1_PR7D!U8D7!J14!@baseboard_fab2_lib.baseboard_fab2(sch_1):page191_i59@mstr_memory.lcmxo2(chips)!LCMXO2_256BGA-IC,H63395-001!!!F2040!PR7D!!!!
S!TP_CPLD1_PR9A!U8D7!J15!@baseboard_fab2_lib.baseboard_fab2(sch_1):page191_i59@mstr_memory.lcmxo2(chips)!LCMXO2_256BGA-IC,H63395-001!!!F2040!PR9A!!!!
S!PU_FAB2_MARKER_CPLD!U8D7!K16!@baseboard_fab2_lib.baseboard_fab2(sch_1):page191_i59@mstr_memory.lcmxo2(chips)!LCMXO2_256BGA-IC,H63395-001!!!F2040!PR9B!!!!
S!TP_CPLD1_PR9C!U8D7!H11!@baseboard_fab2_lib.baseboard_fab2(sch_1):page191_i59@mstr_memory.lcmxo2(chips)!LCMXO2_256BGA-IC,H63395-001!!!F2040!PR9C!!!!
S!TP_CPLD1_PR9D!U8D7!J13!@baseboard_fab2_lib.baseboard_fab2(sch_1):page191_i59@mstr_memory.lcmxo2(chips)!LCMXO2_256BGA-IC,H63395-001!!!F2040!PR9D!!!!
S!FM_P3V3_CPLD_EN!U8D7!A4!@baseboard_fab2_lib.baseboard_fab2(sch_1):page191_i59@mstr_memory.lcmxo2(chips)!LCMXO2_256BGA-IC,H63395-001!!!F2040!PT10A!!!!
S!FM_CPU1_THERMTRIP_LATCH_LVT3_N!U8D7!C5!@baseboard_fab2_lib.baseboard_fab2(sch_1):page191_i59@mstr_memory.lcmxo2(chips)!LCMXO2_256BGA-IC,H63395-001!!!F2040!PT10B!!!!
S!TP_CPLD1_PT11A!U8D7!A5!@baseboard_fab2_lib.baseboard_fab2(sch_1):page191_i59@mstr_memory.lcmxo2(chips)!LCMXO2_256BGA-IC,H63395-001!!!F2040!PT11A!!!!
S!TP_CPLD1_PT11B!U8D7!B6!@baseboard_fab2_lib.baseboard_fab2(sch_1):page191_i59@mstr_memory.lcmxo2(chips)!LCMXO2_256BGA-IC,H63395-001!!!F2040!PT11B!!!!
S!FM_PCH_PRSNT_N!U8D7!A3!@baseboard_fab2_lib.baseboard_fab2(sch_1):page191_i59@mstr_memory.lcmxo2(chips)!LCMXO2_256BGA-IC,H63395-001!!!F2040!PT11C!!!!
S!PWRGD_PVTT_CPU0!U8D7!B4!@baseboard_fab2_lib.baseboard_fab2(sch_1):page191_i59@mstr_memory.lcmxo2(chips)!LCMXO2_256BGA-IC,H63395-001!!!F2040!PT11D!!!!
S!RST_PCIE_CPU_DEV0_N!U8D7!D6!@baseboard_fab2_lib.baseboard_fab2(sch_1):page191_i59@mstr_memory.lcmxo2(chips)!LCMXO2_256BGA-IC,H63395-001!!!F2040!PT12A!!!!
S!PWRGD_P1V26_BMC_STBY!U8D7!E7!@baseboard_fab2_lib.baseboard_fab2(sch_1):page191_i59@mstr_memory.lcmxo2(chips)!LCMXO2_256BGA-IC,H63395-001!!!F2040!PT12B!!!!
S!JTAG_PLD_TDO!U8D7!C6!@baseboard_fab2_lib.baseboard_fab2(sch_1):page191_i59@mstr_memory.lcmxo2(chips)!LCMXO2_256BGA-IC,H63395-001!!!F2040!PT12C_TDO!!!!
S!JTAG_PLD_TDI!U8D7!A6!@baseboard_fab2_lib.baseboard_fab2(sch_1):page191_i59@mstr_memory.lcmxo2(chips)!LCMXO2_256BGA-IC,H63395-001!!!F2040!PT12D_TDI!!!!
S!TP_CPLD1_PT13A!U8D7!B7!@baseboard_fab2_lib.baseboard_fab2(sch_1):page191_i59@mstr_memory.lcmxo2(chips)!LCMXO2_256BGA-IC,H63395-001!!!F2040!PT13A!!!!
S!FM_BMC_ONCTL_N!U8D7!C7!@baseboard_fab2_lib.baseboard_fab2(sch_1):page191_i59@mstr_memory.lcmxo2(chips)!LCMXO2_256BGA-IC,H63395-001!!!F2040!PT13B!!!!
S!FM_CPU1_FIVR_FAULT_LVT3_N!U8D7!E6!@baseboard_fab2_lib.baseboard_fab2(sch_1):page191_i59@mstr_memory.lcmxo2(chips)!LCMXO2_256BGA-IC,H63395-001!!!F2040!PT13C!!!!
S!FM_FORCE_ADR_N!U8D7!D7!@baseboard_fab2_lib.baseboard_fab2(sch_1):page191_i59@mstr_memory.lcmxo2(chips)!LCMXO2_256BGA-IC,H63395-001!!!F2040!PT13D!!!!
S!FM_PLD_DEBUG_MODE_N!U8D7!F7!@baseboard_fab2_lib.baseboard_fab2(sch_1):page191_i59@mstr_memory.lcmxo2(chips)!LCMXO2_256BGA-IC,H63395-001!!!F2040!PT16A!!!!
S!TP_CPLD1_PT16B!U8D7!E8!@baseboard_fab2_lib.baseboard_fab2(sch_1):page191_i59@mstr_memory.lcmxo2(chips)!LCMXO2_256BGA-IC,H63395-001!!!F2040!PT16B!!!!
S!JTAG_PLD_TCK!U8D7!A7!@baseboard_fab2_lib.baseboard_fab2(sch_1):page191_i59@mstr_memory.lcmxo2(chips)!LCMXO2_256BGA-IC,H63395-001!!!F2040!PT16C_TCK!!!!
S!JTAG_PLD_TMS!U8D7!B8!@baseboard_fab2_lib.baseboard_fab2(sch_1):page191_i59@mstr_memory.lcmxo2(chips)!LCMXO2_256BGA-IC,H63395-001!!!F2040!PT16D_TMS!!!!
S!FM_ADR_COMPLETE!U8D7!C8!@baseboard_fab2_lib.baseboard_fab2(sch_1):page191_i59@mstr_memory.lcmxo2(chips)!LCMXO2_256BGA-IC,H63395-001!!!F2040!PT17A_PCLKT0_1!!!!
S!TP_CPLD1_PT17B_PCLKC0_1!U8D7!A8!@baseboard_fab2_lib.baseboard_fab2(sch_1):page191_i59@mstr_memory.lcmxo2(chips)!LCMXO2_256BGA-IC,H63395-001!!!F2040!PT17B_PCLKC0_1!!!!
S!TP_CPLD1_PT17C!U8D7!D8!@baseboard_fab2_lib.baseboard_fab2(sch_1):page191_i59@mstr_memory.lcmxo2(chips)!LCMXO2_256BGA-IC,H63395-001!!!F2040!PT17C!!!!
S!FM_SLP_SUS_N!U8D7!E9!@baseboard_fab2_lib.baseboard_fab2(sch_1):page191_i59@mstr_memory.lcmxo2(chips)!LCMXO2_256BGA-IC,H63395-001!!!F2040!PT17D!!!!
S!SGPIO_BMC_DIN_R!U8D7!F8!@baseboard_fab2_lib.baseboard_fab2(sch_1):page191_i59@mstr_memory.lcmxo2(chips)!LCMXO2_256BGA-IC,H63395-001!!!F2040!PT18A!!!!
S!RST_PCIE_MIDPLANE_N!U8D7!D9!@baseboard_fab2_lib.baseboard_fab2(sch_1):page191_i59@mstr_memory.lcmxo2(chips)!LCMXO2_256BGA-IC,H63395-001!!!F2040!PT18B!!!!
S!SMB_SENSOR_STBY_LVC3_SCL!U8D7!A9!@baseboard_fab2_lib.baseboard_fab2(sch_1):page191_i59@mstr_memory.lcmxo2(chips)!LCMXO2_256BGA-IC,H63395-001!!!F2040!PT18C_SCL_PCLKT0_0!!!!
S!SMB_SENSOR_STBY_LVC3_SDA!U8D7!C9!@baseboard_fab2_lib.baseboard_fab2(sch_1):page191_i59@mstr_memory.lcmxo2(chips)!LCMXO2_256BGA-IC,H63395-001!!!F2040!PT18D_SDA_PCLKC0_0!!!!
S!PU_RST_PERST_BIT1!U8D7!B9!@baseboard_fab2_lib.baseboard_fab2(sch_1):page191_i59@mstr_memory.lcmxo2(chips)!LCMXO2_256BGA-IC,H63395-001!!!F2040!PT19A!!!!
S!FM_PVCCIN_PVCCSA_CPU0_EN_LVC1!U8D7!A10!@baseboard_fab2_lib.baseboard_fab2(sch_1):page191_i59@mstr_memory.lcmxo2(chips)!LCMXO2_256BGA-IC,H63395-001!!!F2040!PT19B!!!!
S!FM_PS_EN!U8D7!F9!@baseboard_fab2_lib.baseboard_fab2(sch_1):page191_i59@mstr_memory.lcmxo2(chips)!LCMXO2_256BGA-IC,H63395-001!!!F2040!PT19C!!!!
S!TP_CPLD1_PT19D!U8D7!E11!@baseboard_fab2_lib.baseboard_fab2(sch_1):page191_i59@mstr_memory.lcmxo2(chips)!LCMXO2_256BGA-IC,H63395-001!!!F2040!PT19D!!!!
S!TP_CPLD1_PT20A!U8D7!D10!@baseboard_fab2_lib.baseboard_fab2(sch_1):page191_i59@mstr_memory.lcmxo2(chips)!LCMXO2_256BGA-IC,H63395-001!!!F2040!PT20A!!!!
S!TP_CPLD1_PT20B!U8D7!E10!@baseboard_fab2_lib.baseboard_fab2(sch_1):page191_i59@mstr_memory.lcmxo2(chips)!LCMXO2_256BGA-IC,H63395-001!!!F2040!PT20B!!!!
S!FM_JTAG_PLD_EN_DEBUG!U8D7!C10!@baseboard_fab2_lib.baseboard_fab2(sch_1):page191_i59@mstr_memory.lcmxo2(chips)!LCMXO2_256BGA-IC,H63395-001!!!F2040!PT20C_JTAGENB!!!!
S!TP_CPLD1_PT20D_PROGRAMN!U8D7!B10!@baseboard_fab2_lib.baseboard_fab2(sch_1):page191_i59@mstr_memory.lcmxo2(chips)!LCMXO2_256BGA-IC,H63395-001!!!F2040!PT20D_PROGRAMN!!!!
S!FM_CPU0_OR_CPU1_MCP_PRES!U8D7!A11!@baseboard_fab2_lib.baseboard_fab2(sch_1):page191_i59@mstr_memory.lcmxo2(chips)!LCMXO2_256BGA-IC,H63395-001!!!F2040!PT21A!!!!
S!FM_CPU0_CD_PRES!U8D7!C11!@baseboard_fab2_lib.baseboard_fab2(sch_1):page191_i59@mstr_memory.lcmxo2(chips)!LCMXO2_256BGA-IC,H63395-001!!!F2040!PT21B!!!!
S!FM_CPU1_CD_PRES!U8D7!F10!@baseboard_fab2_lib.baseboard_fab2(sch_1):page191_i59@mstr_memory.lcmxo2(chips)!LCMXO2_256BGA-IC,H63395-001!!!F2040!PT21C!!!!
S!FM_CPU0_AND_CPU1_MCP_PRES!U8D7!D11!@baseboard_fab2_lib.baseboard_fab2(sch_1):page191_i59@mstr_memory.lcmxo2(chips)!LCMXO2_256BGA-IC,H63395-001!!!F2040!PT21D!!!!
S!PWRGD_DSW_PWROK!U8D7!B11!@baseboard_fab2_lib.baseboard_fab2(sch_1):page191_i59@mstr_memory.lcmxo2(chips)!LCMXO2_256BGA-IC,H63395-001!!!F2040!PT22A!!!!
S!PU_THERMTRIP_FORCE_N!U8D7!A12!@baseboard_fab2_lib.baseboard_fab2(sch_1):page191_i59@mstr_memory.lcmxo2(chips)!LCMXO2_256BGA-IC,H63395-001!!!F2040!PT22B!!!!
S!TP_CPLD1_PT22C!U8D7!B13!@baseboard_fab2_lib.baseboard_fab2(sch_1):page191_i59@mstr_memory.lcmxo2(chips)!LCMXO2_256BGA-IC,H63395-001!!!F2040!PT22C!!!!
S!TP_CPLD1_PT22D!U8D7!A14!@baseboard_fab2_lib.baseboard_fab2(sch_1):page191_i59@mstr_memory.lcmxo2(chips)!LCMXO2_256BGA-IC,H63395-001!!!F2040!PT22D!!!!
S!FM_SLPS4_N!U8D7!C12!@baseboard_fab2_lib.baseboard_fab2(sch_1):page191_i59@mstr_memory.lcmxo2(chips)!LCMXO2_256BGA-IC,H63395-001!!!F2040!PT23A!!!!
S!FM_PCH_PWRBTN_N!U8D7!B12!@baseboard_fab2_lib.baseboard_fab2(sch_1):page191_i59@mstr_memory.lcmxo2(chips)!LCMXO2_256BGA-IC,H63395-001!!!F2040!PT23B!!!!
S!FM_SINT_PRSNT_N!U8D7!B14!@baseboard_fab2_lib.baseboard_fab2(sch_1):page191_i59@mstr_memory.lcmxo2(chips)!LCMXO2_256BGA-IC,H63395-001!!!F2040!PT24A!!!!
S!TP_CPLD1_PT24B!U8D7!A15!@baseboard_fab2_lib.baseboard_fab2(sch_1):page191_i59@mstr_memory.lcmxo2(chips)!LCMXO2_256BGA-IC,H63395-001!!!F2040!PT24B!!!!
S!TP_CPLD1_PT24C_INITN!U8D7!A13!@baseboard_fab2_lib.baseboard_fab2(sch_1):page191_i59@mstr_memory.lcmxo2(chips)!LCMXO2_256BGA-IC,H63395-001!!!F2040!PT24C_INITN!!!!
S!TP_CPLD1_PT24D_DONE!U8D7!C13!@baseboard_fab2_lib.baseboard_fab2(sch_1):page191_i59@mstr_memory.lcmxo2(chips)!LCMXO2_256BGA-IC,H63395-001!!!F2040!PT24D_DONE!!!!
S!FM_ADR_SMI_GPIO_R_N!U8D7!C4!@baseboard_fab2_lib.baseboard_fab2(sch_1):page191_i59@mstr_memory.lcmxo2(chips)!LCMXO2_256BGA-IC,H63395-001!!!F2040!PT9A!!!!
S!PWRGD_P12V_MAIN!U8D7!B5!@baseboard_fab2_lib.baseboard_fab2(sch_1):page191_i59@mstr_memory.lcmxo2(chips)!LCMXO2_256BGA-IC,H63395-001!!!F2040!PT9B!!!!
S!FM_CTNR_PS_ON!U8D7!B3!@baseboard_fab2_lib.baseboard_fab2(sch_1):page191_i59@mstr_memory.lcmxo2(chips)!LCMXO2_256BGA-IC,H63395-001!!!F2040!PT9C!!!!
S!GND!U8D7!B2!@baseboard_fab2_lib.baseboard_fab2(sch_1):page192_i14@mstr_memory.lcmxo2(chips)!LCMXO2_256BGA-IC,H63395-001!!!F2039!GND(0)!!!!
S!GND!U8D7!H8!@baseboard_fab2_lib.baseboard_fab2(sch_1):page192_i14@mstr_memory.lcmxo2(chips)!LCMXO2_256BGA-IC,H63395-001!!!F2039!GND(10)!!!!
S!GND!U8D7!H9!@baseboard_fab2_lib.baseboard_fab2(sch_1):page192_i14@mstr_memory.lcmxo2(chips)!LCMXO2_256BGA-IC,H63395-001!!!F2039!GND(11)!!!!
S!GND!U8D7!J8!@baseboard_fab2_lib.baseboard_fab2(sch_1):page192_i14@mstr_memory.lcmxo2(chips)!LCMXO2_256BGA-IC,H63395-001!!!F2039!GND(12)!!!!
S!GND!U8D7!J9!@baseboard_fab2_lib.baseboard_fab2(sch_1):page192_i14@mstr_memory.lcmxo2(chips)!LCMXO2_256BGA-IC,H63395-001!!!F2039!GND(13)!!!!
S!GND!U8D7!L6!@baseboard_fab2_lib.baseboard_fab2(sch_1):page192_i14@mstr_memory.lcmxo2(chips)!LCMXO2_256BGA-IC,H63395-001!!!F2039!GND(14)!!!!
S!GND!U8D7!L11!@baseboard_fab2_lib.baseboard_fab2(sch_1):page192_i14@mstr_memory.lcmxo2(chips)!LCMXO2_256BGA-IC,H63395-001!!!F2039!GND(15)!!!!
S!GND!U8D7!M5!@baseboard_fab2_lib.baseboard_fab2(sch_1):page192_i14@mstr_memory.lcmxo2(chips)!LCMXO2_256BGA-IC,H63395-001!!!F2039!GND(16)!!!!
S!GND!U8D7!M12!@baseboard_fab2_lib.baseboard_fab2(sch_1):page192_i14@mstr_memory.lcmxo2(chips)!LCMXO2_256BGA-IC,H63395-001!!!F2039!GND(17)!!!!
S!GND!U8D7!N4!@baseboard_fab2_lib.baseboard_fab2(sch_1):page192_i14@mstr_memory.lcmxo2(chips)!LCMXO2_256BGA-IC,H63395-001!!!F2039!GND(18)!!!!
S!GND!U8D7!N13!@baseboard_fab2_lib.baseboard_fab2(sch_1):page192_i14@mstr_memory.lcmxo2(chips)!LCMXO2_256BGA-IC,H63395-001!!!F2039!GND(19)!!!!
S!GND!U8D7!B15!@baseboard_fab2_lib.baseboard_fab2(sch_1):page192_i14@mstr_memory.lcmxo2(chips)!LCMXO2_256BGA-IC,H63395-001!!!F2039!GND(1)!!!!
S!GND!U8D7!P3!@baseboard_fab2_lib.baseboard_fab2(sch_1):page192_i14@mstr_memory.lcmxo2(chips)!LCMXO2_256BGA-IC,H63395-001!!!F2039!GND(20)!!!!
S!GND!U8D7!P14!@baseboard_fab2_lib.baseboard_fab2(sch_1):page192_i14@mstr_memory.lcmxo2(chips)!LCMXO2_256BGA-IC,H63395-001!!!F2039!GND(21)!!!!
S!GND!U8D7!R2!@baseboard_fab2_lib.baseboard_fab2(sch_1):page192_i14@mstr_memory.lcmxo2(chips)!LCMXO2_256BGA-IC,H63395-001!!!F2039!GND(22)!!!!
S!GND!U8D7!R15!@baseboard_fab2_lib.baseboard_fab2(sch_1):page192_i14@mstr_memory.lcmxo2(chips)!LCMXO2_256BGA-IC,H63395-001!!!F2039!GND(23)!!!!
S!GND!U8D7!C3!@baseboard_fab2_lib.baseboard_fab2(sch_1):page192_i14@mstr_memory.lcmxo2(chips)!LCMXO2_256BGA-IC,H63395-001!!!F2039!GND(2)!!!!
S!GND!U8D7!C14!@baseboard_fab2_lib.baseboard_fab2(sch_1):page192_i14@mstr_memory.lcmxo2(chips)!LCMXO2_256BGA-IC,H63395-001!!!F2039!GND(3)!!!!
S!GND!U8D7!D4!@baseboard_fab2_lib.baseboard_fab2(sch_1):page192_i14@mstr_memory.lcmxo2(chips)!LCMXO2_256BGA-IC,H63395-001!!!F2039!GND(4)!!!!
S!GND!U8D7!D13!@baseboard_fab2_lib.baseboard_fab2(sch_1):page192_i14@mstr_memory.lcmxo2(chips)!LCMXO2_256BGA-IC,H63395-001!!!F2039!GND(5)!!!!
S!GND!U8D7!E5!@baseboard_fab2_lib.baseboard_fab2(sch_1):page192_i14@mstr_memory.lcmxo2(chips)!LCMXO2_256BGA-IC,H63395-001!!!F2039!GND(6)!!!!
S!GND!U8D7!E12!@baseboard_fab2_lib.baseboard_fab2(sch_1):page192_i14@mstr_memory.lcmxo2(chips)!LCMXO2_256BGA-IC,H63395-001!!!F2039!GND(7)!!!!
S!GND!U8D7!F6!@baseboard_fab2_lib.baseboard_fab2(sch_1):page192_i14@mstr_memory.lcmxo2(chips)!LCMXO2_256BGA-IC,H63395-001!!!F2039!GND(8)!!!!
S!GND!U8D7!F11!@baseboard_fab2_lib.baseboard_fab2(sch_1):page192_i14@mstr_memory.lcmxo2(chips)!LCMXO2_256BGA-IC,H63395-001!!!F2039!GND(9)!!!!
S!NC_CPLD1!U8D7!A2!@baseboard_fab2_lib.baseboard_fab2(sch_1):page192_i14@mstr_memory.lcmxo2(chips)!LCMXO2_256BGA-IC,H63395-001!!!F2039!NC(0)!!!!
S!P3V3_STBY!U8D7!A1!@baseboard_fab2_lib.baseboard_fab2(sch_1):page192_i14@mstr_memory.lcmxo2(chips)!LCMXO2_256BGA-IC,H63395-001!!!F2039!VCC(0)!!!!
S!P3V3_STBY!U8D7!A16!@baseboard_fab2_lib.baseboard_fab2(sch_1):page192_i14@mstr_memory.lcmxo2(chips)!LCMXO2_256BGA-IC,H63395-001!!!F2039!VCC(1)!!!!
S!P3V3_STBY!U8D7!T1!@baseboard_fab2_lib.baseboard_fab2(sch_1):page192_i14@mstr_memory.lcmxo2(chips)!LCMXO2_256BGA-IC,H63395-001!!!F2039!VCC(2)!!!!
S!P3V3_STBY!U8D7!T16!@baseboard_fab2_lib.baseboard_fab2(sch_1):page192_i14@mstr_memory.lcmxo2(chips)!LCMXO2_256BGA-IC,H63395-001!!!F2039!VCC(3)!!!!
S!P3V3_STBY!U8D7!G7!@baseboard_fab2_lib.baseboard_fab2(sch_1):page192_i14@mstr_memory.lcmxo2(chips)!LCMXO2_256BGA-IC,H63395-001!!!F2039!VCC(4)!!!!
S!P3V3_STBY!U8D7!G10!@baseboard_fab2_lib.baseboard_fab2(sch_1):page192_i14@mstr_memory.lcmxo2(chips)!LCMXO2_256BGA-IC,H63395-001!!!F2039!VCC(5)!!!!
S!P3V3_STBY!U8D7!K7!@baseboard_fab2_lib.baseboard_fab2(sch_1):page192_i14@mstr_memory.lcmxo2(chips)!LCMXO2_256BGA-IC,H63395-001!!!F2039!VCC(6)!!!!
S!P3V3_STBY!U8D7!K10!@baseboard_fab2_lib.baseboard_fab2(sch_1):page192_i14@mstr_memory.lcmxo2(chips)!LCMXO2_256BGA-IC,H63395-001!!!F2039!VCC(7)!!!!
S!P3V3_STBY!U8D7!G8!@baseboard_fab2_lib.baseboard_fab2(sch_1):page192_i14@mstr_memory.lcmxo2(chips)!LCMXO2_256BGA-IC,H63395-001!!!F2039!VCCIO0(0)!!!!
S!P3V3_STBY!U8D7!D12!@baseboard_fab2_lib.baseboard_fab2(sch_1):page192_i14@mstr_memory.lcmxo2(chips)!LCMXO2_256BGA-IC,H63395-001!!!F2039!VCCIO0(1)!!!!
S!P3V3_STBY!U8D7!G9!@baseboard_fab2_lib.baseboard_fab2(sch_1):page192_i14@mstr_memory.lcmxo2(chips)!LCMXO2_256BGA-IC,H63395-001!!!F2039!VCCIO0(2)!!!!
S!P3V3_STBY!U8D7!D5!@baseboard_fab2_lib.baseboard_fab2(sch_1):page192_i14@mstr_memory.lcmxo2(chips)!LCMXO2_256BGA-IC,H63395-001!!!F2039!VCCIO0(3)!!!!
S!P3V3_STBY!U8D7!E13!@baseboard_fab2_lib.baseboard_fab2(sch_1):page192_i14@mstr_memory.lcmxo2(chips)!LCMXO2_256BGA-IC,H63395-001!!!F2039!VCCIO1(0)!!!!
S!P3V3_STBY!U8D7!H10!@baseboard_fab2_lib.baseboard_fab2(sch_1):page192_i14@mstr_memory.lcmxo2(chips)!LCMXO2_256BGA-IC,H63395-001!!!F2039!VCCIO1(1)!!!!
S!P3V3_STBY!U8D7!J10!@baseboard_fab2_lib.baseboard_fab2(sch_1):page192_i14@mstr_memory.lcmxo2(chips)!LCMXO2_256BGA-IC,H63395-001!!!F2039!VCCIO1(2)!!!!
S!P3V3_STBY!U8D7!M13!@baseboard_fab2_lib.baseboard_fab2(sch_1):page192_i14@mstr_memory.lcmxo2(chips)!LCMXO2_256BGA-IC,H63395-001!!!F2039!VCCIO1(3)!!!!
S!P3V3_STBY!U8D7!K9!@baseboard_fab2_lib.baseboard_fab2(sch_1):page192_i14@mstr_memory.lcmxo2(chips)!LCMXO2_256BGA-IC,H63395-001!!!F2039!VCCIO2(0)!!!!
S!P3V3_STBY!U8D7!N12!@baseboard_fab2_lib.baseboard_fab2(sch_1):page192_i14@mstr_memory.lcmxo2(chips)!LCMXO2_256BGA-IC,H63395-001!!!F2039!VCCIO2(1)!!!!
S!P3V3_STBY!U8D7!K8!@baseboard_fab2_lib.baseboard_fab2(sch_1):page192_i14@mstr_memory.lcmxo2(chips)!LCMXO2_256BGA-IC,H63395-001!!!F2039!VCCIO2(2)!!!!
S!P3V3_STBY!U8D7!N5!@baseboard_fab2_lib.baseboard_fab2(sch_1):page192_i14@mstr_memory.lcmxo2(chips)!LCMXO2_256BGA-IC,H63395-001!!!F2039!VCCIO2(3)!!!!
S!P3V3_STBY!U8D7!M4!@baseboard_fab2_lib.baseboard_fab2(sch_1):page192_i14@mstr_memory.lcmxo2(chips)!LCMXO2_256BGA-IC,H63395-001!!!F2039!VCCIO3(0)!!!!
S!P3V3_STBY!U8D7!J7!@baseboard_fab2_lib.baseboard_fab2(sch_1):page192_i14@mstr_memory.lcmxo2(chips)!LCMXO2_256BGA-IC,H63395-001!!!F2039!VCCIO4(0)!!!!
S!P3V3_STBY!U8D7!H7!@baseboard_fab2_lib.baseboard_fab2(sch_1):page192_i14@mstr_memory.lcmxo2(chips)!LCMXO2_256BGA-IC,H63395-001!!!F2039!VCCIO4(1)!!!!
S!P3V3_STBY!U8D7!E4!@baseboard_fab2_lib.baseboard_fab2(sch_1):page192_i14@mstr_memory.lcmxo2(chips)!LCMXO2_256BGA-IC,H63395-001!!!F2039!VCCIO5(0)!!!!
S!SGPIO_BMC_DIN_R!R2R6!1!@baseboard_fab2_lib.baseboard_fab2(sch_1):page191_i166@mstr_discrete.res(chips)!RES_0402-51,5.0%,1/16W,CHIP,G2A!!!F383!A!!!!
S!SGPIO_BMC_DIN!R2R6!2!@baseboard_fab2_lib.baseboard_fab2(sch_1):page191_i166@mstr_discrete.res(chips)!RES_0402-51,5.0%,1/16W,CHIP,G2A!!!F383!B!!!!
S!SGPIO_BMC_LD_R_N!R1U12!1!@baseboard_fab2_lib.baseboard_fab2(sch_1):page144_i547@mstr_discrete.res(chips)!RES_0402-51,5.0%,1/16W,CHIP,G2A!!!F386!A!!!!
S!SGPIO_BMC_LD_N!R1U12!2!@baseboard_fab2_lib.baseboard_fab2(sch_1):page144_i547@mstr_discrete.res(chips)!RES_0402-51,5.0%,1/16W,CHIP,G2A!!!F386!B!!!!
S!SGPIO_BMC_DOUT_R!R1U13!1!@baseboard_fab2_lib.baseboard_fab2(sch_1):page144_i546@mstr_discrete.res(chips)!RES_0402-51,5.0%,1/16W,CHIP,G2A!!!F385!A!!!!
S!SGPIO_BMC_DOUT!R1U13!2!@baseboard_fab2_lib.baseboard_fab2(sch_1):page144_i546@mstr_discrete.res(chips)!RES_0402-51,5.0%,1/16W,CHIP,G2A!!!F385!B!!!!
S!SGPIO_BMC_CLK_R!R1U14!1!@baseboard_fab2_lib.baseboard_fab2(sch_1):page144_i548@mstr_discrete.res(chips)!RES_0402-51,5.0%,1/16W,CHIP,G2A!!!F384!A!!!!
S!SGPIO_BMC_CLK!R1U14!2!@baseboard_fab2_lib.baseboard_fab2(sch_1):page144_i548@mstr_discrete.res(chips)!RES_0402-51,5.0%,1/16W,CHIP,G2A!!!F384!B!!!!
S!P5V_STBY_DBG!F1L1!1!@baseboard_fab2_lib.baseboard_fab2(sch_1):page155_i129@mstr_discrete.fuse(chips)!FUSE_SMT-IC,H45581-001!1!!F2126!A(0)!!!!
S!P5V_STBY_DGB_FS!F1L1!2!@baseboard_fab2_lib.baseboard_fab2(sch_1):page155_i129@mstr_discrete.fuse(chips)!FUSE_SMT-IC,H45581-001!1!!F2126!B(0)!!!!
S!GND!R9F32!1!@baseboard_fab2_lib.baseboard_fab2(sch_1):page239_i15@mstr_discrete.res(chips)!RES_0402-13K,1.0%,1/16W,CHIP,GA!!!F1105!A!!!!
S!VR_P1V538_BMC_STBY_FB!R9F32!2!@baseboard_fab2_lib.baseboard_fab2(sch_1):page239_i15@mstr_discrete.res(chips)!RES_0402-13K,1.0%,1/16W,CHIP,GA!!!F1105!B!!!!
S!FM_DEBUG_RST_BTN_N!S9A1!1!@baseboard_fab2_lib.baseboard_fab2(sch_1):page175_i78@mstr_misc.switch_d37771002(chips)!SWITCH_D37771002_SM-IC,D37771-A!!!F65!PIN1!!!!
S!FM_DEBUG_RST_BTN_N!S9A1!2!@baseboard_fab2_lib.baseboard_fab2(sch_1):page175_i78@mstr_misc.switch_d37771002(chips)!SWITCH_D37771002_SM-IC,D37771-A!!!F65!PIN2!!!!
S!GND!S9A1!3!@baseboard_fab2_lib.baseboard_fab2(sch_1):page175_i78@mstr_misc.switch_d37771002(chips)!SWITCH_D37771002_SM-IC,D37771-A!!!F65!PIN3!!!!
S!GND!S9A1!4!@baseboard_fab2_lib.baseboard_fab2(sch_1):page175_i78@mstr_misc.switch_d37771002(chips)!SWITCH_D37771002_SM-IC,D37771-A!!!F65!PIN4!!!!
S!VR_PVDDQ_ABC_PH1_SW!L7G1!1!@baseboard_fab2_lib.baseboard_fab2(sch_1):page216_i55@mstr_discrete.inductor(chips)!INDUCTOR_SM-0.12UH,IND,D92183-A!!!F2102!INA!!!!
S!PVDDQ_ABC!L7G1!2!@baseboard_fab2_lib.baseboard_fab2(sch_1):page216_i55@mstr_discrete.inductor(chips)!INDUCTOR_SM-0.12UH,IND,D92183-A!!!F2102!INB!!!!
S!VR_PVDDQ_ABC_PH2_SW!L7G2!1!@baseboard_fab2_lib.baseboard_fab2(sch_1):page216_i65@mstr_discrete.inductor(chips)!INDUCTOR_SM-0.12UH,IND,D92183-A!!!F2101!INA!!!!
S!PVDDQ_ABC!L7G2!2!@baseboard_fab2_lib.baseboard_fab2(sch_1):page216_i65@mstr_discrete.inductor(chips)!INDUCTOR_SM-0.12UH,IND,D92183-A!!!F2101!INB!!!!
S!VR_PVDDQ_DEF_PH1_SW!L7A1!1!@baseboard_fab2_lib.baseboard_fab2(sch_1):page219_i55@mstr_discrete.inductor(chips)!INDUCTOR_SM-0.12UH,IND,D92183-A!!!F2104!INA!!!!
S!PVDDQ_DEF!L7A1!2!@baseboard_fab2_lib.baseboard_fab2(sch_1):page219_i55@mstr_discrete.inductor(chips)!INDUCTOR_SM-0.12UH,IND,D92183-A!!!F2104!INB!!!!
S!VR_PVDDQ_DEF_PH2_SW!L7A3!1!@baseboard_fab2_lib.baseboard_fab2(sch_1):page219_i65@mstr_discrete.inductor(chips)!INDUCTOR_SM-0.12UH,IND,D92183-A!!!F2103!INA!!!!
S!PVDDQ_DEF!L7A3!2!@baseboard_fab2_lib.baseboard_fab2(sch_1):page219_i65@mstr_discrete.inductor(chips)!INDUCTOR_SM-0.12UH,IND,D92183-A!!!F2103!INB!!!!
S!VR_PVDDQ_KLM_PH1_SW!L1A2!1!@baseboard_fab2_lib.baseboard_fab2(sch_1):page227_i55@mstr_discrete.inductor(chips)!INDUCTOR_SM-0.12UH,IND,D92183-A!!!F2117!INA!!!!
S!PVDDQ_KLM!L1A2!2!@baseboard_fab2_lib.baseboard_fab2(sch_1):page227_i55@mstr_discrete.inductor(chips)!INDUCTOR_SM-0.12UH,IND,D92183-A!!!F2117!INB!!!!
S!VR_PVDDQ_KLM_PH2_SW!L1A1!1!@baseboard_fab2_lib.baseboard_fab2(sch_1):page227_i65@mstr_discrete.inductor(chips)!INDUCTOR_SM-0.12UH,IND,D92183-A!!!F2118!INA!!!!
S!PVDDQ_KLM!L1A1!2!@baseboard_fab2_lib.baseboard_fab2(sch_1):page227_i65@mstr_discrete.inductor(chips)!INDUCTOR_SM-0.12UH,IND,D92183-A!!!F2118!INB!!!!
S!VR_PVDDQ_GHJ_PH1_SW!L1G1!1!@baseboard_fab2_lib.baseboard_fab2(sch_1):page224_i55@mstr_discrete.inductor(chips)!INDUCTOR_SM-0.12UH,IND,D92183-A!!!F2110!INA!!!!
S!PVDDQ_GHJ!L1G1!2!@baseboard_fab2_lib.baseboard_fab2(sch_1):page224_i55@mstr_discrete.inductor(chips)!INDUCTOR_SM-0.12UH,IND,D92183-A!!!F2110!INB!!!!
S!VR_PVDDQ_GHJ_PH2_SW!L1F2!1!@baseboard_fab2_lib.baseboard_fab2(sch_1):page224_i65@mstr_discrete.inductor(chips)!INDUCTOR_SM-0.12UH,IND,D92183-A!!!F2111!INA!!!!
S!PVDDQ_GHJ!L1F2!2!@baseboard_fab2_lib.baseboard_fab2(sch_1):page224_i65@mstr_discrete.inductor(chips)!INDUCTOR_SM-0.12UH,IND,D92183-A!!!F2111!INB!!!!
S!VR_PVCCIN_CPU0_PHASE3!L4D2!1!@baseboard_fab2_lib.baseboard_fab2(sch_1):page203_i15@mstr_discrete.inductor(chips)!INDUCTOR_SM-0.12UH,IND,D92183-A!!!F2107!INA!!!!
S!PVCCIN_CPU0!L4D2!2!@baseboard_fab2_lib.baseboard_fab2(sch_1):page203_i15@mstr_discrete.inductor(chips)!INDUCTOR_SM-0.12UH,IND,D92183-A!!!F2107!INB!!!!
S!VR_PVCCIN_CPU0_PHASE4!L4D1!1!@baseboard_fab2_lib.baseboard_fab2(sch_1):page203_i24@mstr_discrete.inductor(chips)!INDUCTOR_SM-0.12UH,IND,D92183-A!!!F2108!INA!!!!
S!PVCCIN_CPU0!L4D1!2!@baseboard_fab2_lib.baseboard_fab2(sch_1):page203_i24@mstr_discrete.inductor(chips)!INDUCTOR_SM-0.12UH,IND,D92183-A!!!F2108!INB!!!!
S!VR_PVCCIN_CPU0_PHASE5!L4C3!1!@baseboard_fab2_lib.baseboard_fab2(sch_1):page204_i5@mstr_discrete.inductor(chips)!INDUCTOR_SM-0.12UH,IND,D92183-A!!!F2109!INA!!!!
S!PVCCIN_CPU0!L4C3!2!@baseboard_fab2_lib.baseboard_fab2(sch_1):page204_i5@mstr_discrete.inductor(chips)!INDUCTOR_SM-0.12UH,IND,D92183-A!!!F2109!INB!!!!
S!VR_PVCCIN_CPU0_PHASE2!L4D3!1!@baseboard_fab2_lib.baseboard_fab2(sch_1):page202_i29@mstr_discrete.inductor(chips)!INDUCTOR_SM-0.12UH,IND,D92183-A!!!F2106!INA!!!!
S!PVCCIN_CPU0!L4D3!2!@baseboard_fab2_lib.baseboard_fab2(sch_1):page202_i29@mstr_discrete.inductor(chips)!INDUCTOR_SM-0.12UH,IND,D92183-A!!!F2106!INB!!!!
S!VR_PVCCIN_CPU0_PHASE1!L4E1!1!@baseboard_fab2_lib.baseboard_fab2(sch_1):page202_i5@mstr_discrete.inductor(chips)!INDUCTOR_SM-0.12UH,IND,D92183-A!!!F2105!INA!!!!
S!PVCCIN_CPU0!L4E1!2!@baseboard_fab2_lib.baseboard_fab2(sch_1):page202_i5@mstr_discrete.inductor(chips)!INDUCTOR_SM-0.12UH,IND,D92183-A!!!F2105!INB!!!!
S!VR_PVCCIN_CPU1_PHASE2!L1D3!1!@baseboard_fab2_lib.baseboard_fab2(sch_1):page207_i16@mstr_discrete.inductor(chips)!INDUCTOR_SM-0.12UH,IND,D92183-A!!!F2113!INA!!!!
S!PVCCIN_CPU1!L1D3!2!@baseboard_fab2_lib.baseboard_fab2(sch_1):page207_i16@mstr_discrete.inductor(chips)!INDUCTOR_SM-0.12UH,IND,D92183-A!!!F2113!INB!!!!
S!VR_PVCCIN_CPU1_PHASE1!L1E1!1!@baseboard_fab2_lib.baseboard_fab2(sch_1):page207_i10@mstr_discrete.inductor(chips)!INDUCTOR_SM-0.12UH,IND,D92183-A!!!F2112!INA!!!!
S!PVCCIN_CPU1!L1E1!2!@baseboard_fab2_lib.baseboard_fab2(sch_1):page207_i10@mstr_discrete.inductor(chips)!INDUCTOR_SM-0.12UH,IND,D92183-A!!!F2112!INB!!!!
S!VR_PVCCIN_CPU1_PHASE3!L1D2!1!@baseboard_fab2_lib.baseboard_fab2(sch_1):page208_i11@mstr_discrete.inductor(chips)!INDUCTOR_SM-0.12UH,IND,D92183-A!!!F2114!INA!!!!
S!PVCCIN_CPU1!L1D2!2!@baseboard_fab2_lib.baseboard_fab2(sch_1):page208_i11@mstr_discrete.inductor(chips)!INDUCTOR_SM-0.12UH,IND,D92183-A!!!F2114!INB!!!!
S!VR_PVCCIN_CPU1_PHASE4!L1D1!1!@baseboard_fab2_lib.baseboard_fab2(sch_1):page208_i20@mstr_discrete.inductor(chips)!INDUCTOR_SM-0.12UH,IND,D92183-A!!!F2115!INA!!!!
S!PVCCIN_CPU1!L1D1!2!@baseboard_fab2_lib.baseboard_fab2(sch_1):page208_i20@mstr_discrete.inductor(chips)!INDUCTOR_SM-0.12UH,IND,D92183-A!!!F2115!INB!!!!
S!VR_PVCCIN_CPU1_PHASE5!L1C2!1!@baseboard_fab2_lib.baseboard_fab2(sch_1):page209_i40@mstr_discrete.inductor(chips)!INDUCTOR_SM-0.12UH,IND,D92183-A!!!F2116!INA!!!!
S!PVCCIN_CPU1!L1C2!2!@baseboard_fab2_lib.baseboard_fab2(sch_1):page209_i40@mstr_discrete.inductor(chips)!INDUCTOR_SM-0.12UH,IND,D92183-A!!!F2116!INB!!!!
S!P1V538_BMC_STBY!R9F31!1!@baseboard_fab2_lib.baseboard_fab2(sch_1):page239_i14@mstr_discrete.res(chips)!RES_0402-12K,1%,1/16W,CHIP,G21A!!!F1106!A!!!!
S!VR_P1V538_BMC_STBY_FB!R9F31!2!@baseboard_fab2_lib.baseboard_fab2(sch_1):page239_i14@mstr_discrete.res(chips)!RES_0402-12K,1%,1/16W,CHIP,G21A!!!F1106!B!!!!
S!VR_P1V26_BMC_STBY_FB!EU9F1!4!@baseboard_fab2_lib.baseboard_fab2(sch_1):page238_i40@mstr_vreg.rt9059(chips)!RT9059_DFN-IC,H65765-001!!!F244!ADJ_NC!!!!
S!PWRGD_P1V538_BMC_STBY!EU9F1!6!@baseboard_fab2_lib.baseboard_fab2(sch_1):page238_i40@mstr_vreg.rt9059(chips)!RT9059_DFN-IC,H65765-001!!!F244!EN!!!!
S!GND!EU9F1!11!@baseboard_fab2_lib.baseboard_fab2(sch_1):page238_i40@mstr_vreg.rt9059(chips)!RT9059_DFN-IC,H65765-001!!!F244!GND!!!!
S!PWRGD_P1V26_BMC_STBY_R!EU9F1!5!@baseboard_fab2_lib.baseboard_fab2(sch_1):page238_i40@mstr_vreg.rt9059(chips)!RT9059_DFN-IC,H65765-001!!!F244!PGOOD!!!!
S!P3V3_STBY!EU9F1!10!@baseboard_fab2_lib.baseboard_fab2(sch_1):page238_i40@mstr_vreg.rt9059(chips)!RT9059_DFN-IC,H65765-001!!!F244!VDD!!!!
S!P1V538_BMC_STBY!EU9F1!7!@baseboard_fab2_lib.baseboard_fab2(sch_1):page238_i40@mstr_vreg.rt9059(chips)!RT9059_DFN-IC,H65765-001!!!F244!VIN(0)!!!!
S!P1V538_BMC_STBY!EU9F1!8!@baseboard_fab2_lib.baseboard_fab2(sch_1):page238_i40@mstr_vreg.rt9059(chips)!RT9059_DFN-IC,H65765-001!!!F244!VIN(1)!!!!
S!P1V538_BMC_STBY!EU9F1!9!@baseboard_fab2_lib.baseboard_fab2(sch_1):page238_i40@mstr_vreg.rt9059(chips)!RT9059_DFN-IC,H65765-001!!!F244!VIN(2)!!!!
S!P1V26_BMC_STBY!EU9F1!1!@baseboard_fab2_lib.baseboard_fab2(sch_1):page238_i40@mstr_vreg.rt9059(chips)!RT9059_DFN-IC,H65765-001!!!F244!VOUT(0)!!!!
S!P1V26_BMC_STBY!EU9F1!2!@baseboard_fab2_lib.baseboard_fab2(sch_1):page238_i40@mstr_vreg.rt9059(chips)!RT9059_DFN-IC,H65765-001!!!F244!VOUT(1)!!!!
S!P1V26_BMC_STBY!EU9F1!3!@baseboard_fab2_lib.baseboard_fab2(sch_1):page238_i40@mstr_vreg.rt9059(chips)!RT9059_DFN-IC,H65765-001!!!F244!VOUT(2)!!!!
S!VR_P1V8_PCH_STBY_FB!EU8A2!4!@baseboard_fab2_lib.baseboard_fab2(sch_1):page237_i86@mstr_vreg.rt9059(chips)!RT9059_DFN-IC,H65765-001!!!F245!ADJ_NC!!!!
S!PWRGD_P3V3_STBY!EU8A2!6!@baseboard_fab2_lib.baseboard_fab2(sch_1):page237_i86@mstr_vreg.rt9059(chips)!RT9059_DFN-IC,H65765-001!!!F245!EN!!!!
S!GND!EU8A2!11!@baseboard_fab2_lib.baseboard_fab2(sch_1):page237_i86@mstr_vreg.rt9059(chips)!RT9059_DFN-IC,H65765-001!!!F245!GND!!!!
S!PWRGD_P1V8_PCH_STBY_R!EU8A2!5!@baseboard_fab2_lib.baseboard_fab2(sch_1):page237_i86@mstr_vreg.rt9059(chips)!RT9059_DFN-IC,H65765-001!!!F245!PGOOD!!!!
S!P3V3_STBY!EU8A2!10!@baseboard_fab2_lib.baseboard_fab2(sch_1):page237_i86@mstr_vreg.rt9059(chips)!RT9059_DFN-IC,H65765-001!!!F245!VDD!!!!
S!P3V3_STBY!EU8A2!7!@baseboard_fab2_lib.baseboard_fab2(sch_1):page237_i86@mstr_vreg.rt9059(chips)!RT9059_DFN-IC,H65765-001!!!F245!VIN(0)!!!!
S!P3V3_STBY!EU8A2!8!@baseboard_fab2_lib.baseboard_fab2(sch_1):page237_i86@mstr_vreg.rt9059(chips)!RT9059_DFN-IC,H65765-001!!!F245!VIN(1)!!!!
S!P3V3_STBY!EU8A2!9!@baseboard_fab2_lib.baseboard_fab2(sch_1):page237_i86@mstr_vreg.rt9059(chips)!RT9059_DFN-IC,H65765-001!!!F245!VIN(2)!!!!
S!P1V8_PCH_STBY!EU8A2!1!@baseboard_fab2_lib.baseboard_fab2(sch_1):page237_i86@mstr_vreg.rt9059(chips)!RT9059_DFN-IC,H65765-001!!!F245!VOUT(0)!!!!
S!P1V8_PCH_STBY!EU8A2!2!@baseboard_fab2_lib.baseboard_fab2(sch_1):page237_i86@mstr_vreg.rt9059(chips)!RT9059_DFN-IC,H65765-001!!!F245!VOUT(1)!!!!
S!P1V8_PCH_STBY!EU8A2!3!@baseboard_fab2_lib.baseboard_fab2(sch_1):page237_i86@mstr_vreg.rt9059(chips)!RT9059_DFN-IC,H65765-001!!!F245!VOUT(2)!!!!
S!VR_P1V538_BMC_STBY_FB!EU9F2!4!@baseboard_fab2_lib.baseboard_fab2(sch_1):page239_i70@mstr_vreg.rt9059(chips)!RT9059_DFN-IC,H65765-001!!!F243!ADJ_NC!!!!
S!PWRGD_P3V3_STBY!EU9F2!6!@baseboard_fab2_lib.baseboard_fab2(sch_1):page239_i70@mstr_vreg.rt9059(chips)!RT9059_DFN-IC,H65765-001!!!F243!EN!!!!
S!GND!EU9F2!11!@baseboard_fab2_lib.baseboard_fab2(sch_1):page239_i70@mstr_vreg.rt9059(chips)!RT9059_DFN-IC,H65765-001!!!F243!GND!!!!
S!PWRGD_P1V538_BMC_STBY_R!EU9F2!5!@baseboard_fab2_lib.baseboard_fab2(sch_1):page239_i70@mstr_vreg.rt9059(chips)!RT9059_DFN-IC,H65765-001!!!F243!PGOOD!!!!
S!P3V3_STBY!EU9F2!10!@baseboard_fab2_lib.baseboard_fab2(sch_1):page239_i70@mstr_vreg.rt9059(chips)!RT9059_DFN-IC,H65765-001!!!F243!VDD!!!!
S!P3V3_STBY!EU9F2!7!@baseboard_fab2_lib.baseboard_fab2(sch_1):page239_i70@mstr_vreg.rt9059(chips)!RT9059_DFN-IC,H65765-001!!!F243!VIN(0)!!!!
S!P3V3_STBY!EU9F2!8!@baseboard_fab2_lib.baseboard_fab2(sch_1):page239_i70@mstr_vreg.rt9059(chips)!RT9059_DFN-IC,H65765-001!!!F243!VIN(1)!!!!
S!P3V3_STBY!EU9F2!9!@baseboard_fab2_lib.baseboard_fab2(sch_1):page239_i70@mstr_vreg.rt9059(chips)!RT9059_DFN-IC,H65765-001!!!F243!VIN(2)!!!!
S!P1V538_BMC_STBY!EU9F2!1!@baseboard_fab2_lib.baseboard_fab2(sch_1):page239_i70@mstr_vreg.rt9059(chips)!RT9059_DFN-IC,H65765-001!!!F243!VOUT(0)!!!!
S!P1V538_BMC_STBY!EU9F2!2!@baseboard_fab2_lib.baseboard_fab2(sch_1):page239_i70@mstr_vreg.rt9059(chips)!RT9059_DFN-IC,H65765-001!!!F243!VOUT(1)!!!!
S!P1V538_BMC_STBY!EU9F2!3!@baseboard_fab2_lib.baseboard_fab2(sch_1):page239_i70@mstr_vreg.rt9059(chips)!RT9059_DFN-IC,H65765-001!!!F243!VOUT(2)!!!!
S!A_ADM1085_CEXT!U7D3!5!@baseboard_fab2_lib.baseboard_fab2(sch_1):page196_i70@mstr_analog.adm1085(chips)!ADM1085_SMT-IC,H46130-001!!!F4198!CEXT!!!!
S!PWRGD_P3V3_STBY!U7D3!1!@baseboard_fab2_lib.baseboard_fab2(sch_1):page196_i70@mstr_analog.adm1085(chips)!ADM1085_SMT-IC,H46130-001!!!F4198!ENIN!!!!
S!PWRGD_DSW_PWROK!U7D3!4!@baseboard_fab2_lib.baseboard_fab2(sch_1):page196_i70@mstr_analog.adm1085(chips)!ADM1085_SMT-IC,H46130-001!!!F4198!ENOUT!!!!
S!GND!U7D3!2!@baseboard_fab2_lib.baseboard_fab2(sch_1):page196_i70@mstr_analog.adm1085(chips)!ADM1085_SMT-IC,H46130-001!!!F4198!GND!!!!
S!P3V3_STBY!U7D3!6!@baseboard_fab2_lib.baseboard_fab2(sch_1):page196_i70@mstr_analog.adm1085(chips)!ADM1085_SMT-IC,H46130-001!!!F4198!VCC!!!!
S!VSENSE_P12V_ADM1085!U7D3!3!@baseboard_fab2_lib.baseboard_fab2(sch_1):page196_i70@mstr_analog.adm1085(chips)!ADM1085_SMT-IC,H46130-001!!!F4198!VIN!!!!
S!A_ADM1085_CEXT!C3P45!1!@baseboard_fab2_lib.baseboard_fab2(sch_1):page196_i60@mstr_discrete.cap(chips)!CAP_0402-0.047UF,25V,10%,X7R,AA!!!F4086!A!!!!
S!GND!C3P45!2!@baseboard_fab2_lib.baseboard_fab2(sch_1):page196_i60@mstr_discrete.cap(chips)!CAP_0402-0.047UF,25V,10%,X7R,AA!!!F4086!B!!!!
S!P3V3_STBY!C8D4!1!@baseboard_fab2_lib.baseboard_fab2(sch_1):page196_i105@mstr_discrete.cap(chips)!CAP_0402-0.1UF,16V,10%,X7R,A36A!!!F4077!A!!!!
S!GND!C8D4!2!@baseboard_fab2_lib.baseboard_fab2(sch_1):page196_i105@mstr_discrete.cap(chips)!CAP_0402-0.1UF,16V,10%,X7R,A36A!!!F4077!B!!!!
S!PVCCIO_CPU1!C9M8!1!@baseboard_fab2_lib.baseboard_fab2(sch_1):page163_i10@mstr_discrete.cap(chips)!CAP_0402-0.1UF,16V,10%,X7R,A36A!!!F4078!A!!!!
S!GND!C9M8!2!@baseboard_fab2_lib.baseboard_fab2(sch_1):page163_i10@mstr_discrete.cap(chips)!CAP_0402-0.1UF,16V,10%,X7R,A36A!!!F4078!B!!!!
S!P3V3_STBY!C9M7!1!@baseboard_fab2_lib.baseboard_fab2(sch_1):page163_i12@mstr_discrete.cap(chips)!CAP_0402-0.1UF,16V,10%,X7R,A36A!!!F4079!A!!!!
S!GND!C9M7!2!@baseboard_fab2_lib.baseboard_fab2(sch_1):page163_i12@mstr_discrete.cap(chips)!CAP_0402-0.1UF,16V,10%,X7R,A36A!!!F4079!B!!!!
S!PWRGD_P12V_HSC!C8E3!1!@baseboard_fab2_lib.baseboard_fab2(sch_1):page196_i94@mstr_discrete.cap(chips)!CAP_0402-0.1UF,16V,10%,X7R,A36A!!!F4080!A!!!!
S!GND!C8E3!2!@baseboard_fab2_lib.baseboard_fab2(sch_1):page196_i94@mstr_discrete.cap(chips)!CAP_0402-0.1UF,16V,10%,X7R,A36A!!!F4080!B!!!!
S!P3V3!C1L16!1!@baseboard_fab2_lib.baseboard_fab2(sch_1):page196_i81@mstr_discrete.cap(chips)!CAP_0402-0.1UF,16V,10%,X7R,A36A!!!F4082!A!!!!
S!GND!C1L16!2!@baseboard_fab2_lib.baseboard_fab2(sch_1):page196_i81@mstr_discrete.cap(chips)!CAP_0402-0.1UF,16V,10%,X7R,A36A!!!F4082!B!!!!
S!P3V3_STBY!C3P46!1!@baseboard_fab2_lib.baseboard_fab2(sch_1):page196_i72@mstr_discrete.cap(chips)!CAP_0402-0.1UF,16V,10%,X7R,A36A!!!F4081!A!!!!
S!GND!C3P46!2!@baseboard_fab2_lib.baseboard_fab2(sch_1):page196_i72@mstr_discrete.cap(chips)!CAP_0402-0.1UF,16V,10%,X7R,A36A!!!F4081!B!!!!
S!P3V3_STBY!R3P54!1!@baseboard_fab2_lib.baseboard_fab2(sch_1):page156_i331@mstr_discrete.res(chips)!RES_0402-3.32K,1%,1/16W,EMPTY,A!!!F768!A!!!!
S!FM_CPU0_SM_WP!R3P54!2!@baseboard_fab2_lib.baseboard_fab2(sch_1):page156_i331@mstr_discrete.res(chips)!RES_0402-3.32K,1%,1/16W,EMPTY,A!!!F768!B!!!!
S!P3V3_STBY!R1C35!1!@baseboard_fab2_lib.baseboard_fab2(sch_1):page156_i336@mstr_discrete.res(chips)!RES_0402-3.32K,1%,1/16W,EMPTY,A!!!F767!A!!!!
S!FM_CPU1_SM_WP!R1C35!2!@baseboard_fab2_lib.baseboard_fab2(sch_1):page156_i336@mstr_discrete.res(chips)!RES_0402-3.32K,1%,1/16W,EMPTY,A!!!F767!B!!!!
S!SPI_NIC_MOSI!R1R6!1!@baseboard_fab2_lib.baseboard_fab2(sch_1):page140_i14@mstr_discrete.res(chips)!RES_0402-3.32K,1%,1/16W,EMPTY,A!!!F769!A!!!!
S!GND!R1R6!2!@baseboard_fab2_lib.baseboard_fab2(sch_1):page140_i14@mstr_discrete.res(chips)!RES_0402-3.32K,1%,1/16W,EMPTY,A!!!F769!B!!!!
S!A_P3V3_STBY_SCALED!R1U38!1!@baseboard_fab2_lib.baseboard_fab2(sch_1):page169_i114@mstr_discrete.res(chips)!RES_0402-8.2K,1%,1/16W,CHIP,G2A!!!F293!A!!!!
S!GND!R1U38!2!@baseboard_fab2_lib.baseboard_fab2(sch_1):page169_i114@mstr_discrete.res(chips)!RES_0402-8.2K,1%,1/16W,CHIP,G2A!!!F293!B!!!!
S!A_P3V3_SCALED!R1U27!1!@baseboard_fab2_lib.baseboard_fab2(sch_1):page169_i149@mstr_discrete.res(chips)!RES_0402-8.2K,1%,1/16W,CHIP,G2A!!!F294!A!!!!
S!GND!R1U27!2!@baseboard_fab2_lib.baseboard_fab2(sch_1):page169_i149@mstr_discrete.res(chips)!RES_0402-8.2K,1%,1/16W,CHIP,G2A!!!F294!B!!!!
S!A_USB2VRES!R1T25!1!@baseboard_fab2_lib.baseboard_fab2(sch_1):page144_i461@mstr_discrete.res(chips)!RES_0402-8.2K,1%,1/16W,CHIP,G2A!!!F295!A!!!!
S!GND!R1T25!2!@baseboard_fab2_lib.baseboard_fab2(sch_1):page144_i461@mstr_discrete.res(chips)!RES_0402-8.2K,1%,1/16W,CHIP,G2A!!!F295!B!!!!
S!SATA6G_S0_TX_DP!C8F6!1!@baseboard_fab2_lib.baseboard_fab2(sch_1):page185_i95@mstr_discrete.cap(chips)!CAP_0402LF-0.01UF,25V,10%,EMPTA!!!F3607!A!!!!
S!P3E_PCH_M2_SATA6G_TX_R_DP!C8F6!2!@baseboard_fab2_lib.baseboard_fab2(sch_1):page185_i95@mstr_discrete.cap(chips)!CAP_0402LF-0.01UF,25V,10%,EMPTA!!!F3607!B!!!!
S!SATA6G_S0_TX_DN!C8F11!1!@baseboard_fab2_lib.baseboard_fab2(sch_1):page185_i97@mstr_discrete.cap(chips)!CAP_0402LF-0.01UF,25V,10%,EMPTA!!!F3606!A!!!!
S!P3E_PCH_M2_SATA6G_TX_R_DN!C8F11!2!@baseboard_fab2_lib.baseboard_fab2(sch_1):page185_i97@mstr_discrete.cap(chips)!CAP_0402LF-0.01UF,25V,10%,EMPTA!!!F3606!B!!!!
S!SATA6G_S0_RX_DP!C8F13!1!@baseboard_fab2_lib.baseboard_fab2(sch_1):page185_i99@mstr_discrete.cap(chips)!CAP_0402LF-0.01UF,25V,10%,EMPTA!!!F3605!A!!!!
S!P3E_PCH_M2_SATA6G_RX_R_DP!C8F13!2!@baseboard_fab2_lib.baseboard_fab2(sch_1):page185_i99@mstr_discrete.cap(chips)!CAP_0402LF-0.01UF,25V,10%,EMPTA!!!F3605!B!!!!
S!SATA6G_S0_RX_DN!C8F15!1!@baseboard_fab2_lib.baseboard_fab2(sch_1):page185_i90@mstr_discrete.cap(chips)!CAP_0402LF-0.01UF,25V,10%,EMPTA!!!F3604!A!!!!
S!P3E_PCH_M2_SATA6G_RX_R_DN!C8F15!2!@baseboard_fab2_lib.baseboard_fab2(sch_1):page185_i90@mstr_discrete.cap(chips)!CAP_0402LF-0.01UF,25V,10%,EMPTA!!!F3604!B!!!!
S!USB3_P01_RXN!L1L1!1!@baseboard_fab2_lib.baseboard_fab2(sch_1):page176_i51@mstr_discrete.choke_4pin(chips)!CHOKE_4PIN_SM_B-67 OHM,EMPTY,7A!!!F2260!\1\!!!!
S!USB3_P01_FB_RXN!L1L1!2!@baseboard_fab2_lib.baseboard_fab2(sch_1):page176_i51@mstr_discrete.choke_4pin(chips)!CHOKE_4PIN_SM_B-67 OHM,EMPTY,7A!!!F2260!\2\!!!!
S!USB3_P01_FB_RXP!L1L1!3!@baseboard_fab2_lib.baseboard_fab2(sch_1):page176_i51@mstr_discrete.choke_4pin(chips)!CHOKE_4PIN_SM_B-67 OHM,EMPTY,7A!!!F2260!\3\!!!!
S!USB3_P01_RXP!L1L1!4!@baseboard_fab2_lib.baseboard_fab2(sch_1):page176_i51@mstr_discrete.choke_4pin(chips)!CHOKE_4PIN_SM_B-67 OHM,EMPTY,7A!!!F2260!\4\!!!!
S!USB3_P01_C_TXN!L1M1!1!@baseboard_fab2_lib.baseboard_fab2(sch_1):page176_i62@mstr_discrete.choke_4pin(chips)!CHOKE_4PIN_SM_B-67 OHM,EMPTY,7A!!!F2259!\1\!!!!
S!USB3_P01_FB_TXN!L1M1!2!@baseboard_fab2_lib.baseboard_fab2(sch_1):page176_i62@mstr_discrete.choke_4pin(chips)!CHOKE_4PIN_SM_B-67 OHM,EMPTY,7A!!!F2259!\2\!!!!
S!USB3_P01_FB_TXP!L1M1!3!@baseboard_fab2_lib.baseboard_fab2(sch_1):page176_i62@mstr_discrete.choke_4pin(chips)!CHOKE_4PIN_SM_B-67 OHM,EMPTY,7A!!!F2259!\3\!!!!
S!USB3_P01_C_TXP!L1M1!4!@baseboard_fab2_lib.baseboard_fab2(sch_1):page176_i62@mstr_discrete.choke_4pin(chips)!CHOKE_4PIN_SM_B-67 OHM,EMPTY,7A!!!F2259!\4\!!!!
S!VR_PVPP_DEF_SNUB!R7A15!1!@baseboard_fab2_lib.baseboard_fab2(sch_1):page232_i218@mstr_discrete.res(chips)!RES_0402-2.2,5%,1/16W,EMPTY,G2A!!!F1032!A!!!!
S!GND!R7A15!2!@baseboard_fab2_lib.baseboard_fab2(sch_1):page232_i218@mstr_discrete.res(chips)!RES_0402-2.2,5%,1/16W,EMPTY,G2A!!!F1032!B!!!!
S!VR_PVPP_GHJ_SNUB!R4F6!1!@baseboard_fab2_lib.baseboard_fab2(sch_1):page233_i208@mstr_discrete.res(chips)!RES_0402-2.2,5%,1/16W,EMPTY,G2A!!!F1033!A!!!!
S!GND!R4F6!2!@baseboard_fab2_lib.baseboard_fab2(sch_1):page233_i208@mstr_discrete.res(chips)!RES_0402-2.2,5%,1/16W,EMPTY,G2A!!!F1033!B!!!!
S!VR_PVPP_KLM_SNUB!R4A7!1!@baseboard_fab2_lib.baseboard_fab2(sch_1):page234_i162@mstr_discrete.res(chips)!RES_0402-2.2,5%,1/16W,EMPTY,G2A!!!F1034!A!!!!
S!GND!R4A7!2!@baseboard_fab2_lib.baseboard_fab2(sch_1):page234_i162@mstr_discrete.res(chips)!RES_0402-2.2,5%,1/16W,EMPTY,G2A!!!F1034!B!!!!
S!VR_PVPP_ABC_SNUB!R7F7!1!@baseboard_fab2_lib.baseboard_fab2(sch_1):page231_i174@mstr_discrete.res(chips)!RES_0402-2.2,5%,1/16W,EMPTY,G2A!!!F1031!A!!!!
S!GND!R7F7!2!@baseboard_fab2_lib.baseboard_fab2(sch_1):page231_i174@mstr_discrete.res(chips)!RES_0402-2.2,5%,1/16W,EMPTY,G2A!!!F1031!B!!!!
S!VR_P3V3_STBY_SNUB!R8F3!1!@baseboard_fab2_lib.baseboard_fab2(sch_1):page240_i148@mstr_discrete.res(chips)!RES_0402-2.2,5%,1/16W,EMPTY,G2A!!!F1030!A!!!!
S!GND!R8F3!2!@baseboard_fab2_lib.baseboard_fab2(sch_1):page240_i148@mstr_discrete.res(chips)!RES_0402-2.2,5%,1/16W,EMPTY,G2A!!!F1030!B!!!!
S!FM_UARTSW_LSB_R_N!R1L43!1!@baseboard_fab2_lib.baseboard_fab2(sch_1):page158_i131@mstr_discrete.res(chips)!RES_0402-330,5%,1/16W,CHIP,G21A!!!F665!A!!!!
S!P3V3_STBY!R1L43!2!@baseboard_fab2_lib.baseboard_fab2(sch_1):page158_i131@mstr_discrete.res(chips)!RES_0402-330,5%,1/16W,CHIP,G21A!!!F665!B!!!!
S!FM_UARTSW_MSB_R_N!R1L44!1!@baseboard_fab2_lib.baseboard_fab2(sch_1):page158_i136@mstr_discrete.res(chips)!RES_0402-330,5%,1/16W,CHIP,G21A!!!F664!A!!!!
S!P3V3_STBY!R1L44!2!@baseboard_fab2_lib.baseboard_fab2(sch_1):page158_i136@mstr_discrete.res(chips)!RES_0402-330,5%,1/16W,CHIP,G21A!!!F664!B!!!!
S!P3V3_STBY!R2T4!1!@baseboard_fab2_lib.baseboard_fab2(sch_1):page240_i152@mstr_discrete.res(chips)!RES_0402-1.0K,0.1%,1/16W,CHIP,A!!!F1407!A!!!!
S!GND!R2T4!2!@baseboard_fab2_lib.baseboard_fab2(sch_1):page240_i152@mstr_discrete.res(chips)!RES_0402-1.0K,0.1%,1/16W,CHIP,A!!!F1407!B!!!!
S!P5V_STBY!R8E18!1!@baseboard_fab2_lib.baseboard_fab2(sch_1):page241_i9@mstr_discrete.res(chips)!RES_0402-1.0K,0.1%,1/16W,CHIP,A!!!F1402!A!!!!
S!GND!R8E18!2!@baseboard_fab2_lib.baseboard_fab2(sch_1):page241_i9@mstr_discrete.res(chips)!RES_0402-1.0K,0.1%,1/16W,CHIP,A!!!F1402!B!!!!
S!VSENSE_PVPP_ABC!R7F17!1!@baseboard_fab2_lib.baseboard_fab2(sch_1):page231_i218@mstr_discrete.res(chips)!RES_0402-1.0K,0.1%,1/16W,CHIP,A!!!F1403!A!!!!
S!VR_COMP_PVPP_ABC!R7F17!2!@baseboard_fab2_lib.baseboard_fab2(sch_1):page231_i218@mstr_discrete.res(chips)!RES_0402-1.0K,0.1%,1/16W,CHIP,A!!!F1403!B!!!!
S!VSENSE_PVPP_DEF!R7B18!1!@baseboard_fab2_lib.baseboard_fab2(sch_1):page232_i298@mstr_discrete.res(chips)!RES_0402-1.0K,0.1%,1/16W,CHIP,A!!!F1404!A!!!!
S!VR_COMP_PVPP_DEF!R7B18!2!@baseboard_fab2_lib.baseboard_fab2(sch_1):page232_i298@mstr_discrete.res(chips)!RES_0402-1.0K,0.1%,1/16W,CHIP,A!!!F1404!B!!!!
S!VSENSE_PVPP_GHJ!R4G10!1!@baseboard_fab2_lib.baseboard_fab2(sch_1):page233_i266@mstr_discrete.res(chips)!RES_0402-1.0K,0.1%,1/16W,CHIP,A!!!F1405!A!!!!
S!VR_COMP_PVPP_GHJ!R4G10!2!@baseboard_fab2_lib.baseboard_fab2(sch_1):page233_i266@mstr_discrete.res(chips)!RES_0402-1.0K,0.1%,1/16W,CHIP,A!!!F1405!B!!!!
S!VSENSE_PVPP_KLM!R4B9!1!@baseboard_fab2_lib.baseboard_fab2(sch_1):page234_i219@mstr_discrete.res(chips)!RES_0402-1.0K,0.1%,1/16W,CHIP,A!!!F1406!A!!!!
S!VR_COMP_PVPP_KLM!R4B9!2!@baseboard_fab2_lib.baseboard_fab2(sch_1):page234_i219@mstr_discrete.res(chips)!RES_0402-1.0K,0.1%,1/16W,CHIP,A!!!F1406!B!!!!
S!P1V05_PCH_STBY_KR_PLL!R2N4!1!@baseboard_fab2_lib.baseboard_fab2(sch_1):page118_i96@mstr_discrete.res(chips)!RES_0402-1.0K,0.1%,1/16W,CHIP,A!!!F1408!A!!!!
S!A_KR0_RBIAS!R2N4!2!@baseboard_fab2_lib.baseboard_fab2(sch_1):page118_i96@mstr_discrete.res(chips)!RES_0402-1.0K,0.1%,1/16W,CHIP,A!!!F1408!B!!!!
S!A_KR1_RBIAS!R2M6!1!@baseboard_fab2_lib.baseboard_fab2(sch_1):page118_i99@mstr_discrete.res(chips)!RES_0402-1.0K,0.1%,1/16W,CHIP,A!!!F1409!A!!!!
S!P1V05_PCH_STBY_KR_PLL!R2M6!2!@baseboard_fab2_lib.baseboard_fab2(sch_1):page118_i99@mstr_discrete.res(chips)!RES_0402-1.0K,0.1%,1/16W,CHIP,A!!!F1409!B!!!!
S!VR_P5V_STBY_VSENSE!R7E16!1!@baseboard_fab2_lib.baseboard_fab2(sch_1):page241_i51@mstr_discrete.res(chips)!RES_0402-1.37K,1%,1/16W,CHIP,GA!!!F1395!A!!!!
S!AGND_P5V_STBY!R7E16!2!@baseboard_fab2_lib.baseboard_fab2(sch_1):page241_i51@mstr_discrete.res(chips)!RES_0402-1.37K,1%,1/16W,CHIP,GA!!!F1395!B!!!!
S!P3V3_STBY!R1C34!1!@baseboard_fab2_lib.baseboard_fab2(sch_1):page156_i320@mstr_discrete.res(chips)!RES_0402-10.0K,1%,1/16W,CHIP,GA!!!F1233!A!!!!
S!PU_PIROM_CPU1_ADDR0!R1C34!2!@baseboard_fab2_lib.baseboard_fab2(sch_1):page156_i320@mstr_discrete.res(chips)!RES_0402-10.0K,1%,1/16W,CHIP,GA!!!F1233!B!!!!
S!P3V3_STBY!R9F61!1!@baseboard_fab2_lib.baseboard_fab2(sch_1):page145_i252@mstr_discrete.res(chips)!RES_0402-10.0K,1%,1/16W,CHIP,GA!!!F1234!A!!!!
S!PU_24M_OSC_OE!R9F61!2!@baseboard_fab2_lib.baseboard_fab2(sch_1):page145_i252@mstr_discrete.res(chips)!RES_0402-10.0K,1%,1/16W,CHIP,GA!!!F1234!B!!!!
S!FM_USB_P0_EN_BOOT_BIOS_STRAP_N!R1M25!1!@baseboard_fab2_lib.baseboard_fab2(sch_1):page176_i111@mstr_discrete.res(chips)!RES_0402-10.0K,1%,1/16W,CHIP,GA!!!F1235!A!!!!
S!GND!R1M25!2!@baseboard_fab2_lib.baseboard_fab2(sch_1):page176_i111@mstr_discrete.res(chips)!RES_0402-10.0K,1%,1/16W,CHIP,GA!!!F1235!B!!!!
S!P3V3_STBY!R2P18!1!@baseboard_fab2_lib.baseboard_fab2(sch_1):page196_i121@mstr_discrete.res(chips)!RES_0402-10.0K,1%,1/16W,CHIP,GA!!!F1237!A!!!!
S!PWRGD_P5V_N!R2P18!2!@baseboard_fab2_lib.baseboard_fab2(sch_1):page196_i121@mstr_discrete.res(chips)!RES_0402-10.0K,1%,1/16W,CHIP,GA!!!F1237!B!!!!
S!P3V3_STBY!R8D41!1!@baseboard_fab2_lib.baseboard_fab2(sch_1):page196_i120@mstr_discrete.res(chips)!RES_0402-10.0K,1%,1/16W,CHIP,GA!!!F1238!A!!!!
S!PWRGD_P12V_MAIN_R!R8D41!2!@baseboard_fab2_lib.baseboard_fab2(sch_1):page196_i120@mstr_discrete.res(chips)!RES_0402-10.0K,1%,1/16W,CHIP,GA!!!F1238!B!!!!
S!P3V3_STBY!R2P21!1!@baseboard_fab2_lib.baseboard_fab2(sch_1):page196_i122@mstr_discrete.res(chips)!RES_0402-10.0K,1%,1/16W,CHIP,GA!!!F1236!A!!!!
S!PWRGD_P5V_R!R2P21!2!@baseboard_fab2_lib.baseboard_fab2(sch_1):page196_i122@mstr_discrete.res(chips)!RES_0402-10.0K,1%,1/16W,CHIP,GA!!!F1236!B!!!!
S!A_USB2_VBUS!R8B32!1!@baseboard_fab2_lib.baseboard_fab2(sch_1):page115_i114@mstr_discrete.res(chips)!RES_0402-10.0K,1%,1/16W,CHIP,GA!!!F1239!A!!!!
S!GND!R8B32!2!@baseboard_fab2_lib.baseboard_fab2(sch_1):page115_i114@mstr_discrete.res(chips)!RES_0402-10.0K,1%,1/16W,CHIP,GA!!!F1239!B!!!!
S!P3V3!R8F36!1!@baseboard_fab2_lib.baseboard_fab2(sch_1):page185_i136@mstr_discrete.res(chips)!RES_0402-10.0K,1%,1/16W,CHIP,GA!!!F1332!A!!!!
S!PU_M2_CLK_REQ_N!R8F36!2!@baseboard_fab2_lib.baseboard_fab2(sch_1):page185_i136@mstr_discrete.res(chips)!RES_0402-10.0K,1%,1/16W,CHIP,GA!!!F1332!B!!!!
S!CLK_50M_CKMNG_SPRVLLE!R1R12!1!@baseboard_fab2_lib.baseboard_fab2(sch_1):page139_i213@mstr_discrete.res(chips)!RES_0402-10.0K,1%,1/16W,CHIP,GA!!!F1322!A!!!!
S!GND!R1R12!2!@baseboard_fab2_lib.baseboard_fab2(sch_1):page139_i213@mstr_discrete.res(chips)!RES_0402-10.0K,1%,1/16W,CHIP,GA!!!F1322!B!!!!
S!A_EXTCLKP!R7B7!1!@baseboard_fab2_lib.baseboard_fab2(sch_1):page116_i230@mstr_discrete.res(chips)!RES_0402-10.0K,1%,1/16W,CHIP,GA!!!F1293!A!!!!
S!GND!R7B7!2!@baseboard_fab2_lib.baseboard_fab2(sch_1):page116_i230@mstr_discrete.res(chips)!RES_0402-10.0K,1%,1/16W,CHIP,GA!!!F1293!B!!!!
S!A_EXTCLKN!R7B8!1!@baseboard_fab2_lib.baseboard_fab2(sch_1):page116_i229@mstr_discrete.res(chips)!RES_0402-10.0K,1%,1/16W,CHIP,GA!!!F1292!A!!!!
S!GND!R7B8!2!@baseboard_fab2_lib.baseboard_fab2(sch_1):page116_i229@mstr_discrete.res(chips)!RES_0402-10.0K,1%,1/16W,CHIP,GA!!!F1292!B!!!!
S!CLK_50M_CKMNG_PCH_10GBE!R7C20!1!@baseboard_fab2_lib.baseboard_fab2(sch_1):page121_i73@mstr_discrete.res(chips)!RES_0402-10.0K,1%,1/16W,CHIP,GA!!!F1288!A!!!!
S!GND!R7C20!2!@baseboard_fab2_lib.baseboard_fab2(sch_1):page121_i73@mstr_discrete.res(chips)!RES_0402-10.0K,1%,1/16W,CHIP,GA!!!F1288!B!!!!
S!P3V3_STBY!R7C23!1!@baseboard_fab2_lib.baseboard_fab2(sch_1):page118_i144@mstr_discrete.res(chips)!RES_0402-10.0K,1%,1/16W,CHIP,GA!!!F1286!A!!!!
S!XDP_PCH_PWR_DEBUG_N!R7C23!2!@baseboard_fab2_lib.baseboard_fab2(sch_1):page118_i144@mstr_discrete.res(chips)!RES_0402-10.0K,1%,1/16W,CHIP,GA!!!F1286!B!!!!
S!P3V3_STBY!R7G22!1!@baseboard_fab2_lib.baseboard_fab2(sch_1):page189_i53@mstr_discrete.res(chips)!RES_0402-10.0K,1%,1/16W,CHIP,GA!!!F1273!A!!!!
S!JTAG_TDO_R!R7G22!2!@baseboard_fab2_lib.baseboard_fab2(sch_1):page189_i53@mstr_discrete.res(chips)!RES_0402-10.0K,1%,1/16W,CHIP,GA!!!F1273!B!!!!
S!P3V3_STBY!R7G23!1!@baseboard_fab2_lib.baseboard_fab2(sch_1):page189_i51@mstr_discrete.res(chips)!RES_0402-10.0K,1%,1/16W,CHIP,GA!!!F1272!A!!!!
S!JTAG_TDI_R!R7G23!2!@baseboard_fab2_lib.baseboard_fab2(sch_1):page189_i51@mstr_discrete.res(chips)!RES_0402-10.0K,1%,1/16W,CHIP,GA!!!F1272!B!!!!
S!P3V3_STBY!R8G20!1!@baseboard_fab2_lib.baseboard_fab2(sch_1):page189_i50@mstr_discrete.res(chips)!RES_0402-10.0K,1%,1/16W,CHIP,GA!!!F1258!A!!!!
S!JTAG_TMS_R!R8G20!2!@baseboard_fab2_lib.baseboard_fab2(sch_1):page189_i50@mstr_discrete.res(chips)!RES_0402-10.0K,1%,1/16W,CHIP,GA!!!F1258!B!!!!
S!P3V3_STBY!R2N9!1!@baseboard_fab2_lib.baseboard_fab2(sch_1):page133_i267@mstr_discrete.res(chips)!RES_0402-10.0K,1%,1/16W,CHIP,GA!!!F1316!A!!!!
S!PU_10GBE_LOM_PCI_DISABLE_N!R2N9!2!@baseboard_fab2_lib.baseboard_fab2(sch_1):page133_i267@mstr_discrete.res(chips)!RES_0402-10.0K,1%,1/16W,CHIP,GA!!!F1316!B!!!!
S!IRQ_DIMM_SAVE_N!R8D30!1!@baseboard_fab2_lib.baseboard_fab2(sch_1):page89_i34@mstr_discrete.res(chips)!RES_0402-10.0K,1%,1/16W,CHIP,GA!!!F1266!A!!!!
S!IRQ_DIMM_SAVE_R_N!R8D30!2!@baseboard_fab2_lib.baseboard_fab2(sch_1):page89_i34@mstr_discrete.res(chips)!RES_0402-10.0K,1%,1/16W,CHIP,GA!!!F1266!B!!!!
S!PVPP_ABC!R6F3!1!@baseboard_fab2_lib.baseboard_fab2(sch_1):page89_i7@mstr_discrete.res(chips)!RES_0402-10.0K,1%,1/16W,CHIP,GA!!!F1296!A!!!!
S!IRQ_DIMM_SAVE_N!R6F3!2!@baseboard_fab2_lib.baseboard_fab2(sch_1):page89_i7@mstr_discrete.res(chips)!RES_0402-10.0K,1%,1/16W,CHIP,GA!!!F1296!B!!!!
S!GND!R1U7!1!@baseboard_fab2_lib.baseboard_fab2(sch_1):page145_i127@mstr_discrete.res(chips)!RES_0402-10.0K,1%,1/16W,CHIP,GA!!!F1318!A!!!!
S!PD_SP_ENTEST!R1U7!2!@baseboard_fab2_lib.baseboard_fab2(sch_1):page145_i127@mstr_discrete.res(chips)!RES_0402-10.0K,1%,1/16W,CHIP,GA!!!F1318!B!!!!
S!P3V3_STBY!R9P5!1!@baseboard_fab2_lib.baseboard_fab2(sch_1):page200_i215@mstr_discrete.res(chips)!RES_0402-10.0K,1%,1/16W,CHIP,GA!!!F1244!A!!!!
S!FM_DISABLE_FAN_N!R9P5!2!@baseboard_fab2_lib.baseboard_fab2(sch_1):page200_i215@mstr_discrete.res(chips)!RES_0402-10.0K,1%,1/16W,CHIP,GA!!!F1244!B!!!!
S!P3V3_STBY!R2P19!1!@baseboard_fab2_lib.baseboard_fab2(sch_1):page134_i34@mstr_discrete.res(chips)!RES_0402-10.0K,1%,1/16W,CHIP,GA!!!F1281!A!!!!
S!FM_DIS_ADR_DLY!R2P19!2!@baseboard_fab2_lib.baseboard_fab2(sch_1):page134_i34@mstr_discrete.res(chips)!RES_0402-10.0K,1%,1/16W,CHIP,GA!!!F1281!B!!!!
S!P3V3!R1M11!1!@baseboard_fab2_lib.baseboard_fab2(sch_1):page177_i9@mstr_discrete.res(chips)!RES_0402-10.0K,1%,1/16W,CHIP,GA!!!F1326!A!!!!
S!LED_SATA_ACT_R_N!R1M11!2!@baseboard_fab2_lib.baseboard_fab2(sch_1):page177_i9@mstr_discrete.res(chips)!RES_0402-10.0K,1%,1/16W,CHIP,GA!!!F1326!B!!!!
S!P3V3!R1M12!1!@baseboard_fab2_lib.baseboard_fab2(sch_1):page177_i8@mstr_discrete.res(chips)!RES_0402-10.0K,1%,1/16W,CHIP,GA!!!F1325!A!!!!
S!LED_SAS_ACT_R_N!R1M12!2!@baseboard_fab2_lib.baseboard_fab2(sch_1):page177_i8@mstr_discrete.res(chips)!RES_0402-10.0K,1%,1/16W,CHIP,GA!!!F1325!B!!!!
S!GND!R4P5!1!@baseboard_fab2_lib.baseboard_fab2(sch_1):page97_i80@mstr_discrete.res(chips)!RES_0402-10.0K,1%,1/16W,CHIP,GA!!!F1300!A!!!!
S!PD_CPU0_MCP01_DMON!R4P5!2!@baseboard_fab2_lib.baseboard_fab2(sch_1):page97_i80@mstr_discrete.res(chips)!RES_0402-10.0K,1%,1/16W,CHIP,GA!!!F1300!B!!!!
S!GND!R7P13!1!@baseboard_fab2_lib.baseboard_fab2(sch_1):page97_i81@mstr_discrete.res(chips)!RES_0402-10.0K,1%,1/16W,CHIP,GA!!!F1271!A!!!!
S!PD_CPU1_MCP01_DMON!R7P13!2!@baseboard_fab2_lib.baseboard_fab2(sch_1):page97_i81@mstr_discrete.res(chips)!RES_0402-10.0K,1%,1/16W,CHIP,GA!!!F1271!B!!!!
S!FM_BIOS_SPI_BMC_CTRL!R1U6!1!@baseboard_fab2_lib.baseboard_fab2(sch_1):page154_i128@mstr_discrete.res(chips)!RES_0402-10.0K,1%,1/16W,CHIP,GA!!!F1319!A!!!!
S!GND!R1U6!2!@baseboard_fab2_lib.baseboard_fab2(sch_1):page154_i128@mstr_discrete.res(chips)!RES_0402-10.0K,1%,1/16W,CHIP,GA!!!F1319!B!!!!
S!FM_BIOS_PREFRB2_GOOD!R2N13!1!@baseboard_fab2_lib.baseboard_fab2(sch_1):page147_i142@mstr_discrete.res(chips)!RES_0402-10.0K,1%,1/16W,CHIP,GA!!!F1315!A!!!!
S!GND!R2N13!2!@baseboard_fab2_lib.baseboard_fab2(sch_1):page147_i142@mstr_discrete.res(chips)!RES_0402-10.0K,1%,1/16W,CHIP,GA!!!F1315!B!!!!
S!P3V3_STBY!R3T12!1!@baseboard_fab2_lib.baseboard_fab2(sch_1):page153_i178@mstr_discrete.res(chips)!RES_0402-10.0K,1%,1/16W,CHIP,GA!!!F1305!A!!!!
S!PU_BIOS_SPI_WP1_N!R3T12!2!@baseboard_fab2_lib.baseboard_fab2(sch_1):page153_i178@mstr_discrete.res(chips)!RES_0402-10.0K,1%,1/16W,CHIP,GA!!!F1305!B!!!!
S!P3V3_STBY!R3T4!1!@baseboard_fab2_lib.baseboard_fab2(sch_1):page153_i174@mstr_discrete.res(chips)!RES_0402-10.0K,1%,1/16W,CHIP,GA!!!F1306!A!!!!
S!PU_BIOS_SPI_HOLD1_N!R3T4!2!@baseboard_fab2_lib.baseboard_fab2(sch_1):page153_i174@mstr_discrete.res(chips)!RES_0402-10.0K,1%,1/16W,CHIP,GA!!!F1306!B!!!!
S!P3V3_STBY!R1D23!1!@baseboard_fab2_lib.baseboard_fab2(sch_1):page200_i191@mstr_discrete.res(chips)!RES_0402-10.0K,1%,1/16W,CHIP,GA!!!F1327!A!!!!
S!IRQ_OC_DETECT_N!R1D23!2!@baseboard_fab2_lib.baseboard_fab2(sch_1):page200_i191@mstr_discrete.res(chips)!RES_0402-10.0K,1%,1/16W,CHIP,GA!!!F1327!B!!!!
S!P3V3_STBY!R1D10!1!@baseboard_fab2_lib.baseboard_fab2(sch_1):page200_i189@mstr_discrete.res(chips)!RES_0402-10.0K,1%,1/16W,CHIP,GA!!!F1331!A!!!!
S!A_HSC_LOW_GATE!R1D10!2!@baseboard_fab2_lib.baseboard_fab2(sch_1):page200_i189@mstr_discrete.res(chips)!RES_0402-10.0K,1%,1/16W,CHIP,GA!!!F1331!B!!!!
S!P3V3_STBY!R9P10!1!@baseboard_fab2_lib.baseboard_fab2(sch_1):page200_i192@mstr_discrete.res(chips)!RES_0402-10.0K,1%,1/16W,CHIP,GA!!!F1241!A!!!!
S!A_P12V_STBY_FPH_GATE!R9P10!2!@baseboard_fab2_lib.baseboard_fab2(sch_1):page200_i192@mstr_discrete.res(chips)!RES_0402-10.0K,1%,1/16W,CHIP,GA!!!F1241!B!!!!
S!A_P12V_STBY_FP_TRIGGER!R9P11!1!@baseboard_fab2_lib.baseboard_fab2(sch_1):page200_i108@mstr_discrete.res(chips)!RES_0402-10.0K,1%,1/16W,CHIP,GA!!!F1240!A!!!!
S!AGND_HSC!R9P11!2!@baseboard_fab2_lib.baseboard_fab2(sch_1):page200_i108@mstr_discrete.res(chips)!RES_0402-10.0K,1%,1/16W,CHIP,GA!!!F1240!B!!!!
S!A_HSC_LOW!R1D12!1!@baseboard_fab2_lib.baseboard_fab2(sch_1):page200_i174@mstr_discrete.res(chips)!RES_0402-10.0K,1%,1/16W,CHIP,GA!!!F1330!A!!!!
S!AGND_HSC!R1D12!2!@baseboard_fab2_lib.baseboard_fab2(sch_1):page200_i174@mstr_discrete.res(chips)!RES_0402-10.0K,1%,1/16W,CHIP,GA!!!F1330!B!!!!
S!A_HSC_HIGH!R1D19!1!@baseboard_fab2_lib.baseboard_fab2(sch_1):page200_i175@mstr_discrete.res(chips)!RES_0402-10.0K,1%,1/16W,CHIP,GA!!!F1329!A!!!!
S!AGND_HSC!R1D19!2!@baseboard_fab2_lib.baseboard_fab2(sch_1):page200_i175@mstr_discrete.res(chips)!RES_0402-10.0K,1%,1/16W,CHIP,GA!!!F1329!B!!!!
S!A_P12V_STBY_ADR_TRIGGER!R9P9!1!@baseboard_fab2_lib.baseboard_fab2(sch_1):page200_i146@mstr_discrete.res(chips)!RES_0402-10.0K,1%,1/16W,CHIP,GA!!!F1242!A!!!!
S!AGND_HSC!R9P9!2!@baseboard_fab2_lib.baseboard_fab2(sch_1):page200_i146@mstr_discrete.res(chips)!RES_0402-10.0K,1%,1/16W,CHIP,GA!!!F1242!B!!!!
S!P3V3_STBY!R1D22!1!@baseboard_fab2_lib.baseboard_fab2(sch_1):page200_i158@mstr_discrete.res(chips)!RES_0402-10.0K,1%,1/16W,CHIP,GA!!!F1328!A!!!!
S!FM_OC_DETECT_N!R1D22!2!@baseboard_fab2_lib.baseboard_fab2(sch_1):page200_i158@mstr_discrete.res(chips)!RES_0402-10.0K,1%,1/16W,CHIP,GA!!!F1328!B!!!!
S!FM_BIOS_USB_RECOVERY!R3T14!1!@baseboard_fab2_lib.baseboard_fab2(sch_1):page136_i156@mstr_discrete.res(chips)!RES_0402-10.0K,1%,1/16W,CHIP,GA!!!F1280!A!!!!
S!GND!R3T14!2!@baseboard_fab2_lib.baseboard_fab2(sch_1):page136_i156@mstr_discrete.res(chips)!RES_0402-10.0K,1%,1/16W,CHIP,GA!!!F1280!B!!!!
S!FM_PVPP_CPU1_EN!R4G5!1!@baseboard_fab2_lib.baseboard_fab2(sch_1):page233_i182@mstr_discrete.res(chips)!RES_0402-10.0K,1%,1/16W,CHIP,GA!!!F1303!A!!!!
S!GND!R4G5!2!@baseboard_fab2_lib.baseboard_fab2(sch_1):page233_i182@mstr_discrete.res(chips)!RES_0402-10.0K,1%,1/16W,CHIP,GA!!!F1303!B!!!!
S!P3V3_STBY!R1M24!1!@baseboard_fab2_lib.baseboard_fab2(sch_1):page176_i105@mstr_discrete.res(chips)!RES_0402-10.0K,1%,1/16W,CHIP,GA!!!F1254!A!!!!
S!FM_OC0_USB_N!R1M24!2!@baseboard_fab2_lib.baseboard_fab2(sch_1):page176_i105@mstr_discrete.res(chips)!RES_0402-10.0K,1%,1/16W,CHIP,GA!!!F1254!B!!!!
S!FM_PVPP_CPU0_EN!R7F14!1!@baseboard_fab2_lib.baseboard_fab2(sch_1):page231_i136@mstr_discrete.res(chips)!RES_0402-10.0K,1%,1/16W,CHIP,GA!!!F1276!A!!!!
S!GND!R7F14!2!@baseboard_fab2_lib.baseboard_fab2(sch_1):page231_i136@mstr_discrete.res(chips)!RES_0402-10.0K,1%,1/16W,CHIP,GA!!!F1276!B!!!!
S!VSENSE_VOUT_P3V3_STBY!R8E34!1!@baseboard_fab2_lib.baseboard_fab2(sch_1):page240_i142@mstr_discrete.res(chips)!RES_0402-10.0K,1%,1/16W,CHIP,GA!!!F1262!A!!!!
S!AGND_P3V3_STBY!R8E34!2!@baseboard_fab2_lib.baseboard_fab2(sch_1):page240_i142@mstr_discrete.res(chips)!RES_0402-10.0K,1%,1/16W,CHIP,GA!!!F1262!B!!!!
S!P3V3_STBY!R2R3!1!@baseboard_fab2_lib.baseboard_fab2(sch_1):page192_i41@mstr_discrete.res(chips)!RES_0402-10.0K,1%,1/16W,CHIP,GA!!!F1311!A!!!!
S!FM_PLD_DEBUG_MODE_N!R2R3!2!@baseboard_fab2_lib.baseboard_fab2(sch_1):page192_i41@mstr_discrete.res(chips)!RES_0402-10.0K,1%,1/16W,CHIP,GA!!!F1311!B!!!!
S!P3V3_STBY!R7E5!1!@baseboard_fab2_lib.baseboard_fab2(sch_1):page192_i38@mstr_discrete.res(chips)!RES_0402-10.0K,1%,1/16W,CHIP,GA!!!F1279!A!!!!
S!PU_THERMTRIP_FORCE_N!R7E5!2!@baseboard_fab2_lib.baseboard_fab2(sch_1):page192_i38@mstr_discrete.res(chips)!RES_0402-10.0K,1%,1/16W,CHIP,GA!!!F1279!B!!!!
S!P3V3_STBY!R2N6!1!@baseboard_fab2_lib.baseboard_fab2(sch_1):page118_i128@mstr_discrete.res(chips)!RES_0402-10.0K,1%,1/16W,CHIP,GA!!!F1317!A!!!!
S!FM_GBE_LOM_DISABLE_N!R2N6!2!@baseboard_fab2_lib.baseboard_fab2(sch_1):page118_i128@mstr_discrete.res(chips)!RES_0402-10.0K,1%,1/16W,CHIP,GA!!!F1317!B!!!!
S!P3V3_STBY!R7E6!1!@baseboard_fab2_lib.baseboard_fab2(sch_1):page192_i33@mstr_discrete.res(chips)!RES_0402-10.0K,1%,1/16W,CHIP,GA!!!F1278!A!!!!
S!PU_RST_PERST_BIT1!R7E6!2!@baseboard_fab2_lib.baseboard_fab2(sch_1):page192_i33@mstr_discrete.res(chips)!RES_0402-10.0K,1%,1/16W,CHIP,GA!!!F1278!B!!!!
S!P3V3_STBY!R2R1!1!@baseboard_fab2_lib.baseboard_fab2(sch_1):page192_i34@mstr_discrete.res(chips)!RES_0402-10.0K,1%,1/16W,CHIP,GA!!!F1312!A!!!!
S!PU_RST_PERST_BIT0!R2R1!2!@baseboard_fab2_lib.baseboard_fab2(sch_1):page192_i34@mstr_discrete.res(chips)!RES_0402-10.0K,1%,1/16W,CHIP,GA!!!F1312!B!!!!
S!P3V3_STBY!R9P6!1!@baseboard_fab2_lib.baseboard_fab2(sch_1):page200_i149@mstr_discrete.res(chips)!RES_0402-10.0K,1%,1/16W,CHIP,GA!!!F1243!A!!!!
S!FM_UV_ADR_TRIGGER_N!R9P6!2!@baseboard_fab2_lib.baseboard_fab2(sch_1):page200_i149@mstr_discrete.res(chips)!RES_0402-10.0K,1%,1/16W,CHIP,GA!!!F1243!B!!!!
S!P3V3_STBY!R7C5!1!@baseboard_fab2_lib.baseboard_fab2(sch_1):page133_i297@mstr_discrete.res(chips)!RES_0402-10.0K,1%,1/16W,CHIP,GA!!!F1291!A!!!!
S!FM_SINT_PRSNT_N!R7C5!2!@baseboard_fab2_lib.baseboard_fab2(sch_1):page133_i297@mstr_discrete.res(chips)!RES_0402-10.0K,1%,1/16W,CHIP,GA!!!F1291!B!!!!
S!P3V3_STBY!R7C8!1!@baseboard_fab2_lib.baseboard_fab2(sch_1):page133_i296@mstr_discrete.res(chips)!RES_0402-10.0K,1%,1/16W,CHIP,GA!!!F1290!A!!!!
S!FM_WBG_PRSNT_N!R7C8!2!@baseboard_fab2_lib.baseboard_fab2(sch_1):page133_i296@mstr_discrete.res(chips)!RES_0402-10.0K,1%,1/16W,CHIP,GA!!!F1290!B!!!!
S!P3V3_STBY!R7B6!1!@baseboard_fab2_lib.baseboard_fab2(sch_1):page133_i295@mstr_discrete.res(chips)!RES_0402-10.0K,1%,1/16W,CHIP,GA!!!F1294!A!!!!
S!FM_PCH_PRSNT_N!R7B6!2!@baseboard_fab2_lib.baseboard_fab2(sch_1):page133_i295@mstr_discrete.res(chips)!RES_0402-10.0K,1%,1/16W,CHIP,GA!!!F1294!B!!!!
S!P3V3_STBY!R7D12!1!@baseboard_fab2_lib.baseboard_fab2(sch_1):page133_i237@mstr_discrete.res(chips)!RES_0402-10.0K,1%,1/16W,CHIP,GA!!!F1282!A!!!!
S!FM_OCP_MEZZA_PRES_N!R7D12!2!@baseboard_fab2_lib.baseboard_fab2(sch_1):page133_i237@mstr_discrete.res(chips)!RES_0402-10.0K,1%,1/16W,CHIP,GA!!!F1282!B!!!!
S!P3V3_STBY!R7C13!1!@baseboard_fab2_lib.baseboard_fab2(sch_1):page137_i67@mstr_discrete.res(chips)!RES_0402-10.0K,1%,1/16W,CHIP,GA!!!F1289!A!!!!
S!FM_UART_PRES_N!R7C13!2!@baseboard_fab2_lib.baseboard_fab2(sch_1):page137_i67@mstr_discrete.res(chips)!RES_0402-10.0K,1%,1/16W,CHIP,GA!!!F1289!B!!!!
S!P3V3_STBY!R2N28!1!@baseboard_fab2_lib.baseboard_fab2(sch_1):page136_i147@mstr_discrete.res(chips)!RES_0402-10.0K,1%,1/16W,CHIP,GA!!!F1270!A!!!!
S!FM_PASSWORD_CLEAR_N!R2N28!2!@baseboard_fab2_lib.baseboard_fab2(sch_1):page136_i147@mstr_discrete.res(chips)!RES_0402-10.0K,1%,1/16W,CHIP,GA!!!F1270!B!!!!
S!P3V3_STBY!R8E3!1!@baseboard_fab2_lib.baseboard_fab2(sch_1):page133_i355@mstr_discrete.res(chips)!RES_0402-10.0K,1%,1/16W,CHIP,GA!!!F1265!A!!!!
S!FM_TPM_PRES_N!R8E3!2!@baseboard_fab2_lib.baseboard_fab2(sch_1):page133_i355@mstr_discrete.res(chips)!RES_0402-10.0K,1%,1/16W,CHIP,GA!!!F1265!B!!!!
S!P3V3_STBY!R2N23!1!@baseboard_fab2_lib.baseboard_fab2(sch_1):page134_i17@mstr_discrete.res(chips)!RES_0402-10.0K,1%,1/16W,CHIP,GA!!!F1313!A!!!!
S!FM_QAT_EN_N!R2N23!2!@baseboard_fab2_lib.baseboard_fab2(sch_1):page134_i17@mstr_discrete.res(chips)!RES_0402-10.0K,1%,1/16W,CHIP,GA!!!F1313!B!!!!
S!P3V3_STBY!R7G26!1!@baseboard_fab2_lib.baseboard_fab2(sch_1):page136_i101@mstr_discrete.res(chips)!RES_0402-10.0K,1%,1/16W,CHIP,GA!!!F1307!A!!!!
S!FM_ME_RECOVER_N!R7G26!2!@baseboard_fab2_lib.baseboard_fab2(sch_1):page136_i101@mstr_discrete.res(chips)!RES_0402-10.0K,1%,1/16W,CHIP,GA!!!F1307!B!!!!
S!P3V3_STBY!R8E36!1!@baseboard_fab2_lib.baseboard_fab2(sch_1):page142_i28@mstr_discrete.res(chips)!RES_0402-10.0K,1%,1/16W,CHIP,GA!!!F1261!A!!!!
S!FM_PE_SLOTX24_WAKE_N!R8E36!2!@baseboard_fab2_lib.baseboard_fab2(sch_1):page142_i28@mstr_discrete.res(chips)!RES_0402-10.0K,1%,1/16W,CHIP,GA!!!F1261!B!!!!
S!P3V3_STBY!R9F12!1!@baseboard_fab2_lib.baseboard_fab2(sch_1):page239_i6@mstr_discrete.res(chips)!RES_0402-10.0K,1%,1/16W,CHIP,GA!!!F1246!A!!!!
S!PWRGD_P1V538_BMC_STBY_R!R9F12!2!@baseboard_fab2_lib.baseboard_fab2(sch_1):page239_i6@mstr_discrete.res(chips)!RES_0402-10.0K,1%,1/16W,CHIP,GA!!!F1246!B!!!!
S!P3V3_STBY!R2N16!1!@baseboard_fab2_lib.baseboard_fab2(sch_1):page133_i247@mstr_discrete.res(chips)!RES_0402-10.0K,1%,1/16W,CHIP,GA!!!F1314!A!!!!
S!PU_IRQ_VRALERT_N!R2N16!2!@baseboard_fab2_lib.baseboard_fab2(sch_1):page133_i247@mstr_discrete.res(chips)!RES_0402-10.0K,1%,1/16W,CHIP,GA!!!F1314!B!!!!
S!P1V05_PCH_STBY!R7C21!1!@baseboard_fab2_lib.baseboard_fab2(sch_1):page135_i58@mstr_discrete.res(chips)!RES_0402-10.0K,1%,1/16W,CHIP,GA!!!F1287!A!!!!
S!FM_PCH_LVC1_THERMTRIP_N!R7C21!2!@baseboard_fab2_lib.baseboard_fab2(sch_1):page135_i58@mstr_discrete.res(chips)!RES_0402-10.0K,1%,1/16W,CHIP,GA!!!F1287!B!!!!
S!FM_BIOS_TOP_SWAP!R8E16!1!@baseboard_fab2_lib.baseboard_fab2(sch_1):page136_i140@mstr_discrete.res(chips)!RES_0402-10.0K,1%,1/16W,CHIP,GA!!!F1264!A!!!!
S!GND!R8E16!2!@baseboard_fab2_lib.baseboard_fab2(sch_1):page136_i140@mstr_discrete.res(chips)!RES_0402-10.0K,1%,1/16W,CHIP,GA!!!F1264!B!!!!
S!P3V3_STBY!R5N3!1!@baseboard_fab2_lib.baseboard_fab2(sch_1):page21_i240@mstr_discrete.res(chips)!RES_0402-10.0K,1%,1/16W,CHIP,GA!!!F1298!A!!!!
S!FM_CPU0_PKGID2!R5N3!2!@baseboard_fab2_lib.baseboard_fab2(sch_1):page21_i240@mstr_discrete.res(chips)!RES_0402-10.0K,1%,1/16W,CHIP,GA!!!F1298!B!!!!
S!P3V3_STBY!R5N5!1!@baseboard_fab2_lib.baseboard_fab2(sch_1):page21_i239@mstr_discrete.res(chips)!RES_0402-10.0K,1%,1/16W,CHIP,GA!!!F1297!A!!!!
S!FM_CPU0_PKGID1!R5N5!2!@baseboard_fab2_lib.baseboard_fab2(sch_1):page21_i239@mstr_discrete.res(chips)!RES_0402-10.0K,1%,1/16W,CHIP,GA!!!F1297!B!!!!
S!P3V3_STBY!R5N1!1!@baseboard_fab2_lib.baseboard_fab2(sch_1):page21_i238@mstr_discrete.res(chips)!RES_0402-10.0K,1%,1/16W,CHIP,GA!!!F1299!A!!!!
S!FM_CPU0_PKGID0!R5N1!2!@baseboard_fab2_lib.baseboard_fab2(sch_1):page21_i238@mstr_discrete.res(chips)!RES_0402-10.0K,1%,1/16W,CHIP,GA!!!F1299!B!!!!
S!P3V3_STBY!R8N3!1!@baseboard_fab2_lib.baseboard_fab2(sch_1):page55_i159@mstr_discrete.res(chips)!RES_0402-10.0K,1%,1/16W,CHIP,GA!!!F1256!A!!!!
S!FM_CPU1_PKGID2!R8N3!2!@baseboard_fab2_lib.baseboard_fab2(sch_1):page55_i159@mstr_discrete.res(chips)!RES_0402-10.0K,1%,1/16W,CHIP,GA!!!F1256!B!!!!
S!P3V3_STBY!R8N5!1!@baseboard_fab2_lib.baseboard_fab2(sch_1):page55_i160@mstr_discrete.res(chips)!RES_0402-10.0K,1%,1/16W,CHIP,GA!!!F1255!A!!!!
S!FM_CPU1_PKGID1!R8N5!2!@baseboard_fab2_lib.baseboard_fab2(sch_1):page55_i160@mstr_discrete.res(chips)!RES_0402-10.0K,1%,1/16W,CHIP,GA!!!F1255!B!!!!
S!P3V3_STBY!R8N2!1!@baseboard_fab2_lib.baseboard_fab2(sch_1):page55_i161@mstr_discrete.res(chips)!RES_0402-10.0K,1%,1/16W,CHIP,GA!!!F1257!A!!!!
S!FM_CPU1_PKGID0!R8N2!2!@baseboard_fab2_lib.baseboard_fab2(sch_1):page55_i161@mstr_discrete.res(chips)!RES_0402-10.0K,1%,1/16W,CHIP,GA!!!F1257!B!!!!
S!P3V3_STBY!R9E1!1!@baseboard_fab2_lib.baseboard_fab2(sch_1):page139_i179@mstr_discrete.res(chips)!RES_0402-10.0K,1%,1/16W,CHIP,GA!!!F1253!A!!!!
S!PU_JTAG_SPRV_TDI!R9E1!2!@baseboard_fab2_lib.baseboard_fab2(sch_1):page139_i179@mstr_discrete.res(chips)!RES_0402-10.0K,1%,1/16W,CHIP,GA!!!F1253!B!!!!
S!P3V3_STBY!R9E3!1!@baseboard_fab2_lib.baseboard_fab2(sch_1):page139_i178@mstr_discrete.res(chips)!RES_0402-10.0K,1%,1/16W,CHIP,GA!!!F1251!A!!!!
S!PU_JTAG_SPRV_TMS!R9E3!2!@baseboard_fab2_lib.baseboard_fab2(sch_1):page139_i178@mstr_discrete.res(chips)!RES_0402-10.0K,1%,1/16W,CHIP,GA!!!F1251!B!!!!
S!P3V3_STBY!R9E2!1!@baseboard_fab2_lib.baseboard_fab2(sch_1):page139_i177@mstr_discrete.res(chips)!RES_0402-10.0K,1%,1/16W,CHIP,GA!!!F1252!A!!!!
S!PU_JTAG_SPRV_TCK!R9E2!2!@baseboard_fab2_lib.baseboard_fab2(sch_1):page139_i177@mstr_discrete.res(chips)!RES_0402-10.0K,1%,1/16W,CHIP,GA!!!F1252!B!!!!
S!PU_JTAG_SPRV_TDO!R9E22!1!@baseboard_fab2_lib.baseboard_fab2(sch_1):page139_i181@mstr_discrete.res(chips)!RES_0402-10.0K,1%,1/16W,CHIP,GA!!!F1248!A!!!!
S!P3V3_STBY!R9E22!2!@baseboard_fab2_lib.baseboard_fab2(sch_1):page139_i181@mstr_discrete.res(chips)!RES_0402-10.0K,1%,1/16W,CHIP,GA!!!F1248!B!!!!
S!P3V3_STBY!R9F13!1!@baseboard_fab2_lib.baseboard_fab2(sch_1):page238_i21@mstr_discrete.res(chips)!RES_0402-10.0K,1%,1/16W,CHIP,GA!!!F1245!A!!!!
S!PWRGD_P1V26_BMC_STBY_R!R9F13!2!@baseboard_fab2_lib.baseboard_fab2(sch_1):page238_i21@mstr_discrete.res(chips)!RES_0402-10.0K,1%,1/16W,CHIP,GA!!!F1245!B!!!!
S!GND!R9F8!1!@baseboard_fab2_lib.baseboard_fab2(sch_1):page238_i14@mstr_discrete.res(chips)!RES_0402-10.0K,1%,1/16W,CHIP,GA!!!F1247!A!!!!
S!VR_P1V26_BMC_STBY_FB!R9F8!2!@baseboard_fab2_lib.baseboard_fab2(sch_1):page238_i14@mstr_discrete.res(chips)!RES_0402-10.0K,1%,1/16W,CHIP,GA!!!F1247!B!!!!
S!P3V3_STBY!R8D13!1!@baseboard_fab2_lib.baseboard_fab2(sch_1):page125_i52@mstr_discrete.res(chips)!RES_0402-10.0K,1%,1/16W,CHIP,GA!!!F1268!A!!!!
S!PU_ADR_TIMER_HOLD_OFF_N!R8D13!2!@baseboard_fab2_lib.baseboard_fab2(sch_1):page125_i52@mstr_discrete.res(chips)!RES_0402-10.0K,1%,1/16W,CHIP,GA!!!F1268!B!!!!
S!P3V3!R4G18!1!@baseboard_fab2_lib.baseboard_fab2(sch_1):page221_i45@mstr_discrete.res(chips)!RES_0402-10.0K,1%,1/16W,CHIP,GA!!!F1301!A!!!!
S!PWRGD_PVTT_ABC_CPU0_R!R4G18!2!@baseboard_fab2_lib.baseboard_fab2(sch_1):page221_i45@mstr_discrete.res(chips)!RES_0402-10.0K,1%,1/16W,CHIP,GA!!!F1301!B!!!!
S!P3V3_STBY!R7D8!1!@baseboard_fab2_lib.baseboard_fab2(sch_1):page133_i200@mstr_discrete.res(chips)!RES_0402-10.0K,1%,1/16W,CHIP,GA!!!F1284!A!!!!
S!PU_LPC_CLKRUN_N!R7D8!2!@baseboard_fab2_lib.baseboard_fab2(sch_1):page133_i200@mstr_discrete.res(chips)!RES_0402-10.0K,1%,1/16W,CHIP,GA!!!F1284!B!!!!
S!P3V3_STBY!R7D4!1!@baseboard_fab2_lib.baseboard_fab2(sch_1):page133_i245@mstr_discrete.res(chips)!RES_0402-10.0K,1%,1/16W,CHIP,GA!!!F1285!A!!!!
S!PU_IRQ_PCH_SCI_WHEA_N!R7D4!2!@baseboard_fab2_lib.baseboard_fab2(sch_1):page133_i245@mstr_discrete.res(chips)!RES_0402-10.0K,1%,1/16W,CHIP,GA!!!F1285!B!!!!
S!P3V3_STBY!R7D10!1!@baseboard_fab2_lib.baseboard_fab2(sch_1):page133_i202@mstr_discrete.res(chips)!RES_0402-10.0K,1%,1/16W,CHIP,GA!!!F1283!A!!!!
S!PU_LPC_PME_N!R7D10!2!@baseboard_fab2_lib.baseboard_fab2(sch_1):page133_i202@mstr_discrete.res(chips)!RES_0402-10.0K,1%,1/16W,CHIP,GA!!!F1283!B!!!!
S!P3V3_STBY!R8F26!1!@baseboard_fab2_lib.baseboard_fab2(sch_1):page156_i211@mstr_discrete.res(chips)!RES_0402-10.0K,1%,1/16W,CHIP,GA!!!F1260!A!!!!
S!FM_PCH_PWRBTN_R_N!R8F26!2!@baseboard_fab2_lib.baseboard_fab2(sch_1):page156_i211@mstr_discrete.res(chips)!RES_0402-10.0K,1%,1/16W,CHIP,GA!!!F1260!B!!!!
S!P3V3_STBY!R2T22!1!@baseboard_fab2_lib.baseboard_fab2(sch_1):page156_i210@mstr_discrete.res(chips)!RES_0402-10.0K,1%,1/16W,CHIP,GA!!!F1309!A!!!!
S!RST_BMC_SYSRST_BTN_OUT_B_R_N!R2T22!2!@baseboard_fab2_lib.baseboard_fab2(sch_1):page156_i210@mstr_discrete.res(chips)!RES_0402-10.0K,1%,1/16W,CHIP,GA!!!F1309!B!!!!
S!P3V3_STBY!R7F32!1!@baseboard_fab2_lib.baseboard_fab2(sch_1):page153_i140@mstr_discrete.res(chips)!RES_0402-10.0K,1%,1/16W,CHIP,GA!!!F1274!A!!!!
S!PU_BIOS_SPI_HOLD0_N!R7F32!2!@baseboard_fab2_lib.baseboard_fab2(sch_1):page153_i140@mstr_discrete.res(chips)!RES_0402-10.0K,1%,1/16W,CHIP,GA!!!F1274!B!!!!
S!P3V3_STBY!R7F28!1!@baseboard_fab2_lib.baseboard_fab2(sch_1):page153_i168@mstr_discrete.res(chips)!RES_0402-10.0K,1%,1/16W,CHIP,GA!!!F1275!A!!!!
S!PU_BIOS_SPI_WP0_N!R7F28!2!@baseboard_fab2_lib.baseboard_fab2(sch_1):page153_i168@mstr_discrete.res(chips)!RES_0402-10.0K,1%,1/16W,CHIP,GA!!!F1275!B!!!!
S!P3V3_STBY!R2T8!1!@baseboard_fab2_lib.baseboard_fab2(sch_1):page154_i106@mstr_discrete.res(chips)!RES_0402-10.0K,1%,1/16W,CHIP,GA!!!F1310!A!!!!
S!SPI_SWITCH_CS0_N!R2T8!2!@baseboard_fab2_lib.baseboard_fab2(sch_1):page154_i106@mstr_discrete.res(chips)!RES_0402-10.0K,1%,1/16W,CHIP,GA!!!F1310!B!!!!
S!P3V3!R6L9!1!@baseboard_fab2_lib.baseboard_fab2(sch_1):page222_i19@mstr_discrete.res(chips)!RES_0402-10.0K,1%,1/16W,CHIP,GA!!!F1295!A!!!!
S!PWRGD_PVTT_DEF_CPU0_R!R6L9!2!@baseboard_fab2_lib.baseboard_fab2(sch_1):page222_i19@mstr_discrete.res(chips)!RES_0402-10.0K,1%,1/16W,CHIP,GA!!!F1295!B!!!!
S!P3V3!R4G17!1!@baseboard_fab2_lib.baseboard_fab2(sch_1):page229_i14@mstr_discrete.res(chips)!RES_0402-10.0K,1%,1/16W,CHIP,GA!!!F1302!A!!!!
S!PWRGD_PVTT_GHJ_CPU1_R!R4G17!2!@baseboard_fab2_lib.baseboard_fab2(sch_1):page229_i14@mstr_discrete.res(chips)!RES_0402-10.0K,1%,1/16W,CHIP,GA!!!F1302!B!!!!
S!P3V3!R4A5!1!@baseboard_fab2_lib.baseboard_fab2(sch_1):page230_i17@mstr_discrete.res(chips)!RES_0402-10.0K,1%,1/16W,CHIP,GA!!!F1304!A!!!!
S!PWRGD_PVTT_KLM_CPU1_R!R4A5!2!@baseboard_fab2_lib.baseboard_fab2(sch_1):page230_i17@mstr_discrete.res(chips)!RES_0402-10.0K,1%,1/16W,CHIP,GA!!!F1304!B!!!!
S!P3V3!R2P15!1!@baseboard_fab2_lib.baseboard_fab2(sch_1):page185_i111@mstr_discrete.res(chips)!RES_0402-10.0K,1%,1/16W,CHIP,GA!!!F1267!A!!!!
S!FM_M2_SSD_PEDET!R2P15!2!@baseboard_fab2_lib.baseboard_fab2(sch_1):page185_i111@mstr_discrete.res(chips)!RES_0402-10.0K,1%,1/16W,CHIP,GA!!!F1267!B!!!!
S!P3V3_STBY!R2P16!1!@baseboard_fab2_lib.baseboard_fab2(sch_1):page185_i113@mstr_discrete.res(chips)!RES_0402-10.0K,1%,1/16W,CHIP,GA!!!F1269!A!!!!
S!FM_M2_DET_LVC3!R2P16!2!@baseboard_fab2_lib.baseboard_fab2(sch_1):page185_i113@mstr_discrete.res(chips)!RES_0402-10.0K,1%,1/16W,CHIP,GA!!!F1269!B!!!!
S!P3V3_STBY!R9E4!1!@baseboard_fab2_lib.baseboard_fab2(sch_1):page139_i200@mstr_discrete.res(chips)!RES_0402-10.0K,1%,1/16W,CHIP,GA!!!F1250!A!!!!
S!RST_PLTRST_SPRV_R_N!R9E4!2!@baseboard_fab2_lib.baseboard_fab2(sch_1):page139_i200@mstr_discrete.res(chips)!RES_0402-10.0K,1%,1/16W,CHIP,GA!!!F1250!B!!!!
S!P3V3_STBY!R8E30!1!@baseboard_fab2_lib.baseboard_fab2(sch_1):page142_i23@mstr_discrete.res(chips)!RES_0402-10.0K,1%,1/16W,CHIP,GA!!!F1263!A!!!!
S!FM_ALL_WAKE_N!R8E30!2!@baseboard_fab2_lib.baseboard_fab2(sch_1):page142_i23@mstr_discrete.res(chips)!RES_0402-10.0K,1%,1/16W,CHIP,GA!!!F1263!B!!!!
S!P3V3_STBY!R1R13!1!@baseboard_fab2_lib.baseboard_fab2(sch_1):page147_i109@mstr_discrete.res(chips)!RES_0402-10.0K,1%,1/16W,CHIP,GA!!!F1321!A!!!!
S!RMII_SPRNGVLLE_BMC_PCH_RXD1!R1R13!2!@baseboard_fab2_lib.baseboard_fab2(sch_1):page147_i109@mstr_discrete.res(chips)!RES_0402-10.0K,1%,1/16W,CHIP,GA!!!F1321!B!!!!
S!P3V3_STBY!R1R10!1!@baseboard_fab2_lib.baseboard_fab2(sch_1):page147_i108@mstr_discrete.res(chips)!RES_0402-10.0K,1%,1/16W,CHIP,GA!!!F1323!A!!!!
S!RMII_SPRNGVLLE_BMC_PCH_RXD0!R1R10!2!@baseboard_fab2_lib.baseboard_fab2(sch_1):page147_i108@mstr_discrete.res(chips)!RES_0402-10.0K,1%,1/16W,CHIP,GA!!!F1323!B!!!!
S!P3V3_STBY!R8F32!1!@baseboard_fab2_lib.baseboard_fab2(sch_1):page147_i118@mstr_discrete.res(chips)!RES_0402-10.0K,1%,1/16W,CHIP,GA!!!F1259!A!!!!
S!RMII_BMC_PCH_SPRNGVLLE_TXD1!R8F32!2!@baseboard_fab2_lib.baseboard_fab2(sch_1):page147_i118@mstr_discrete.res(chips)!RES_0402-10.0K,1%,1/16W,CHIP,GA!!!F1259!B!!!!
S!P3V3_STBY!R1R4!1!@baseboard_fab2_lib.baseboard_fab2(sch_1):page147_i119@mstr_discrete.res(chips)!RES_0402-10.0K,1%,1/16W,CHIP,GA!!!F1324!A!!!!
S!RMII_BMC_PCH_SPRNGVLLE_TXD0!R1R4!2!@baseboard_fab2_lib.baseboard_fab2(sch_1):page147_i119@mstr_discrete.res(chips)!RES_0402-10.0K,1%,1/16W,CHIP,GA!!!F1324!B!!!!
S!RMII_BMC_PCH_SPRNGVLLE_TXEN!R9E13!1!@baseboard_fab2_lib.baseboard_fab2(sch_1):page139_i212@mstr_discrete.res(chips)!RES_0402-10.0K,1%,1/16W,CHIP,GA!!!F1249!A!!!!
S!GND!R9E13!2!@baseboard_fab2_lib.baseboard_fab2(sch_1):page139_i212@mstr_discrete.res(chips)!RES_0402-10.0K,1%,1/16W,CHIP,GA!!!F1249!B!!!!
S!RMII_BMC_PCH_SPRNGVLLE_CRSDV!R1T1!1!@baseboard_fab2_lib.baseboard_fab2(sch_1):page139_i214@mstr_discrete.res(chips)!RES_0402-10.0K,1%,1/16W,CHIP,GA!!!F1320!A!!!!
S!GND!R1T1!2!@baseboard_fab2_lib.baseboard_fab2(sch_1):page139_i214@mstr_discrete.res(chips)!RES_0402-10.0K,1%,1/16W,CHIP,GA!!!F1320!B!!!!
S!P3V3_STBY!R3N10!1!@baseboard_fab2_lib.baseboard_fab2(sch_1):page121_i37@mstr_discrete.res(chips)!RES_0402-10.0K,1%,1/16W,CHIP,GA!!!F1308!A!!!!
S!FM_INTRUDER_HDR_PCH_N!R3N10!2!@baseboard_fab2_lib.baseboard_fab2(sch_1):page121_i37@mstr_discrete.res(chips)!RES_0402-10.0K,1%,1/16W,CHIP,GA!!!F1308!B!!!!
S!VR_P5V_STBY_VSENSE_R!R7F1!1!@baseboard_fab2_lib.baseboard_fab2(sch_1):page241_i50@mstr_discrete.res(chips)!RES_0402-10.0K,1%,1/16W,CHIP,GA!!!F1277!A!!!!
S!VR_P5V_STBY_VSENSE!R7F1!2!@baseboard_fab2_lib.baseboard_fab2(sch_1):page241_i50@mstr_discrete.res(chips)!RES_0402-10.0K,1%,1/16W,CHIP,GA!!!F1277!B!!!!
S!P5V!R8D39!1!@baseboard_fab2_lib.baseboard_fab2(sch_1):page196_i114@mstr_discrete.res(chips)!RES_0402-49.9K,1%,1/16W,CHIP,GA!!!F396!A!!!!
S!A_PG_P5V!R8D39!2!@baseboard_fab2_lib.baseboard_fab2(sch_1):page196_i114@mstr_discrete.res(chips)!RES_0402-49.9K,1%,1/16W,CHIP,GA!!!F396!B!!!!
S!PD_ADCREXT!R9G7!1!@baseboard_fab2_lib.baseboard_fab2(sch_1):page147_i78@mstr_discrete.res(chips)!RES_0402-49.9K,1%,1/16W,CHIP,GA!!!F397!A!!!!
S!GND!R9G7!2!@baseboard_fab2_lib.baseboard_fab2(sch_1):page147_i78@mstr_discrete.res(chips)!RES_0402-49.9K,1%,1/16W,CHIP,GA!!!F397!B!!!!
S!VR_P1V8_PCH_STBY_FB!R2L19!1!@baseboard_fab2_lib.baseboard_fab2(sch_1):page237_i80@mstr_discrete.res(chips)!RES_0402-49.9K,1%,1/16W,CHIP,GA!!!F398!A!!!!
S!GND!R2L19!2!@baseboard_fab2_lib.baseboard_fab2(sch_1):page237_i80@mstr_discrete.res(chips)!RES_0402-49.9K,1%,1/16W,CHIP,GA!!!F398!B!!!!
S!VR_P5V_STBY_RT!R7E14!1!@baseboard_fab2_lib.baseboard_fab2(sch_1):page241_i18@mstr_discrete.res(chips)!RES_0402-75K,1%,1/16W,CHIP,G21A!!!F299!A!!!!
S!AGND_P5V_STBY!R7E14!2!@baseboard_fab2_lib.baseboard_fab2(sch_1):page241_i18@mstr_discrete.res(chips)!RES_0402-75K,1%,1/16W,CHIP,G21A!!!F299!B!!!!
S!VR_P5V_STBY_BOOT!EU7E2!13!@baseboard_fab2_lib.baseboard_fab2(sch_1):page241_i83@mstr_vreg.tps54821(chips)!TPS54821_LCC-IC,H63269-001!!!F46!BOOT!!!!
S!VR_P5V_STBY_COMP!EU7E2!8!@baseboard_fab2_lib.baseboard_fab2(sch_1):page241_i83@mstr_vreg.tps54821(chips)!TPS54821_LCC-IC,H63269-001!!!F46!COMP!!!!
S!VR_P5V_STBY_EN!EU7E2!10!@baseboard_fab2_lib.baseboard_fab2(sch_1):page241_i83@mstr_vreg.tps54821(chips)!TPS54821_LCC-IC,H63269-001!!!F46!EN!!!!
S!GND!EU7E2!2!@baseboard_fab2_lib.baseboard_fab2(sch_1):page241_i83@mstr_vreg.tps54821(chips)!TPS54821_LCC-IC,H63269-001!!!F46!GND(0)!!!!
S!GND!EU7E2!3!@baseboard_fab2_lib.baseboard_fab2(sch_1):page241_i83@mstr_vreg.tps54821(chips)!TPS54821_LCC-IC,H63269-001!!!F46!GND(1)!!!!
S!VR_P5V_STBY_PHASE!EU7E2!11!@baseboard_fab2_lib.baseboard_fab2(sch_1):page241_i83@mstr_vreg.tps54821(chips)!TPS54821_LCC-IC,H63269-001!!!F46!PH(0)!!!!
S!VR_P5V_STBY_PHASE!EU7E2!12!@baseboard_fab2_lib.baseboard_fab2(sch_1):page241_i83@mstr_vreg.tps54821(chips)!TPS54821_LCC-IC,H63269-001!!!F46!PH(1)!!!!
S!VR_FET_SW_P5V_STBY_PVIN!EU7E2!4!@baseboard_fab2_lib.baseboard_fab2(sch_1):page241_i83@mstr_vreg.tps54821(chips)!TPS54821_LCC-IC,H63269-001!!!F46!PVIN(0)!!!!
S!VR_FET_SW_P5V_STBY_PVIN!EU7E2!5!@baseboard_fab2_lib.baseboard_fab2(sch_1):page241_i83@mstr_vreg.tps54821(chips)!TPS54821_LCC-IC,H63269-001!!!F46!PVIN(1)!!!!
S!PWRGD_P5V_STBY_R!EU7E2!14!@baseboard_fab2_lib.baseboard_fab2(sch_1):page241_i83@mstr_vreg.tps54821(chips)!TPS54821_LCC-IC,H63269-001!!!F46!PWRGD!!!!
S!VR_P5V_STBY_RT!EU7E2!1!@baseboard_fab2_lib.baseboard_fab2(sch_1):page241_i83@mstr_vreg.tps54821(chips)!TPS54821_LCC-IC,H63269-001!!!F46!RT_CLK!!!!
S!VR_P5V_STBY_SS!EU7E2!9!@baseboard_fab2_lib.baseboard_fab2(sch_1):page241_i83@mstr_vreg.tps54821(chips)!TPS54821_LCC-IC,H63269-001!!!F46!SS_TR!!!!
S!GND!EU7E2!15!@baseboard_fab2_lib.baseboard_fab2(sch_1):page241_i83@mstr_vreg.tps54821(chips)!TPS54821_LCC-IC,H63269-001!!!F46!THPAD!!!!
S!VR_P5V_STBY_VIN!EU7E2!6!@baseboard_fab2_lib.baseboard_fab2(sch_1):page241_i83@mstr_vreg.tps54821(chips)!TPS54821_LCC-IC,H63269-001!!!F46!VIN!!!!
S!VR_P5V_STBY_VSENSE!EU7E2!7!@baseboard_fab2_lib.baseboard_fab2(sch_1):page241_i83@mstr_vreg.tps54821(chips)!TPS54821_LCC-IC,H63269-001!!!F46!VSENSE!!!!
S!FM_ADC128_A0!EU9G1!7!@baseboard_fab2_lib.baseboard_fab2(sch_1):page165_i52@mstr_digital.adc128d818(chips)!ADC128D818_SM-IC,H63642-001!!!F4199!A0!!!!
S!FM_ADC128_A1!EU9G1!8!@baseboard_fab2_lib.baseboard_fab2(sch_1):page165_i52@mstr_digital.adc128d818(chips)!ADC128D818_SM-IC,H63642-001!!!F4199!A1!!!!
S!GND!EU9G1!4!@baseboard_fab2_lib.baseboard_fab2(sch_1):page165_i52@mstr_digital.adc128d818(chips)!ADC128D818_SM-IC,H63642-001!!!F4199!GND!!!!
S!A_P3V3_SCALED!EU9G1!16!@baseboard_fab2_lib.baseboard_fab2(sch_1):page165_i52@mstr_digital.adc128d818(chips)!ADC128D818_SM-IC,H63642-001!!!F4199!IN0!!!!
S!A_P5V_SCALED!EU9G1!15!@baseboard_fab2_lib.baseboard_fab2(sch_1):page165_i52@mstr_digital.adc128d818(chips)!ADC128D818_SM-IC,H63642-001!!!F4199!IN1!!!!
S!A_P12V_STBY_SCALED!EU9G1!14!@baseboard_fab2_lib.baseboard_fab2(sch_1):page165_i52@mstr_digital.adc128d818(chips)!ADC128D818_SM-IC,H63642-001!!!F4199!IN2!!!!
S!A_P1V05_STBY_PCH_SENSOR!EU9G1!13!@baseboard_fab2_lib.baseboard_fab2(sch_1):page165_i52@mstr_digital.adc128d818(chips)!ADC128D818_SM-IC,H63642-001!!!F4199!IN3!!!!
S!A_PVNN_STBY_PCH_SENSOR!EU9G1!12!@baseboard_fab2_lib.baseboard_fab2(sch_1):page165_i52@mstr_digital.adc128d818(chips)!ADC128D818_SM-IC,H63642-001!!!F4199!IN4!!!!
S!A_P3V3_STBY_SCALED!EU9G1!11!@baseboard_fab2_lib.baseboard_fab2(sch_1):page165_i52@mstr_digital.adc128d818(chips)!ADC128D818_SM-IC,H63642-001!!!F4199!IN5!!!!
S!A_P5V_STBY_SCALED!EU9G1!10!@baseboard_fab2_lib.baseboard_fab2(sch_1):page165_i52@mstr_digital.adc128d818(chips)!ADC128D818_SM-IC,H63642-001!!!F4199!IN6!!!!
S!A_P3V_BAT_SCALED!EU9G1!9!@baseboard_fab2_lib.baseboard_fab2(sch_1):page165_i52@mstr_digital.adc128d818(chips)!ADC128D818_SM-IC,H63642-001!!!F4199!IN7!!!!
S!IRQ_VM_INT_R_N!EU9G1!6!@baseboard_fab2_lib.baseboard_fab2(sch_1):page165_i52@mstr_digital.adc128d818(chips)!ADC128D818_SM-IC,H63642-001!!!F4199!INT_N!!!!
S!SMB_SENSOR_PCH_STBY_LVC3_SCL!EU9G1!3!@baseboard_fab2_lib.baseboard_fab2(sch_1):page165_i52@mstr_digital.adc128d818(chips)!ADC128D818_SM-IC,H63642-001!!!F4199!SCL!!!!
S!SMB_SENSOR_PCH_STBY_LVC3_SDA!EU9G1!2!@baseboard_fab2_lib.baseboard_fab2(sch_1):page165_i52@mstr_digital.adc128d818(chips)!ADC128D818_SM-IC,H63642-001!!!F4199!SDA!!!!
S!P3V3_FB_ADC128_VCC!EU9G1!5!@baseboard_fab2_lib.baseboard_fab2(sch_1):page165_i52@mstr_digital.adc128d818(chips)!ADC128D818_SM-IC,H63642-001!!!F4199!VP!!!!
S!TP_ADC128_VREF!EU9G1!1!@baseboard_fab2_lib.baseboard_fab2(sch_1):page165_i52@mstr_digital.adc128d818(chips)!ADC128D818_SM-IC,H63642-001!!!F4199!VREF!!!!
S!XTAL_PCH_48M_IN!C7C4!1!@baseboard_fab2_lib.baseboard_fab2(sch_1):page114_i50@mstr_discrete.cap(chips)!CAP_0402LF-15.0PF,50V,5%,COG,AA!!!F3157!A!!!!
S!GND!C7C4!2!@baseboard_fab2_lib.baseboard_fab2(sch_1):page114_i50@mstr_discrete.cap(chips)!CAP_0402LF-15.0PF,50V,5%,COG,AA!!!F3157!B!!!!
S!XTAL_PCH_48M_OUT!C7C5!1!@baseboard_fab2_lib.baseboard_fab2(sch_1):page114_i47@mstr_discrete.cap(chips)!CAP_0402LF-15.0PF,50V,5%,COG,AA!!!F3156!A!!!!
S!GND!C7C5!2!@baseboard_fab2_lib.baseboard_fab2(sch_1):page114_i47@mstr_discrete.cap(chips)!CAP_0402LF-15.0PF,50V,5%,COG,AA!!!F3156!B!!!!
S!XTAL_KR_25M_IN!C8C1!1!@baseboard_fab2_lib.baseboard_fab2(sch_1):page118_i79@mstr_discrete.cap(chips)!CAP_0402LF-33.0PF,50V,5%,COG,AA!!!F3119!A!!!!
S!GND!C8C1!2!@baseboard_fab2_lib.baseboard_fab2(sch_1):page118_i79@mstr_discrete.cap(chips)!CAP_0402LF-33.0PF,50V,5%,COG,AA!!!F3119!B!!!!
S!XTAL_KR_25M_OUT!C8C2!1!@baseboard_fab2_lib.baseboard_fab2(sch_1):page118_i77@mstr_discrete.cap(chips)!CAP_0402LF-33.0PF,50V,5%,COG,AA!!!F3118!A!!!!
S!GND!C8C2!2!@baseboard_fab2_lib.baseboard_fab2(sch_1):page118_i77@mstr_discrete.cap(chips)!CAP_0402LF-33.0PF,50V,5%,COG,AA!!!F3118!B!!!!
S!GND!Y8C1!4!!CRYSTAL_2013-25.000MHZ,IC,H196A!!!!!!!!
S!GND!Y8C1!2!!CRYSTAL_2013-25.000MHZ,IC,H196A!!!!!!!!
S!XTAL_KR_25M_IN!Y8C1!1!@baseboard_fab2_lib.baseboard_fab2(sch_1):page118_i76@mstr_discrete.crystal(chips)!CRYSTAL_2013-25.000MHZ,IC,H196A!!!F2231!A!!!!
S!XTAL_KR_25M_OUT!Y8C1!3!@baseboard_fab2_lib.baseboard_fab2(sch_1):page118_i76@mstr_discrete.crystal(chips)!CRYSTAL_2013-25.000MHZ,IC,H196A!!!F2231!B!!!!
S!PVPP_ABC!R8B11!1!@baseboard_fab2_lib.baseboard_fab2(sch_1):page91_i35@mstr_discrete.res(chips)!RES_0402-1.8K,1%,1/16W,CHIP,G2A!!!F1380!A!!!!
S!SMB_HFI1_CPU0_LVC2_SCL!R8B11!2!@baseboard_fab2_lib.baseboard_fab2(sch_1):page91_i35@mstr_discrete.res(chips)!RES_0402-1.8K,1%,1/16W,CHIP,G2A!!!F1380!B!!!!
S!PVPP_ABC!R8B7!1!@baseboard_fab2_lib.baseboard_fab2(sch_1):page91_i36@mstr_discrete.res(chips)!RES_0402-1.8K,1%,1/16W,CHIP,G2A!!!F1381!A!!!!
S!SMB_HFI0_CPU0_LVC2_SDA!R8B7!2!@baseboard_fab2_lib.baseboard_fab2(sch_1):page91_i36@mstr_discrete.res(chips)!RES_0402-1.8K,1%,1/16W,CHIP,G2A!!!F1381!B!!!!
S!PVPP_ABC!R8B6!1!@baseboard_fab2_lib.baseboard_fab2(sch_1):page91_i37@mstr_discrete.res(chips)!RES_0402-1.8K,1%,1/16W,CHIP,G2A!!!F1382!A!!!!
S!SMB_HFI0_CPU0_LVC2_SCL!R8B6!2!@baseboard_fab2_lib.baseboard_fab2(sch_1):page91_i37@mstr_discrete.res(chips)!RES_0402-1.8K,1%,1/16W,CHIP,G2A!!!F1382!B!!!!
S!PVPP_ABC!R8B13!1!@baseboard_fab2_lib.baseboard_fab2(sch_1):page91_i34@mstr_discrete.res(chips)!RES_0402-1.8K,1%,1/16W,CHIP,G2A!!!F1379!A!!!!
S!SMB_HFI1_CPU0_LVC2_SDA!R8B13!2!@baseboard_fab2_lib.baseboard_fab2(sch_1):page91_i34@mstr_discrete.res(chips)!RES_0402-1.8K,1%,1/16W,CHIP,G2A!!!F1379!B!!!!
S!P3V3_STBY!R5N2!1!@baseboard_fab2_lib.baseboard_fab2(sch_1):page21_i227@mstr_discrete.res(chips)!RES_0402-1.8K,1%,1/16W,CHIP,G2A!!!F1384!A!!!!
S!FM_CPU0_PROC_ID1!R5N2!2!@baseboard_fab2_lib.baseboard_fab2(sch_1):page21_i227@mstr_discrete.res(chips)!RES_0402-1.8K,1%,1/16W,CHIP,G2A!!!F1384!B!!!!
S!P3V3_STBY!R8N1!1!@baseboard_fab2_lib.baseboard_fab2(sch_1):page55_i157@mstr_discrete.res(chips)!RES_0402-1.8K,1%,1/16W,CHIP,G2A!!!F1378!A!!!!
S!FM_CPU1_PROC_ID1!R8N1!2!@baseboard_fab2_lib.baseboard_fab2(sch_1):page55_i157@mstr_discrete.res(chips)!RES_0402-1.8K,1%,1/16W,CHIP,G2A!!!F1378!B!!!!
S!P3V3_STBY!R5N4!1!@baseboard_fab2_lib.baseboard_fab2(sch_1):page21_i241@mstr_discrete.res(chips)!RES_0402-1.8K,1%,1/16W,CHIP,G2A!!!F1383!A!!!!
S!FM_CPU0_PROC_ID0!R5N4!2!@baseboard_fab2_lib.baseboard_fab2(sch_1):page21_i241@mstr_discrete.res(chips)!RES_0402-1.8K,1%,1/16W,CHIP,G2A!!!F1383!B!!!!
S!P3V3_STBY!R8N4!1!@baseboard_fab2_lib.baseboard_fab2(sch_1):page55_i158@mstr_discrete.res(chips)!RES_0402-1.8K,1%,1/16W,CHIP,G2A!!!F1377!A!!!!
S!FM_CPU1_PROC_ID0!R8N4!2!@baseboard_fab2_lib.baseboard_fab2(sch_1):page55_i158@mstr_discrete.res(chips)!RES_0402-1.8K,1%,1/16W,CHIP,G2A!!!F1377!B!!!!
S!A_PCH_XCLK_BIASREF!R3N1!1!@baseboard_fab2_lib.baseboard_fab2(sch_1):page114_i149@mstr_discrete.res(chips)!RES_0402-169,1.0%,1/16W,CHIP,GA!!!F1065!A!!!!
S!GND!R3N1!2!@baseboard_fab2_lib.baseboard_fab2(sch_1):page114_i149@mstr_discrete.res(chips)!RES_0402-169,1.0%,1/16W,CHIP,GA!!!F1065!B!!!!
S!XTAL_PCH_48M_IN!R7C1!1!@baseboard_fab2_lib.baseboard_fab2(sch_1):page114_i48@mstr_discrete.res(chips)!RES_0603-200K,0.1%,1/10W,CHIP,A!!!F257!A!!!!
S!XTAL_PCH_48M_OUT!R7C1!2!@baseboard_fab2_lib.baseboard_fab2(sch_1):page114_i48@mstr_discrete.res(chips)!RES_0603-200K,0.1%,1/10W,CHIP,A!!!F257!B!!!!
S!P3V3_STBY!R1E11!1!@baseboard_fab2_lib.baseboard_fab2(sch_1):page161_i120@mstr_discrete.res(chips)!RES_0402-10.0K,1%,1/16W,EMPTY,A!!!F1232!A!!!!
S!FM_ENABLE_FAN_POWER!R1E11!2!@baseboard_fab2_lib.baseboard_fab2(sch_1):page161_i120@mstr_discrete.res(chips)!RES_0402-10.0K,1%,1/16W,EMPTY,A!!!F1232!B!!!!
S!PWRGD_P5V_STBY!R8F1!1!@baseboard_fab2_lib.baseboard_fab2(sch_1):page240_i111@mstr_discrete.res(chips)!RES_0402-10.0K,1%,1/16W,EMPTY,A!!!F1222!A!!!!
S!GND!R8F1!2!@baseboard_fab2_lib.baseboard_fab2(sch_1):page240_i111@mstr_discrete.res(chips)!RES_0402-10.0K,1%,1/16W,EMPTY,A!!!F1222!B!!!!
S!GND!R2N12!1!@baseboard_fab2_lib.baseboard_fab2(sch_1):page133_i122@mstr_discrete.res(chips)!RES_0402-10.0K,1%,1/16W,EMPTY,A!!!F1231!A!!!!
S!PWRGD_SYS_PWROK!R2N12!2!@baseboard_fab2_lib.baseboard_fab2(sch_1):page133_i122@mstr_discrete.res(chips)!RES_0402-10.0K,1%,1/16W,EMPTY,A!!!F1231!B!!!!
S!FM_JTAG_PLD_EN_DEBUG!R3R11!1!@baseboard_fab2_lib.baseboard_fab2(sch_1):page189_i45@mstr_discrete.res(chips)!RES_0402-10.0K,1%,1/16W,EMPTY,A!!!F1228!A!!!!
S!GND!R3R11!2!@baseboard_fab2_lib.baseboard_fab2(sch_1):page189_i45@mstr_discrete.res(chips)!RES_0402-10.0K,1%,1/16W,EMPTY,A!!!F1228!B!!!!
S!PU_BIOS_SPI_WP0_N!R7F30!1!@baseboard_fab2_lib.baseboard_fab2(sch_1):page153_i170@mstr_discrete.res(chips)!RES_0402-10.0K,1%,1/16W,EMPTY,A!!!F1224!A!!!!
S!GND!R7F30!2!@baseboard_fab2_lib.baseboard_fab2(sch_1):page153_i170@mstr_discrete.res(chips)!RES_0402-10.0K,1%,1/16W,EMPTY,A!!!F1224!B!!!!
S!PU_BIOS_SPI_WP1_N!R3T9!1!@baseboard_fab2_lib.baseboard_fab2(sch_1):page153_i179@mstr_discrete.res(chips)!RES_0402-10.0K,1%,1/16W,EMPTY,A!!!F1227!A!!!!
S!GND!R3T9!2!@baseboard_fab2_lib.baseboard_fab2(sch_1):page153_i179@mstr_discrete.res(chips)!RES_0402-10.0K,1%,1/16W,EMPTY,A!!!F1227!B!!!!
S!P3V3_STBY!R3P50!1!@baseboard_fab2_lib.baseboard_fab2(sch_1):page196_i71@mstr_discrete.res(chips)!RES_0402-10.0K,1%,1/16W,EMPTY,A!!!F1229!A!!!!
S!PWRGD_P3V3_STBY!R3P50!2!@baseboard_fab2_lib.baseboard_fab2(sch_1):page196_i71@mstr_discrete.res(chips)!RES_0402-10.0K,1%,1/16W,EMPTY,A!!!F1229!B!!!!
S!P3V3_STBY!R8D16!1!@baseboard_fab2_lib.baseboard_fab2(sch_1):page125_i71@mstr_discrete.res(chips)!RES_0402-10.0K,1%,1/16W,EMPTY,A!!!F1223!A!!!!
S!RMII_PCH_SPRNGVLLE_ARB_OUT!R8D16!2!@baseboard_fab2_lib.baseboard_fab2(sch_1):page125_i71@mstr_discrete.res(chips)!RES_0402-10.0K,1%,1/16W,EMPTY,A!!!F1223!B!!!!
S!P3V3_DB1200!R4D35!1!@baseboard_fab2_lib.baseboard_fab2(sch_1):page102_i38@mstr_discrete.res(chips)!RES_0402-10.0K,1%,1/16W,EMPTY,A!!!F1226!A!!!!
S!FM_DB1200_SMB_SA0!R4D35!2!@baseboard_fab2_lib.baseboard_fab2(sch_1):page102_i38@mstr_discrete.res(chips)!RES_0402-10.0K,1%,1/16W,EMPTY,A!!!F1226!B!!!!
S!P3V3_DB1200!R4D38!1!@baseboard_fab2_lib.baseboard_fab2(sch_1):page102_i37@mstr_discrete.res(chips)!RES_0402-10.0K,1%,1/16W,EMPTY,A!!!F1225!A!!!!
S!FM_DB1200_SMB_SA1!R4D38!2!@baseboard_fab2_lib.baseboard_fab2(sch_1):page102_i37@mstr_discrete.res(chips)!RES_0402-10.0K,1%,1/16W,EMPTY,A!!!F1225!B!!!!
S!A_HSC_TIMER_R!R9P19!1!@baseboard_fab2_lib.baseboard_fab2(sch_1):page200_i70@mstr_discrete.res(chips)!RES_0402-10.0K,1%,1/16W,EMPTY,A!!!F1221!A!!!!
S!AGND_HSC!R9P19!2!@baseboard_fab2_lib.baseboard_fab2(sch_1):page200_i70@mstr_discrete.res(chips)!RES_0402-10.0K,1%,1/16W,EMPTY,A!!!F1221!B!!!!
S!PD_PEREXT!R2T12!1!@baseboard_fab2_lib.baseboard_fab2(sch_1):page145_i205@mstr_discrete.res(chips)!RES_0402-10.0K,1%,1/16W,EMPTY,A!!!F1230!A!!!!
S!GND!R2T12!2!@baseboard_fab2_lib.baseboard_fab2(sch_1):page145_i205@mstr_discrete.res(chips)!RES_0402-10.0K,1%,1/16W,EMPTY,A!!!F1230!B!!!!
S!VSENSE_PMAX_CPU0!R5D5!1!@baseboard_fab2_lib.baseboard_fab2(sch_1):page37_i303@mstr_discrete.res(chips)!RES_0402-249,0.1%,1/16W,CHIP,GA!!!F807!A!!!!
S!GND!R5D5!2!@baseboard_fab2_lib.baseboard_fab2(sch_1):page37_i303@mstr_discrete.res(chips)!RES_0402-249,0.1%,1/16W,CHIP,GA!!!F807!B!!!!
S!VSENSE_PMAX_CPU1!R3D27!1!@baseboard_fab2_lib.baseboard_fab2(sch_1):page71_i43@mstr_discrete.res(chips)!RES_0402-249,0.1%,1/16W,CHIP,GA!!!F808!A!!!!
S!GND!R3D27!2!@baseboard_fab2_lib.baseboard_fab2(sch_1):page71_i43@mstr_discrete.res(chips)!RES_0402-249,0.1%,1/16W,CHIP,GA!!!F808!B!!!!
S!P1V26_BMC_STBY!R9F6!1!@baseboard_fab2_lib.baseboard_fab2(sch_1):page238_i17@mstr_discrete.res(chips)!RES_0402-5.76K,1%,1/16W,CHIP,GA!!!F387!A!!!!
S!VR_P1V26_BMC_STBY_FB!R9F6!2!@baseboard_fab2_lib.baseboard_fab2(sch_1):page238_i17@mstr_discrete.res(chips)!RES_0402-5.76K,1%,1/16W,CHIP,GA!!!F387!B!!!!
S!CLK_100M_CPU1_RC_REFCLK1_R_DP!R4D23!1!@baseboard_fab2_lib.baseboard_fab2(sch_1):page103_i9@mstr_discrete.res(chips)!RES_0402-27.4,1%,1/16W,CHIP,G2A!!!F785!A!!!!
S!CLK_100M_CPU1_RC_REFCLK1_DP!R4D23!2!@baseboard_fab2_lib.baseboard_fab2(sch_1):page103_i9@mstr_discrete.res(chips)!RES_0402-27.4,1%,1/16W,CHIP,G2A!!!F785!B!!!!
S!CLK_100M_CPU1_RC_REFCLK1_R_DN!R4D28!1!@baseboard_fab2_lib.baseboard_fab2(sch_1):page103_i14@mstr_discrete.res(chips)!RES_0402-27.4,1%,1/16W,CHIP,G2A!!!F783!A!!!!
S!CLK_100M_CPU1_RC_REFCLK1_DN!R4D28!2!@baseboard_fab2_lib.baseboard_fab2(sch_1):page103_i14@mstr_discrete.res(chips)!RES_0402-27.4,1%,1/16W,CHIP,G2A!!!F783!B!!!!
S!CLK_100M_CPU1_RC_REFCLK0_R_DP!R4D19!1!@baseboard_fab2_lib.baseboard_fab2(sch_1):page103_i19@mstr_discrete.res(chips)!RES_0402-27.4,1%,1/16W,CHIP,G2A!!!F789!A!!!!
S!CLK_100M_CPU1_RC_REFCLK0_DP!R4D19!2!@baseboard_fab2_lib.baseboard_fab2(sch_1):page103_i19@mstr_discrete.res(chips)!RES_0402-27.4,1%,1/16W,CHIP,G2A!!!F789!B!!!!
S!CLK_100M_CPU1_RC_REFCLK0_R_DN!R4D21!1!@baseboard_fab2_lib.baseboard_fab2(sch_1):page103_i24@mstr_discrete.res(chips)!RES_0402-27.4,1%,1/16W,CHIP,G2A!!!F787!A!!!!
S!CLK_100M_CPU1_RC_REFCLK0_DN!R4D21!2!@baseboard_fab2_lib.baseboard_fab2(sch_1):page103_i24@mstr_discrete.res(chips)!RES_0402-27.4,1%,1/16W,CHIP,G2A!!!F787!B!!!!
S!CLK_100M_CPU1_PE_REFCLK_R_DP!R4D13!1!@baseboard_fab2_lib.baseboard_fab2(sch_1):page103_i29@mstr_discrete.res(chips)!RES_0402-27.4,1%,1/16W,CHIP,G2A!!!F793!A!!!!
S!CLK_100M_CPU1_PE_REFCLK_DP!R4D13!2!@baseboard_fab2_lib.baseboard_fab2(sch_1):page103_i29@mstr_discrete.res(chips)!RES_0402-27.4,1%,1/16W,CHIP,G2A!!!F793!B!!!!
S!CLK_100M_CPU1_PE_REFCLK_R_DN!R4D16!1!@baseboard_fab2_lib.baseboard_fab2(sch_1):page103_i34@mstr_discrete.res(chips)!RES_0402-27.4,1%,1/16W,CHIP,G2A!!!F791!A!!!!
S!CLK_100M_CPU1_PE_REFCLK_DN!R4D16!2!@baseboard_fab2_lib.baseboard_fab2(sch_1):page103_i34@mstr_discrete.res(chips)!RES_0402-27.4,1%,1/16W,CHIP,G2A!!!F791!B!!!!
S!CLK_100M_CPU1_BCLK2_R_DP!R4D9!1!@baseboard_fab2_lib.baseboard_fab2(sch_1):page103_i39@mstr_discrete.res(chips)!RES_0402-27.4,1%,1/16W,CHIP,G2A!!!F797!A!!!!
S!CLK_100M_CPU1_BCLK2_DP!R4D9!2!@baseboard_fab2_lib.baseboard_fab2(sch_1):page103_i39@mstr_discrete.res(chips)!RES_0402-27.4,1%,1/16W,CHIP,G2A!!!F797!B!!!!
S!CLK_100M_CPU1_BCLK2_R_DN!R4D11!1!@baseboard_fab2_lib.baseboard_fab2(sch_1):page103_i44@mstr_discrete.res(chips)!RES_0402-27.4,1%,1/16W,CHIP,G2A!!!F795!A!!!!
S!CLK_100M_CPU1_BCLK2_DN!R4D11!2!@baseboard_fab2_lib.baseboard_fab2(sch_1):page103_i44@mstr_discrete.res(chips)!RES_0402-27.4,1%,1/16W,CHIP,G2A!!!F795!B!!!!
S!CLK_100M_CPU1_BCLK1_R_DN!R4D1!1!@baseboard_fab2_lib.baseboard_fab2(sch_1):page103_i54@mstr_discrete.res(chips)!RES_0402-27.4,1%,1/16W,CHIP,G2A!!!F805!A!!!!
S!CLK_100M_CPU1_BCLK1_DN!R4D1!2!@baseboard_fab2_lib.baseboard_fab2(sch_1):page103_i54@mstr_discrete.res(chips)!RES_0402-27.4,1%,1/16W,CHIP,G2A!!!F805!B!!!!
S!CLK_100M_CPU1_BCLK0_R_DP!R4D4!1!@baseboard_fab2_lib.baseboard_fab2(sch_1):page103_i59@mstr_discrete.res(chips)!RES_0402-27.4,1%,1/16W,CHIP,G2A!!!F802!A!!!!
S!CLK_100M_CPU1_BCLK0_DP!R4D4!2!@baseboard_fab2_lib.baseboard_fab2(sch_1):page103_i59@mstr_discrete.res(chips)!RES_0402-27.4,1%,1/16W,CHIP,G2A!!!F802!B!!!!
S!CLK_100M_CPU1_BCLK0_R_DN!R4D3!1!@baseboard_fab2_lib.baseboard_fab2(sch_1):page103_i64@mstr_discrete.res(chips)!RES_0402-27.4,1%,1/16W,CHIP,G2A!!!F803!A!!!!
S!CLK_100M_CPU1_BCLK0_DN!R4D3!2!@baseboard_fab2_lib.baseboard_fab2(sch_1):page103_i64@mstr_discrete.res(chips)!RES_0402-27.4,1%,1/16W,CHIP,G2A!!!F803!B!!!!
S!CLK_100M_CPU0_RC_REFCLK1_R_DP!R4D6!1!@baseboard_fab2_lib.baseboard_fab2(sch_1):page103_i74@mstr_discrete.res(chips)!RES_0402-27.4,1%,1/16W,CHIP,G2A!!!F800!A!!!!
S!CLK_100M_CPU0_RC_REFCLK1_DP!R4D6!2!@baseboard_fab2_lib.baseboard_fab2(sch_1):page103_i74@mstr_discrete.res(chips)!RES_0402-27.4,1%,1/16W,CHIP,G2A!!!F800!B!!!!
S!CLK_100M_CPU0_RC_REFCLK1_R_DN!R4D5!1!@baseboard_fab2_lib.baseboard_fab2(sch_1):page103_i79@mstr_discrete.res(chips)!RES_0402-27.4,1%,1/16W,CHIP,G2A!!!F801!A!!!!
S!CLK_100M_CPU0_RC_REFCLK1_DN!R4D5!2!@baseboard_fab2_lib.baseboard_fab2(sch_1):page103_i79@mstr_discrete.res(chips)!RES_0402-27.4,1%,1/16W,CHIP,G2A!!!F801!B!!!!
S!CLK_100M_CPU0_RC_REFCLK0_R_DP!R4D8!1!@baseboard_fab2_lib.baseboard_fab2(sch_1):page103_i84@mstr_discrete.res(chips)!RES_0402-27.4,1%,1/16W,CHIP,G2A!!!F798!A!!!!
S!CLK_100M_CPU0_RC_REFCLK0_DP!R4D8!2!@baseboard_fab2_lib.baseboard_fab2(sch_1):page103_i84@mstr_discrete.res(chips)!RES_0402-27.4,1%,1/16W,CHIP,G2A!!!F798!B!!!!
S!CLK_100M_CPU0_RC_REFCLK0_R_DN!R4D7!1!@baseboard_fab2_lib.baseboard_fab2(sch_1):page103_i89@mstr_discrete.res(chips)!RES_0402-27.4,1%,1/16W,CHIP,G2A!!!F799!A!!!!
S!CLK_100M_CPU0_RC_REFCLK0_DN!R4D7!2!@baseboard_fab2_lib.baseboard_fab2(sch_1):page103_i89@mstr_discrete.res(chips)!RES_0402-27.4,1%,1/16W,CHIP,G2A!!!F799!B!!!!
S!CLK_100M_CPU0_PE_REFCLK_R_DP!R4D12!1!@baseboard_fab2_lib.baseboard_fab2(sch_1):page103_i94@mstr_discrete.res(chips)!RES_0402-27.4,1%,1/16W,CHIP,G2A!!!F794!A!!!!
S!CLK_100M_CPU0_PE_REFCLK_DP!R4D12!2!@baseboard_fab2_lib.baseboard_fab2(sch_1):page103_i94@mstr_discrete.res(chips)!RES_0402-27.4,1%,1/16W,CHIP,G2A!!!F794!B!!!!
S!CLK_100M_CPU0_PE_REFCLK_R_DN!R4D10!1!@baseboard_fab2_lib.baseboard_fab2(sch_1):page103_i99@mstr_discrete.res(chips)!RES_0402-27.4,1%,1/16W,CHIP,G2A!!!F796!A!!!!
S!CLK_100M_CPU0_PE_REFCLK_DN!R4D10!2!@baseboard_fab2_lib.baseboard_fab2(sch_1):page103_i99@mstr_discrete.res(chips)!RES_0402-27.4,1%,1/16W,CHIP,G2A!!!F796!B!!!!
S!CLK_100M_CPU0_BCLK2_R_DP!R4D17!1!@baseboard_fab2_lib.baseboard_fab2(sch_1):page103_i104@mstr_discrete.res(chips)!RES_0402-27.4,1%,1/16W,CHIP,G2A!!!F790!A!!!!
S!CLK_100M_CPU0_BCLK2_DP!R4D17!2!@baseboard_fab2_lib.baseboard_fab2(sch_1):page103_i104@mstr_discrete.res(chips)!RES_0402-27.4,1%,1/16W,CHIP,G2A!!!F790!B!!!!
S!CLK_100M_CPU0_BCLK2_R_DN!R4D14!1!@baseboard_fab2_lib.baseboard_fab2(sch_1):page103_i109@mstr_discrete.res(chips)!RES_0402-27.4,1%,1/16W,CHIP,G2A!!!F792!A!!!!
S!CLK_100M_CPU0_BCLK2_DN!R4D14!2!@baseboard_fab2_lib.baseboard_fab2(sch_1):page103_i109@mstr_discrete.res(chips)!RES_0402-27.4,1%,1/16W,CHIP,G2A!!!F792!B!!!!
S!CLK_100M_CPU0_BCLK1_R_DP!R4D22!1!@baseboard_fab2_lib.baseboard_fab2(sch_1):page103_i114@mstr_discrete.res(chips)!RES_0402-27.4,1%,1/16W,CHIP,G2A!!!F786!A!!!!
S!CLK_100M_CPU0_BCLK1_DP!R4D22!2!@baseboard_fab2_lib.baseboard_fab2(sch_1):page103_i114@mstr_discrete.res(chips)!RES_0402-27.4,1%,1/16W,CHIP,G2A!!!F786!B!!!!
S!CLK_100M_CPU0_BCLK1_R_DN!R4D20!1!@baseboard_fab2_lib.baseboard_fab2(sch_1):page103_i119@mstr_discrete.res(chips)!RES_0402-27.4,1%,1/16W,CHIP,G2A!!!F788!A!!!!
S!CLK_100M_CPU0_BCLK1_DN!R4D20!2!@baseboard_fab2_lib.baseboard_fab2(sch_1):page103_i119@mstr_discrete.res(chips)!RES_0402-27.4,1%,1/16W,CHIP,G2A!!!F788!B!!!!
S!CLK_100M_CPU0_BCLK0_R_DP!R4D29!1!@baseboard_fab2_lib.baseboard_fab2(sch_1):page103_i69@mstr_discrete.res(chips)!RES_0402-27.4,1%,1/16W,CHIP,G2A!!!F782!A!!!!
S!CLK_100M_CPU0_BCLK0_DP!R4D29!2!@baseboard_fab2_lib.baseboard_fab2(sch_1):page103_i69@mstr_discrete.res(chips)!RES_0402-27.4,1%,1/16W,CHIP,G2A!!!F782!B!!!!
S!CLK_100M_CPU0_BCLK0_R_DN!R4D25!1!@baseboard_fab2_lib.baseboard_fab2(sch_1):page103_i1@mstr_discrete.res(chips)!RES_0402-27.4,1%,1/16W,CHIP,G2A!!!F784!A!!!!
S!CLK_100M_CPU0_BCLK0_DN!R4D25!2!@baseboard_fab2_lib.baseboard_fab2(sch_1):page103_i1@mstr_discrete.res(chips)!RES_0402-27.4,1%,1/16W,CHIP,G2A!!!F784!B!!!!
S!CLK_100M_CPU1_BCLK1_R_DP!R4D2!1!@baseboard_fab2_lib.baseboard_fab2(sch_1):page103_i49@mstr_discrete.res(chips)!RES_0402-27.4,1%,1/16W,CHIP,G2A!!!F804!A!!!!
S!CLK_100M_CPU1_BCLK1_DP!R4D2!2!@baseboard_fab2_lib.baseboard_fab2(sch_1):page103_i49@mstr_discrete.res(chips)!RES_0402-27.4,1%,1/16W,CHIP,G2A!!!F804!B!!!!
S!P12V_STBY!L4C1!1!@baseboard_fab2_lib.baseboard_fab2(sch_1):page204_i46@mstr_discrete.inductor(chips)!INDUCTOR_SM-100NH,IND,D92183-0A!!!F2090!INA!!!!
S!VR_FET_SW_P12V_PVCCIN_CPU0_R!L4C1!2!@baseboard_fab2_lib.baseboard_fab2(sch_1):page204_i46@mstr_discrete.inductor(chips)!INDUCTOR_SM-100NH,IND,D92183-0A!!!F2090!INB!!!!
S!P12V_STBY!L1B2!1!@baseboard_fab2_lib.baseboard_fab2(sch_1):page209_i32@mstr_discrete.inductor(chips)!INDUCTOR_SM-100NH,IND,D92183-0A!!!F2091!INA!!!!
S!VR_FET_SW_P12V_PVCCIN_CPU1_R!L1B2!2!@baseboard_fab2_lib.baseboard_fab2(sch_1):page209_i32@mstr_discrete.inductor(chips)!INDUCTOR_SM-100NH,IND,D92183-0A!!!F2091!INB!!!!
S!P12V_STBY!L7F2!1!@baseboard_fab2_lib.baseboard_fab2(sch_1):page217_i124@mstr_discrete.inductor(chips)!INDUCTOR_SM-100NH,IND,D92183-0B!!!F2085!INA!!!!
S!VR_FET_SW_P12V_STBY_PVDDQ_ABC!L7F2!2!@baseboard_fab2_lib.baseboard_fab2(sch_1):page217_i124@mstr_discrete.inductor(chips)!INDUCTOR_SM-100NH,IND,D92183-0B!!!F2085!INB!!!!
S!P12V_STBY!L1F1!1!@baseboard_fab2_lib.baseboard_fab2(sch_1):page225_i124@mstr_discrete.inductor(chips)!INDUCTOR_SM-100NH,IND,D92183-0B!!!F2088!INA!!!!
S!VR_FET_SW_P12V_STBY_PVDDQ_GHJ!L1F1!2!@baseboard_fab2_lib.baseboard_fab2(sch_1):page225_i124@mstr_discrete.inductor(chips)!INDUCTOR_SM-100NH,IND,D92183-0B!!!F2088!INB!!!!
S!P12V_STBY!L1B1!1!@baseboard_fab2_lib.baseboard_fab2(sch_1):page228_i124@mstr_discrete.inductor(chips)!INDUCTOR_SM-100NH,IND,D92183-0B!!!F2089!INA!!!!
S!VR_FET_SW_P12V_STBY_PVDDQ_KLM!L1B1!2!@baseboard_fab2_lib.baseboard_fab2(sch_1):page228_i124@mstr_discrete.inductor(chips)!INDUCTOR_SM-100NH,IND,D92183-0B!!!F2089!INB!!!!
S!P12V_STBY!L7A5!1!@baseboard_fab2_lib.baseboard_fab2(sch_1):page220_i124@mstr_discrete.inductor(chips)!INDUCTOR_SM-100NH,IND,D92183-0B!!!F2087!INA!!!!
S!VR_FET_SW_P12V_STBY_PVDDQ_DEF!L7A5!2!@baseboard_fab2_lib.baseboard_fab2(sch_1):page220_i124@mstr_discrete.inductor(chips)!INDUCTOR_SM-100NH,IND,D92183-0B!!!F2087!INB!!!!
S!P12V_STBY!L7C1!1!@baseboard_fab2_lib.baseboard_fab2(sch_1):page212_i56@mstr_discrete.inductor(chips)!INDUCTOR_SM-100NH,IND,D92183-0B!!!F2086!INA!!!!
S!VR_FET_SW_P12V_STBY_PVCCIO_CPU0!L7C1!2!@baseboard_fab2_lib.baseboard_fab2(sch_1):page212_i56@mstr_discrete.inductor(chips)!INDUCTOR_SM-100NH,IND,D92183-0B!!!F2086!INB!!!!
S!FM_100M_N!EU4D2!4!@baseboard_fab2_lib.baseboard_fab2(sch_1):page102_i1@mstr_clock.nb3w1200l(chips)!NB3W1200L_LCC-IC,H13585-001!!!F2006!\100m_133m_n\!!!!
S!CLK_100M_DB1200_DN!EU4D2!10!@baseboard_fab2_lib.baseboard_fab2(sch_1):page102_i1@mstr_clock.nb3w1200l(chips)!NB3W1200L_LCC-IC,H13585-001!!!F2006!CLK_INN!!!!
S!CLK_100M_DB1200_DP!EU4D2!9!@baseboard_fab2_lib.baseboard_fab2(sch_1):page102_i1@mstr_clock.nb3w1200l(chips)!NB3W1200L_LCC-IC,H13585-001!!!F2006!CLK_INP!!!!
S!CLK_100M_CPU0_BCLK0_R_DN!EU4D2!18!@baseboard_fab2_lib.baseboard_fab2(sch_1):page102_i1@mstr_clock.nb3w1200l(chips)!NB3W1200L_LCC-IC,H13585-001!!!F2006!DIF_0N!!!!
S!CLK_100M_CPU0_BCLK0_R_DP!EU4D2!17!@baseboard_fab2_lib.baseboard_fab2(sch_1):page102_i1@mstr_clock.nb3w1200l(chips)!NB3W1200L_LCC-IC,H13585-001!!!F2006!DIF_0P!!!!
S!CLK_100M_CPU1_RC_REFCLK0_R_DN!EU4D2!60!@baseboard_fab2_lib.baseboard_fab2(sch_1):page102_i1@mstr_clock.nb3w1200l(chips)!NB3W1200L_LCC-IC,H13585-001!!!F2006!DIF_10N!!!!
S!CLK_100M_CPU1_RC_REFCLK0_R_DP!EU4D2!59!@baseboard_fab2_lib.baseboard_fab2(sch_1):page102_i1@mstr_clock.nb3w1200l(chips)!NB3W1200L_LCC-IC,H13585-001!!!F2006!DIF_10P!!!!
S!CLK_100M_CPU1_RC_REFCLK1_R_DN!EU4D2!64!@baseboard_fab2_lib.baseboard_fab2(sch_1):page102_i1@mstr_clock.nb3w1200l(chips)!NB3W1200L_LCC-IC,H13585-001!!!F2006!DIF_11N!!!!
S!CLK_100M_CPU1_RC_REFCLK1_R_DP!EU4D2!63!@baseboard_fab2_lib.baseboard_fab2(sch_1):page102_i1@mstr_clock.nb3w1200l(chips)!NB3W1200L_LCC-IC,H13585-001!!!F2006!DIF_11P!!!!
S!CLK_100M_CPU0_BCLK1_R_DN!EU4D2!22!@baseboard_fab2_lib.baseboard_fab2(sch_1):page102_i1@mstr_clock.nb3w1200l(chips)!NB3W1200L_LCC-IC,H13585-001!!!F2006!DIF_1N!!!!
S!CLK_100M_CPU0_BCLK1_R_DP!EU4D2!21!@baseboard_fab2_lib.baseboard_fab2(sch_1):page102_i1@mstr_clock.nb3w1200l(chips)!NB3W1200L_LCC-IC,H13585-001!!!F2006!DIF_1P!!!!
S!CLK_100M_CPU0_BCLK2_R_DN!EU4D2!27!@baseboard_fab2_lib.baseboard_fab2(sch_1):page102_i1@mstr_clock.nb3w1200l(chips)!NB3W1200L_LCC-IC,H13585-001!!!F2006!DIF_2N!!!!
S!CLK_100M_CPU0_BCLK2_R_DP!EU4D2!26!@baseboard_fab2_lib.baseboard_fab2(sch_1):page102_i1@mstr_clock.nb3w1200l(chips)!NB3W1200L_LCC-IC,H13585-001!!!F2006!DIF_2P!!!!
S!CLK_100M_CPU0_PE_REFCLK_R_DN!EU4D2!31!@baseboard_fab2_lib.baseboard_fab2(sch_1):page102_i1@mstr_clock.nb3w1200l(chips)!NB3W1200L_LCC-IC,H13585-001!!!F2006!DIF_3N!!!!
S!CLK_100M_CPU0_PE_REFCLK_R_DP!EU4D2!30!@baseboard_fab2_lib.baseboard_fab2(sch_1):page102_i1@mstr_clock.nb3w1200l(chips)!NB3W1200L_LCC-IC,H13585-001!!!F2006!DIF_3P!!!!
S!CLK_100M_CPU0_RC_REFCLK0_R_DN!EU4D2!35!@baseboard_fab2_lib.baseboard_fab2(sch_1):page102_i1@mstr_clock.nb3w1200l(chips)!NB3W1200L_LCC-IC,H13585-001!!!F2006!DIF_4N!!!!
S!CLK_100M_CPU0_RC_REFCLK0_R_DP!EU4D2!34!@baseboard_fab2_lib.baseboard_fab2(sch_1):page102_i1@mstr_clock.nb3w1200l(chips)!NB3W1200L_LCC-IC,H13585-001!!!F2006!DIF_4P!!!!
S!CLK_100M_CPU0_RC_REFCLK1_R_DN!EU4D2!39!@baseboard_fab2_lib.baseboard_fab2(sch_1):page102_i1@mstr_clock.nb3w1200l(chips)!NB3W1200L_LCC-IC,H13585-001!!!F2006!DIF_5N!!!!
S!CLK_100M_CPU0_RC_REFCLK1_R_DP!EU4D2!38!@baseboard_fab2_lib.baseboard_fab2(sch_1):page102_i1@mstr_clock.nb3w1200l(chips)!NB3W1200L_LCC-IC,H13585-001!!!F2006!DIF_5P!!!!
S!CLK_100M_CPU1_BCLK0_R_DN!EU4D2!43!@baseboard_fab2_lib.baseboard_fab2(sch_1):page102_i1@mstr_clock.nb3w1200l(chips)!NB3W1200L_LCC-IC,H13585-001!!!F2006!DIF_6N!!!!
S!CLK_100M_CPU1_BCLK0_R_DP!EU4D2!42!@baseboard_fab2_lib.baseboard_fab2(sch_1):page102_i1@mstr_clock.nb3w1200l(chips)!NB3W1200L_LCC-IC,H13585-001!!!F2006!DIF_6P!!!!
S!CLK_100M_CPU1_BCLK1_R_DN!EU4D2!47!@baseboard_fab2_lib.baseboard_fab2(sch_1):page102_i1@mstr_clock.nb3w1200l(chips)!NB3W1200L_LCC-IC,H13585-001!!!F2006!DIF_7N!!!!
S!CLK_100M_CPU1_BCLK1_R_DP!EU4D2!46!@baseboard_fab2_lib.baseboard_fab2(sch_1):page102_i1@mstr_clock.nb3w1200l(chips)!NB3W1200L_LCC-IC,H13585-001!!!F2006!DIF_7P!!!!
S!CLK_100M_CPU1_BCLK2_R_DN!EU4D2!51!@baseboard_fab2_lib.baseboard_fab2(sch_1):page102_i1@mstr_clock.nb3w1200l(chips)!NB3W1200L_LCC-IC,H13585-001!!!F2006!DIF_8N!!!!
S!CLK_100M_CPU1_BCLK2_R_DP!EU4D2!50!@baseboard_fab2_lib.baseboard_fab2(sch_1):page102_i1@mstr_clock.nb3w1200l(chips)!NB3W1200L_LCC-IC,H13585-001!!!F2006!DIF_8P!!!!
S!CLK_100M_CPU1_PE_REFCLK_R_DN!EU4D2!55!@baseboard_fab2_lib.baseboard_fab2(sch_1):page102_i1@mstr_clock.nb3w1200l(chips)!NB3W1200L_LCC-IC,H13585-001!!!F2006!DIF_9N!!!!
S!CLK_100M_CPU1_PE_REFCLK_R_DP!EU4D2!54!@baseboard_fab2_lib.baseboard_fab2(sch_1):page102_i1@mstr_clock.nb3w1200l(chips)!NB3W1200L_LCC-IC,H13585-001!!!F2006!DIF_9P!!!!
S!GND!EU4D2!7!@baseboard_fab2_lib.baseboard_fab2(sch_1):page102_i1@mstr_clock.nb3w1200l(chips)!NB3W1200L_LCC-IC,H13585-001!!!F2006!GND(0)!!!!
S!GND!EU4D2!23!@baseboard_fab2_lib.baseboard_fab2(sch_1):page102_i1@mstr_clock.nb3w1200l(chips)!NB3W1200L_LCC-IC,H13585-001!!!F2006!GND(1)!!!!
S!GND!EU4D2!33!@baseboard_fab2_lib.baseboard_fab2(sch_1):page102_i1@mstr_clock.nb3w1200l(chips)!NB3W1200L_LCC-IC,H13585-001!!!F2006!GND(2)!!!!
S!GND!EU4D2!41!@baseboard_fab2_lib.baseboard_fab2(sch_1):page102_i1@mstr_clock.nb3w1200l(chips)!NB3W1200L_LCC-IC,H13585-001!!!F2006!GND(3)!!!!
S!GND!EU4D2!48!@baseboard_fab2_lib.baseboard_fab2(sch_1):page102_i1@mstr_clock.nb3w1200l(chips)!NB3W1200L_LCC-IC,H13585-001!!!F2006!GND(4)!!!!
S!GND!EU4D2!58!@baseboard_fab2_lib.baseboard_fab2(sch_1):page102_i1@mstr_clock.nb3w1200l(chips)!NB3W1200L_LCC-IC,H13585-001!!!F2006!GND(5)!!!!
S!GND!EU4D2!2!@baseboard_fab2_lib.baseboard_fab2(sch_1):page102_i1@mstr_clock.nb3w1200l(chips)!NB3W1200L_LCC-IC,H13585-001!!!F2006!GNDA!!!!
S!FM_HBW_BYPASS_LOWBW_N!EU4D2!5!@baseboard_fab2_lib.baseboard_fab2(sch_1):page102_i1@mstr_clock.nb3w1200l(chips)!NB3W1200L_LCC-IC,H13585-001!!!F2006!HBW_BYPASS_LOBW_N!!!!
S!NC_DB1200ZL<0>!EU4D2!3!@baseboard_fab2_lib.baseboard_fab2(sch_1):page102_i1@mstr_clock.nb3w1200l(chips)!NB3W1200L_LCC-IC,H13585-001!!!F2006!NC(0)!!!!
S!NC_DB1200ZL<1>!EU4D2!16!@baseboard_fab2_lib.baseboard_fab2(sch_1):page102_i1@mstr_clock.nb3w1200l(chips)!NB3W1200L_LCC-IC,H13585-001!!!F2006!NC(1)!!!!
S!NC_DB1200ZL<2>!EU4D2!15!@baseboard_fab2_lib.baseboard_fab2(sch_1):page102_i1@mstr_clock.nb3w1200l(chips)!NB3W1200L_LCC-IC,H13585-001!!!F2006!NC(2)!!!!
S!FM_DB1200ZL_BCLKS_EN_N!EU4D2!19!@baseboard_fab2_lib.baseboard_fab2(sch_1):page102_i1@mstr_clock.nb3w1200l(chips)!NB3W1200L_LCC-IC,H13585-001!!!F2006!OE_0_N!!!!
S!FM_CPU1_MCP_CLK_EN_N!EU4D2!61!@baseboard_fab2_lib.baseboard_fab2(sch_1):page102_i1@mstr_clock.nb3w1200l(chips)!NB3W1200L_LCC-IC,H13585-001!!!F2006!OE_10_N!!!!
S!FM_CPU1_MCP_CLK_EN_N!EU4D2!62!@baseboard_fab2_lib.baseboard_fab2(sch_1):page102_i1@mstr_clock.nb3w1200l(chips)!NB3W1200L_LCC-IC,H13585-001!!!F2006!OE_11_N!!!!
S!FM_DB1200ZL_BCLKS_EN_N!EU4D2!20!@baseboard_fab2_lib.baseboard_fab2(sch_1):page102_i1@mstr_clock.nb3w1200l(chips)!NB3W1200L_LCC-IC,H13585-001!!!F2006!OE_1_N!!!!
S!FM_DB1200ZL_BCLKS_EN_N!EU4D2!28!@baseboard_fab2_lib.baseboard_fab2(sch_1):page102_i1@mstr_clock.nb3w1200l(chips)!NB3W1200L_LCC-IC,H13585-001!!!F2006!OE_2_N!!!!
S!FM_CPU0_MCP_CLK_EN_N!EU4D2!29!@baseboard_fab2_lib.baseboard_fab2(sch_1):page102_i1@mstr_clock.nb3w1200l(chips)!NB3W1200L_LCC-IC,H13585-001!!!F2006!OE_3_N!!!!
S!FM_CPU0_MCP_CLK_EN_N!EU4D2!36!@baseboard_fab2_lib.baseboard_fab2(sch_1):page102_i1@mstr_clock.nb3w1200l(chips)!NB3W1200L_LCC-IC,H13585-001!!!F2006!OE_4_N!!!!
S!FM_CPU0_MCP_CLK_EN_N!EU4D2!37!@baseboard_fab2_lib.baseboard_fab2(sch_1):page102_i1@mstr_clock.nb3w1200l(chips)!NB3W1200L_LCC-IC,H13585-001!!!F2006!OE_5_N!!!!
S!FM_DB1200ZL_BCLKS_EN_N!EU4D2!44!@baseboard_fab2_lib.baseboard_fab2(sch_1):page102_i1@mstr_clock.nb3w1200l(chips)!NB3W1200L_LCC-IC,H13585-001!!!F2006!OE_6_N!!!!
S!FM_DB1200ZL_BCLKS_EN_N!EU4D2!45!@baseboard_fab2_lib.baseboard_fab2(sch_1):page102_i1@mstr_clock.nb3w1200l(chips)!NB3W1200L_LCC-IC,H13585-001!!!F2006!OE_7_N!!!!
S!FM_DB1200ZL_BCLKS_EN_N!EU4D2!52!@baseboard_fab2_lib.baseboard_fab2(sch_1):page102_i1@mstr_clock.nb3w1200l(chips)!NB3W1200L_LCC-IC,H13585-001!!!F2006!OE_8_N!!!!
S!FM_CPU1_MCP_CLK_EN_N!EU4D2!53!@baseboard_fab2_lib.baseboard_fab2(sch_1):page102_i1@mstr_clock.nb3w1200l(chips)!NB3W1200L_LCC-IC,H13585-001!!!F2006!OE_9_N!!!!
S!FM_DB1200_PWRGD!EU4D2!6!@baseboard_fab2_lib.baseboard_fab2(sch_1):page102_i1@mstr_clock.nb3w1200l(chips)!NB3W1200L_LCC-IC,H13585-001!!!F2006!PWRGD_PWRDN_N!!!!
S!FM_DB1200_SMB_SA0!EU4D2!11!@baseboard_fab2_lib.baseboard_fab2(sch_1):page102_i1@mstr_clock.nb3w1200l(chips)!NB3W1200L_LCC-IC,H13585-001!!!F2006!SA_0!!!!
S!FM_DB1200_SMB_SA1!EU4D2!14!@baseboard_fab2_lib.baseboard_fab2(sch_1):page102_i1@mstr_clock.nb3w1200l(chips)!NB3W1200L_LCC-IC,H13585-001!!!F2006!SA_1!!!!
S!SMB_HOST_STBY_LVC3_SCL_R2!EU4D2!13!@baseboard_fab2_lib.baseboard_fab2(sch_1):page102_i1@mstr_clock.nb3w1200l(chips)!NB3W1200L_LCC-IC,H13585-001!!!F2006!SCL!!!!
S!SMB_HOST_STBY_LVC3_SDA_R2!EU4D2!12!@baseboard_fab2_lib.baseboard_fab2(sch_1):page102_i1@mstr_clock.nb3w1200l(chips)!NB3W1200L_LCC-IC,H13585-001!!!F2006!SDA!!!!
S!GND!EU4D2!65!@baseboard_fab2_lib.baseboard_fab2(sch_1):page102_i1@mstr_clock.nb3w1200l(chips)!NB3W1200L_LCC-IC,H13585-001!!!F2006!THPAD!!!!
S!P3V3_DB1200!EU4D2!24!@baseboard_fab2_lib.baseboard_fab2(sch_1):page102_i1@mstr_clock.nb3w1200l(chips)!NB3W1200L_LCC-IC,H13585-001!!!F2006!VDD(0)!!!!
S!P3V3_DB1200!EU4D2!40!@baseboard_fab2_lib.baseboard_fab2(sch_1):page102_i1@mstr_clock.nb3w1200l(chips)!NB3W1200L_LCC-IC,H13585-001!!!F2006!VDD(1)!!!!
S!P3V3_DB1200!EU4D2!57!@baseboard_fab2_lib.baseboard_fab2(sch_1):page102_i1@mstr_clock.nb3w1200l(chips)!NB3W1200L_LCC-IC,H13585-001!!!F2006!VDD(2)!!!!
S!P3V3_DB1200_A!EU4D2!1!@baseboard_fab2_lib.baseboard_fab2(sch_1):page102_i1@mstr_clock.nb3w1200l(chips)!NB3W1200L_LCC-IC,H13585-001!!!F2006!VDDA!!!!
S!P3V3_DB1200!EU4D2!25!@baseboard_fab2_lib.baseboard_fab2(sch_1):page102_i1@mstr_clock.nb3w1200l(chips)!NB3W1200L_LCC-IC,H13585-001!!!F2006!VDDIO(0)!!!!
S!P3V3_DB1200!EU4D2!32!@baseboard_fab2_lib.baseboard_fab2(sch_1):page102_i1@mstr_clock.nb3w1200l(chips)!NB3W1200L_LCC-IC,H13585-001!!!F2006!VDDIO(1)!!!!
S!P3V3_DB1200!EU4D2!49!@baseboard_fab2_lib.baseboard_fab2(sch_1):page102_i1@mstr_clock.nb3w1200l(chips)!NB3W1200L_LCC-IC,H13585-001!!!F2006!VDDIO(2)!!!!
S!P3V3_DB1200!EU4D2!56!@baseboard_fab2_lib.baseboard_fab2(sch_1):page102_i1@mstr_clock.nb3w1200l(chips)!NB3W1200L_LCC-IC,H13585-001!!!F2006!VDDIO(3)!!!!
S!P3V3_DB1200_R!EU4D2!8!@baseboard_fab2_lib.baseboard_fab2(sch_1):page102_i1@mstr_clock.nb3w1200l(chips)!NB3W1200L_LCC-IC,H13585-001!!!F2006!VDDR!!!!
S!FM_POST_CARD_PRES_BMC_N!Q1L4!6!@baseboard_fab2_lib.baseboard_fab2(sch_1):page168_i19@mstr_discrete.fet_n_dual(chips)!FET_N_DUAL_SMLF-2N7002DW,FET,DA!1!!F2180!DRAIN(0)!!!!
S!FM_DB_PRESENT!Q1L4!2!@baseboard_fab2_lib.baseboard_fab2(sch_1):page168_i19@mstr_discrete.fet_n_dual(chips)!FET_N_DUAL_SMLF-2N7002DW,FET,DA!1!!F2180!GATE(0)!!!!
S!GND!Q1L4!1!@baseboard_fab2_lib.baseboard_fab2(sch_1):page168_i19@mstr_discrete.fet_n_dual(chips)!FET_N_DUAL_SMLF-2N7002DW,FET,DA!1!!F2180!SOURCE(0)!!!!
S!TP_FET_Q56_3!Q1L4!3!@baseboard_fab2_lib.baseboard_fab2(sch_1):page168_i18@mstr_discrete.fet_n_dual(chips)!FET_N_DUAL_SMLF-2N7002DW,FET,DA!1!!F2179!DRAIN(0)!!!!
S!TP_FET_Q56_4!Q1L4!5!@baseboard_fab2_lib.baseboard_fab2(sch_1):page168_i18@mstr_discrete.fet_n_dual(chips)!FET_N_DUAL_SMLF-2N7002DW,FET,DA!1!!F2179!GATE(0)!!!!
S!TP_FET_Q56_4!Q1L4!4!@baseboard_fab2_lib.baseboard_fab2(sch_1):page168_i18@mstr_discrete.fet_n_dual(chips)!FET_N_DUAL_SMLF-2N7002DW,FET,DA!1!!F2179!SOURCE(0)!!!!
S!A_HSC_ISET_S2!Q1D1!6!@baseboard_fab2_lib.baseboard_fab2(sch_1):page199_i86@mstr_discrete.fet_n_dual(chips)!FET_N_DUAL_SMLF-2N7002DW,FET,DA!1!!F2182!DRAIN(0)!!!!
S!A_HSC_LOW_EN!Q1D1!2!@baseboard_fab2_lib.baseboard_fab2(sch_1):page199_i86@mstr_discrete.fet_n_dual(chips)!FET_N_DUAL_SMLF-2N7002DW,FET,DA!1!!F2182!GATE(0)!!!!
S!AGND_HSC!Q1D1!1!@baseboard_fab2_lib.baseboard_fab2(sch_1):page199_i86@mstr_discrete.fet_n_dual(chips)!FET_N_DUAL_SMLF-2N7002DW,FET,DA!1!!F2182!SOURCE(0)!!!!
S!A_HSC_ISET_S!Q1D1!3!@baseboard_fab2_lib.baseboard_fab2(sch_1):page199_i82@mstr_discrete.fet_n_dual(chips)!FET_N_DUAL_SMLF-2N7002DW,FET,DA!1!!F2181!DRAIN(0)!!!!
S!A_HSC_HIGH_EN!Q1D1!5!@baseboard_fab2_lib.baseboard_fab2(sch_1):page199_i82@mstr_discrete.fet_n_dual(chips)!FET_N_DUAL_SMLF-2N7002DW,FET,DA!1!!F2181!GATE(0)!!!!
S!AGND_HSC!Q1D1!4!@baseboard_fab2_lib.baseboard_fab2(sch_1):page199_i82@mstr_discrete.fet_n_dual(chips)!FET_N_DUAL_SMLF-2N7002DW,FET,DA!1!!F2181!SOURCE(0)!!!!
S!A_HSC_LOW_DRAIN!Q9P1!6!@baseboard_fab2_lib.baseboard_fab2(sch_1):page200_i196@mstr_discrete.fet_n_dual(chips)!FET_N_DUAL_SMLF-2N7002DW,FET,DA!1!!F2178!DRAIN(0)!!!!
S!A_HSC_LOW_GATE!Q9P1!2!@baseboard_fab2_lib.baseboard_fab2(sch_1):page200_i196@mstr_discrete.fet_n_dual(chips)!FET_N_DUAL_SMLF-2N7002DW,FET,DA!1!!F2178!GATE(0)!!!!
S!GND!Q9P1!1!@baseboard_fab2_lib.baseboard_fab2(sch_1):page200_i196@mstr_discrete.fet_n_dual(chips)!FET_N_DUAL_SMLF-2N7002DW,FET,DA!1!!F2178!SOURCE(0)!!!!
S!IRQ_UV_DETECT_N!Q9P1!3!@baseboard_fab2_lib.baseboard_fab2(sch_1):page200_i199@mstr_discrete.fet_n_dual(chips)!FET_N_DUAL_SMLF-2N7002DW,FET,DA!1!!F2177!DRAIN(0)!!!!
S!A_P12V_STBY_FPH_GATE!Q9P1!5!@baseboard_fab2_lib.baseboard_fab2(sch_1):page200_i199@mstr_discrete.fet_n_dual(chips)!FET_N_DUAL_SMLF-2N7002DW,FET,DA!1!!F2177!GATE(0)!!!!
S!GND!Q9P1!4!@baseboard_fab2_lib.baseboard_fab2(sch_1):page200_i199@mstr_discrete.fet_n_dual(chips)!FET_N_DUAL_SMLF-2N7002DW,FET,DA!1!!F2177!SOURCE(0)!!!!
S!VR_PVNN_PCH_XADDR2!R8A2!1!@baseboard_fab2_lib.baseboard_fab2(sch_1):page235_i217@mstr_discrete.res(chips)!RES_0402-2.67K,1%,1/16W,CHIP,GA!!!F995!A!!!!
S!GND!R8A2!2!@baseboard_fab2_lib.baseboard_fab2(sch_1):page235_i217@mstr_discrete.res(chips)!RES_0402-2.67K,1%,1/16W,CHIP,GA!!!F995!B!!!!
S!GND!J8A2!A3!@baseboard_fab2_lib.baseboard_fab2(sch_1):page174_i26@mstr_conn.conn36_g97614001(chips)!CONN36_G97614001_CP-CONN,G9761A!!!F2251!GND1!!!!
S!GND!J8A2!D3!@baseboard_fab2_lib.baseboard_fab2(sch_1):page174_i26@mstr_conn.conn36_g97614001(chips)!CONN36_G97614001_CP-CONN,G9761A!!!F2251!GND10!!!!
S!GND!J8A2!D6!@baseboard_fab2_lib.baseboard_fab2(sch_1):page174_i26@mstr_conn.conn36_g97614001(chips)!CONN36_G97614001_CP-CONN,G9761A!!!F2251!GND11!!!!
S!GND!J8A2!D9!@baseboard_fab2_lib.baseboard_fab2(sch_1):page174_i26@mstr_conn.conn36_g97614001(chips)!CONN36_G97614001_CP-CONN,G9761A!!!F2251!GND12!!!!
S!GND!J8A2!A6!@baseboard_fab2_lib.baseboard_fab2(sch_1):page174_i26@mstr_conn.conn36_g97614001(chips)!CONN36_G97614001_CP-CONN,G9761A!!!F2251!GND2!!!!
S!GND!J8A2!A9!@baseboard_fab2_lib.baseboard_fab2(sch_1):page174_i26@mstr_conn.conn36_g97614001(chips)!CONN36_G97614001_CP-CONN,G9761A!!!F2251!GND3!!!!
S!GND!J8A2!B3!@baseboard_fab2_lib.baseboard_fab2(sch_1):page174_i26@mstr_conn.conn36_g97614001(chips)!CONN36_G97614001_CP-CONN,G9761A!!!F2251!GND4!!!!
S!GND!J8A2!B6!@baseboard_fab2_lib.baseboard_fab2(sch_1):page174_i26@mstr_conn.conn36_g97614001(chips)!CONN36_G97614001_CP-CONN,G9761A!!!F2251!GND5!!!!
S!GND!J8A2!B9!@baseboard_fab2_lib.baseboard_fab2(sch_1):page174_i26@mstr_conn.conn36_g97614001(chips)!CONN36_G97614001_CP-CONN,G9761A!!!F2251!GND6!!!!
S!GND!J8A2!C3!@baseboard_fab2_lib.baseboard_fab2(sch_1):page174_i26@mstr_conn.conn36_g97614001(chips)!CONN36_G97614001_CP-CONN,G9761A!!!F2251!GND7!!!!
S!GND!J8A2!C6!@baseboard_fab2_lib.baseboard_fab2(sch_1):page174_i26@mstr_conn.conn36_g97614001(chips)!CONN36_G97614001_CP-CONN,G9761A!!!F2251!GND8!!!!
S!GND!J8A2!C9!@baseboard_fab2_lib.baseboard_fab2(sch_1):page174_i26@mstr_conn.conn36_g97614001(chips)!CONN36_G97614001_CP-CONN,G9761A!!!F2251!GND9!!!!
S!SATA6G_P8_RX_C_DN!J8A2!B5!@baseboard_fab2_lib.baseboard_fab2(sch_1):page174_i26@mstr_conn.conn36_g97614001(chips)!CONN36_G97614001_CP-CONN,G9761A!!!F2251!RXA0_DN!!!!
S!SATA6G_P8_RX_C_DP!J8A2!B4!@baseboard_fab2_lib.baseboard_fab2(sch_1):page174_i26@mstr_conn.conn36_g97614001(chips)!CONN36_G97614001_CP-CONN,G9761A!!!F2251!RXA0_DP!!!!
S!SATA6G_P9_RX_C_DN!J8A2!A5!@baseboard_fab2_lib.baseboard_fab2(sch_1):page174_i26@mstr_conn.conn36_g97614001(chips)!CONN36_G97614001_CP-CONN,G9761A!!!F2251!RXA1_DN!!!!
S!SATA6G_P9_RX_C_DP!J8A2!A4!@baseboard_fab2_lib.baseboard_fab2(sch_1):page174_i26@mstr_conn.conn36_g97614001(chips)!CONN36_G97614001_CP-CONN,G9761A!!!F2251!RXA1_DP!!!!
S!SATA6G_P10_RX_C_DN!J8A2!B8!@baseboard_fab2_lib.baseboard_fab2(sch_1):page174_i26@mstr_conn.conn36_g97614001(chips)!CONN36_G97614001_CP-CONN,G9761A!!!F2251!RXA2_DN!!!!
S!SATA6G_P10_RX_C_DP!J8A2!B7!@baseboard_fab2_lib.baseboard_fab2(sch_1):page174_i26@mstr_conn.conn36_g97614001(chips)!CONN36_G97614001_CP-CONN,G9761A!!!F2251!RXA2_DP!!!!
S!SATA6G_P11_RX_C_DN!J8A2!A8!@baseboard_fab2_lib.baseboard_fab2(sch_1):page174_i26@mstr_conn.conn36_g97614001(chips)!CONN36_G97614001_CP-CONN,G9761A!!!F2251!RXA3_DN!!!!
S!SATA6G_P11_RX_C_DP!J8A2!A7!@baseboard_fab2_lib.baseboard_fab2(sch_1):page174_i26@mstr_conn.conn36_g97614001(chips)!CONN36_G97614001_CP-CONN,G9761A!!!F2251!RXA3_DP!!!!
S!SGPIO_PCH_SSATA_CLOCK_R!J8A2!A2!@baseboard_fab2_lib.baseboard_fab2(sch_1):page174_i26@mstr_conn.conn36_g97614001(chips)!CONN36_G97614001_CP-CONN,G9761A!!!F2251!SIDEBAND0!!!!
S!SGPIO_PCH_SSATA_LOAD_R!J8A2!B2!@baseboard_fab2_lib.baseboard_fab2(sch_1):page174_i26@mstr_conn.conn36_g97614001(chips)!CONN36_G97614001_CP-CONN,G9761A!!!F2251!SIDEBAND1!!!!
S!GND!J8A2!C2!@baseboard_fab2_lib.baseboard_fab2(sch_1):page174_i26@mstr_conn.conn36_g97614001(chips)!CONN36_G97614001_CP-CONN,G9761A!!!F2251!SIDEBAND2!!!!
S!GND!J8A2!B1!@baseboard_fab2_lib.baseboard_fab2(sch_1):page174_i26@mstr_conn.conn36_g97614001(chips)!CONN36_G97614001_CP-CONN,G9761A!!!F2251!SIDEBAND3!!!!
S!SGPIO_PCH_SSATA_DOUT0_R!J8A2!C1!@baseboard_fab2_lib.baseboard_fab2(sch_1):page174_i26@mstr_conn.conn36_g97614001(chips)!CONN36_G97614001_CP-CONN,G9761A!!!F2251!SIDEBAND4!!!!
S!PU_DATAIN1_SATA_2!J8A2!D1!@baseboard_fab2_lib.baseboard_fab2(sch_1):page174_i26@mstr_conn.conn36_g97614001(chips)!CONN36_G97614001_CP-CONN,G9761A!!!F2251!SIDEBAND5!!!!
S!PD_SATA2_CONTROLLER_TYPE!J8A2!D2!@baseboard_fab2_lib.baseboard_fab2(sch_1):page174_i26@mstr_conn.conn36_g97614001(chips)!CONN36_G97614001_CP-CONN,G9761A!!!F2251!SIDEBAND6!!!!
S!TP_FM_QAT_CBL_PRSNT2_N!J8A2!A1!@baseboard_fab2_lib.baseboard_fab2(sch_1):page174_i26@mstr_conn.conn36_g97614001(chips)!CONN36_G97614001_CP-CONN,G9761A!!!F2251!SIDEBAND7!!!!
S!SATA6G_P8_TX_C_DN!J8A2!D5!@baseboard_fab2_lib.baseboard_fab2(sch_1):page174_i26@mstr_conn.conn36_g97614001(chips)!CONN36_G97614001_CP-CONN,G9761A!!!F2251!TXA0_DN!!!!
S!SATA6G_P8_TX_C_DP!J8A2!D4!@baseboard_fab2_lib.baseboard_fab2(sch_1):page174_i26@mstr_conn.conn36_g97614001(chips)!CONN36_G97614001_CP-CONN,G9761A!!!F2251!TXA0_DP!!!!
S!SATA6G_P9_TX_C_DN!J8A2!C5!@baseboard_fab2_lib.baseboard_fab2(sch_1):page174_i26@mstr_conn.conn36_g97614001(chips)!CONN36_G97614001_CP-CONN,G9761A!!!F2251!TXA1_DN!!!!
S!SATA6G_P9_TX_C_DP!J8A2!C4!@baseboard_fab2_lib.baseboard_fab2(sch_1):page174_i26@mstr_conn.conn36_g97614001(chips)!CONN36_G97614001_CP-CONN,G9761A!!!F2251!TXA1_DP!!!!
S!SATA6G_P10_TX_C_DN!J8A2!D8!@baseboard_fab2_lib.baseboard_fab2(sch_1):page174_i26@mstr_conn.conn36_g97614001(chips)!CONN36_G97614001_CP-CONN,G9761A!!!F2251!TXA2_DN!!!!
S!SATA6G_P10_TX_C_DP!J8A2!D7!@baseboard_fab2_lib.baseboard_fab2(sch_1):page174_i26@mstr_conn.conn36_g97614001(chips)!CONN36_G97614001_CP-CONN,G9761A!!!F2251!TXA2_DP!!!!
S!SATA6G_P11_TX_C_DN!J8A2!C8!@baseboard_fab2_lib.baseboard_fab2(sch_1):page174_i26@mstr_conn.conn36_g97614001(chips)!CONN36_G97614001_CP-CONN,G9761A!!!F2251!TXA3_DN!!!!
S!SATA6G_P11_TX_C_DP!J8A2!C7!@baseboard_fab2_lib.baseboard_fab2(sch_1):page174_i26@mstr_conn.conn36_g97614001(chips)!CONN36_G97614001_CP-CONN,G9761A!!!F2251!TXA3_DP!!!!
S!GND!J8A1!2D9!@baseboard_fab2_lib.baseboard_fab2(sch_1):page173_i163@mstr_conn.conn72_g97614002_a(chips)!CONN72_G97614002_A_CP-CONN,G97A!!!F2240!GND(0)!!!!
S!GND!J8A1!2A6!@baseboard_fab2_lib.baseboard_fab2(sch_1):page173_i163@mstr_conn.conn72_g97614002_a(chips)!CONN72_G97614002_A_CP-CONN,G97A!!!F2240!GND(10)!!!!
S!GND!J8A1!2A3!@baseboard_fab2_lib.baseboard_fab2(sch_1):page173_i163@mstr_conn.conn72_g97614002_a(chips)!CONN72_G97614002_A_CP-CONN,G97A!!!F2240!GND(11)!!!!
S!GND!J8A1!1D9!@baseboard_fab2_lib.baseboard_fab2(sch_1):page173_i163@mstr_conn.conn72_g97614002_a(chips)!CONN72_G97614002_A_CP-CONN,G97A!!!F2240!GND(12)!!!!
S!GND!J8A1!1D6!@baseboard_fab2_lib.baseboard_fab2(sch_1):page173_i163@mstr_conn.conn72_g97614002_a(chips)!CONN72_G97614002_A_CP-CONN,G97A!!!F2240!GND(13)!!!!
S!GND!J8A1!1D3!@baseboard_fab2_lib.baseboard_fab2(sch_1):page173_i163@mstr_conn.conn72_g97614002_a(chips)!CONN72_G97614002_A_CP-CONN,G97A!!!F2240!GND(14)!!!!
S!GND!J8A1!1C9!@baseboard_fab2_lib.baseboard_fab2(sch_1):page173_i163@mstr_conn.conn72_g97614002_a(chips)!CONN72_G97614002_A_CP-CONN,G97A!!!F2240!GND(15)!!!!
S!GND!J8A1!1C6!@baseboard_fab2_lib.baseboard_fab2(sch_1):page173_i163@mstr_conn.conn72_g97614002_a(chips)!CONN72_G97614002_A_CP-CONN,G97A!!!F2240!GND(16)!!!!
S!GND!J8A1!1C3!@baseboard_fab2_lib.baseboard_fab2(sch_1):page173_i163@mstr_conn.conn72_g97614002_a(chips)!CONN72_G97614002_A_CP-CONN,G97A!!!F2240!GND(17)!!!!
S!GND!J8A1!1B9!@baseboard_fab2_lib.baseboard_fab2(sch_1):page173_i163@mstr_conn.conn72_g97614002_a(chips)!CONN72_G97614002_A_CP-CONN,G97A!!!F2240!GND(18)!!!!
S!GND!J8A1!1B6!@baseboard_fab2_lib.baseboard_fab2(sch_1):page173_i163@mstr_conn.conn72_g97614002_a(chips)!CONN72_G97614002_A_CP-CONN,G97A!!!F2240!GND(19)!!!!
S!GND!J8A1!2D6!@baseboard_fab2_lib.baseboard_fab2(sch_1):page173_i163@mstr_conn.conn72_g97614002_a(chips)!CONN72_G97614002_A_CP-CONN,G97A!!!F2240!GND(1)!!!!
S!GND!J8A1!1B3!@baseboard_fab2_lib.baseboard_fab2(sch_1):page173_i163@mstr_conn.conn72_g97614002_a(chips)!CONN72_G97614002_A_CP-CONN,G97A!!!F2240!GND(20)!!!!
S!GND!J8A1!1A9!@baseboard_fab2_lib.baseboard_fab2(sch_1):page173_i163@mstr_conn.conn72_g97614002_a(chips)!CONN72_G97614002_A_CP-CONN,G97A!!!F2240!GND(21)!!!!
S!GND!J8A1!1A6!@baseboard_fab2_lib.baseboard_fab2(sch_1):page173_i163@mstr_conn.conn72_g97614002_a(chips)!CONN72_G97614002_A_CP-CONN,G97A!!!F2240!GND(22)!!!!
S!GND!J8A1!1A3!@baseboard_fab2_lib.baseboard_fab2(sch_1):page173_i163@mstr_conn.conn72_g97614002_a(chips)!CONN72_G97614002_A_CP-CONN,G97A!!!F2240!GND(23)!!!!
S!GND!J8A1!2D3!@baseboard_fab2_lib.baseboard_fab2(sch_1):page173_i163@mstr_conn.conn72_g97614002_a(chips)!CONN72_G97614002_A_CP-CONN,G97A!!!F2240!GND(2)!!!!
S!GND!J8A1!2C9!@baseboard_fab2_lib.baseboard_fab2(sch_1):page173_i163@mstr_conn.conn72_g97614002_a(chips)!CONN72_G97614002_A_CP-CONN,G97A!!!F2240!GND(3)!!!!
S!GND!J8A1!2C6!@baseboard_fab2_lib.baseboard_fab2(sch_1):page173_i163@mstr_conn.conn72_g97614002_a(chips)!CONN72_G97614002_A_CP-CONN,G97A!!!F2240!GND(4)!!!!
S!GND!J8A1!2C3!@baseboard_fab2_lib.baseboard_fab2(sch_1):page173_i163@mstr_conn.conn72_g97614002_a(chips)!CONN72_G97614002_A_CP-CONN,G97A!!!F2240!GND(5)!!!!
S!GND!J8A1!2B9!@baseboard_fab2_lib.baseboard_fab2(sch_1):page173_i163@mstr_conn.conn72_g97614002_a(chips)!CONN72_G97614002_A_CP-CONN,G97A!!!F2240!GND(6)!!!!
S!GND!J8A1!2B6!@baseboard_fab2_lib.baseboard_fab2(sch_1):page173_i163@mstr_conn.conn72_g97614002_a(chips)!CONN72_G97614002_A_CP-CONN,G97A!!!F2240!GND(7)!!!!
S!GND!J8A1!2B3!@baseboard_fab2_lib.baseboard_fab2(sch_1):page173_i163@mstr_conn.conn72_g97614002_a(chips)!CONN72_G97614002_A_CP-CONN,G97A!!!F2240!GND(8)!!!!
S!GND!J8A1!2A9!@baseboard_fab2_lib.baseboard_fab2(sch_1):page173_i163@mstr_conn.conn72_g97614002_a(chips)!CONN72_G97614002_A_CP-CONN,G97A!!!F2240!GND(9)!!!!
S!SATA6G_P0_RX_C_DN!J8A1!1B5!@baseboard_fab2_lib.baseboard_fab2(sch_1):page173_i163@mstr_conn.conn72_g97614002_a(chips)!CONN72_G97614002_A_CP-CONN,G97A!!!F2240!RXA0_DN!!!!
S!SATA6G_P0_RX_C_DP!J8A1!1B4!@baseboard_fab2_lib.baseboard_fab2(sch_1):page173_i163@mstr_conn.conn72_g97614002_a(chips)!CONN72_G97614002_A_CP-CONN,G97A!!!F2240!RXA0_DP!!!!
S!SATA6G_P1_RX_C_DN!J8A1!1A5!@baseboard_fab2_lib.baseboard_fab2(sch_1):page173_i163@mstr_conn.conn72_g97614002_a(chips)!CONN72_G97614002_A_CP-CONN,G97A!!!F2240!RXA1_DN!!!!
S!SATA6G_P1_RX_C_DP!J8A1!1A4!@baseboard_fab2_lib.baseboard_fab2(sch_1):page173_i163@mstr_conn.conn72_g97614002_a(chips)!CONN72_G97614002_A_CP-CONN,G97A!!!F2240!RXA1_DP!!!!
S!SATA6G_P2_RX_C_DN!J8A1!1B8!@baseboard_fab2_lib.baseboard_fab2(sch_1):page173_i163@mstr_conn.conn72_g97614002_a(chips)!CONN72_G97614002_A_CP-CONN,G97A!!!F2240!RXA2_DN!!!!
S!SATA6G_P2_RX_C_DP!J8A1!1B7!@baseboard_fab2_lib.baseboard_fab2(sch_1):page173_i163@mstr_conn.conn72_g97614002_a(chips)!CONN72_G97614002_A_CP-CONN,G97A!!!F2240!RXA2_DP!!!!
S!SATA6G_P3_RX_C_DN!J8A1!1A8!@baseboard_fab2_lib.baseboard_fab2(sch_1):page173_i163@mstr_conn.conn72_g97614002_a(chips)!CONN72_G97614002_A_CP-CONN,G97A!!!F2240!RXA3_DN!!!!
S!SATA6G_P3_RX_C_DP!J8A1!1A7!@baseboard_fab2_lib.baseboard_fab2(sch_1):page173_i163@mstr_conn.conn72_g97614002_a(chips)!CONN72_G97614002_A_CP-CONN,G97A!!!F2240!RXA3_DP!!!!
S!SATA6G_P4_RX_C_DN!J8A1!2B5!@baseboard_fab2_lib.baseboard_fab2(sch_1):page173_i163@mstr_conn.conn72_g97614002_a(chips)!CONN72_G97614002_A_CP-CONN,G97A!!!F2240!RXB0_DN!!!!
S!SATA6G_P4_RX_C_DP!J8A1!2B4!@baseboard_fab2_lib.baseboard_fab2(sch_1):page173_i163@mstr_conn.conn72_g97614002_a(chips)!CONN72_G97614002_A_CP-CONN,G97A!!!F2240!RXB0_DP!!!!
S!SATA6G_P5_RX_C_DN!J8A1!2A5!@baseboard_fab2_lib.baseboard_fab2(sch_1):page173_i163@mstr_conn.conn72_g97614002_a(chips)!CONN72_G97614002_A_CP-CONN,G97A!!!F2240!RXB1_DN!!!!
S!SATA6G_P5_RX_C_DP!J8A1!2A4!@baseboard_fab2_lib.baseboard_fab2(sch_1):page173_i163@mstr_conn.conn72_g97614002_a(chips)!CONN72_G97614002_A_CP-CONN,G97A!!!F2240!RXB1_DP!!!!
S!SATA6G_P6_RX_C_DN!J8A1!2B8!@baseboard_fab2_lib.baseboard_fab2(sch_1):page173_i163@mstr_conn.conn72_g97614002_a(chips)!CONN72_G97614002_A_CP-CONN,G97A!!!F2240!RXB2_DN!!!!
S!SATA6G_P6_RX_C_DP!J8A1!2B7!@baseboard_fab2_lib.baseboard_fab2(sch_1):page173_i163@mstr_conn.conn72_g97614002_a(chips)!CONN72_G97614002_A_CP-CONN,G97A!!!F2240!RXB2_DP!!!!
S!SATA6G_P7_RX_C_DN!J8A1!2A8!@baseboard_fab2_lib.baseboard_fab2(sch_1):page173_i163@mstr_conn.conn72_g97614002_a(chips)!CONN72_G97614002_A_CP-CONN,G97A!!!F2240!RXB3_DN!!!!
S!SATA6G_P7_RX_C_DP!J8A1!2A7!@baseboard_fab2_lib.baseboard_fab2(sch_1):page173_i163@mstr_conn.conn72_g97614002_a(chips)!CONN72_G97614002_A_CP-CONN,G97A!!!F2240!RXB3_DP!!!!
S!SGPIO_PCH_SATA_CLOCK_R!J8A1!1A2!@baseboard_fab2_lib.baseboard_fab2(sch_1):page173_i163@mstr_conn.conn72_g97614002_a(chips)!CONN72_G97614002_A_CP-CONN,G97A!!!F2240!SIDEBANDA_0!!!!
S!SGPIO_PCH_SATA_LOAD_R!J8A1!1B2!@baseboard_fab2_lib.baseboard_fab2(sch_1):page173_i163@mstr_conn.conn72_g97614002_a(chips)!CONN72_G97614002_A_CP-CONN,G97A!!!F2240!SIDEBANDA_1!!!!
S!GND!J8A1!1C2!@baseboard_fab2_lib.baseboard_fab2(sch_1):page173_i163@mstr_conn.conn72_g97614002_a(chips)!CONN72_G97614002_A_CP-CONN,G97A!!!F2240!SIDEBANDA_2!!!!
S!GND!J8A1!1B1!@baseboard_fab2_lib.baseboard_fab2(sch_1):page173_i163@mstr_conn.conn72_g97614002_a(chips)!CONN72_G97614002_A_CP-CONN,G97A!!!F2240!SIDEBANDA_3!!!!
S!SGPIO_PCH_SATA_DOUT0_R!J8A1!1C1!@baseboard_fab2_lib.baseboard_fab2(sch_1):page173_i163@mstr_conn.conn72_g97614002_a(chips)!CONN72_G97614002_A_CP-CONN,G97A!!!F2240!SIDEBANDA_4!!!!
S!PU_DATAIN1_SATA_0_R!J8A1!1D1!@baseboard_fab2_lib.baseboard_fab2(sch_1):page173_i163@mstr_conn.conn72_g97614002_a(chips)!CONN72_G97614002_A_CP-CONN,G97A!!!F2240!SIDEBANDA_5!!!!
S!PD_SATA0_CONTROLLER_TYPE_R!J8A1!1D2!@baseboard_fab2_lib.baseboard_fab2(sch_1):page173_i163@mstr_conn.conn72_g97614002_a(chips)!CONN72_G97614002_A_CP-CONN,G97A!!!F2240!SIDEBANDA_6!!!!
S!TP_FM_QAT_CBL_PRSNT0_R_N!J8A1!1A1!@baseboard_fab2_lib.baseboard_fab2(sch_1):page173_i163@mstr_conn.conn72_g97614002_a(chips)!CONN72_G97614002_A_CP-CONN,G97A!!!F2240!SIDEBANDA_7!!!!
S!TP_SGPIO_SATA_CLOCK1_R!J8A1!2A2!@baseboard_fab2_lib.baseboard_fab2(sch_1):page173_i163@mstr_conn.conn72_g97614002_a(chips)!CONN72_G97614002_A_CP-CONN,G97A!!!F2240!SIDEBANDB_0!!!!
S!TP_SGPIO_SATA_LOAD1_R!J8A1!2B2!@baseboard_fab2_lib.baseboard_fab2(sch_1):page173_i163@mstr_conn.conn72_g97614002_a(chips)!CONN72_G97614002_A_CP-CONN,G97A!!!F2240!SIDEBANDB_1!!!!
S!GND!J8A1!2C2!@baseboard_fab2_lib.baseboard_fab2(sch_1):page173_i163@mstr_conn.conn72_g97614002_a(chips)!CONN72_G97614002_A_CP-CONN,G97A!!!F2240!SIDEBANDB_2!!!!
S!GND!J8A1!2B1!@baseboard_fab2_lib.baseboard_fab2(sch_1):page173_i163@mstr_conn.conn72_g97614002_a(chips)!CONN72_G97614002_A_CP-CONN,G97A!!!F2240!SIDEBANDB_3!!!!
S!TP_SGPIO_SATA_DATA1_R!J8A1!2C1!@baseboard_fab2_lib.baseboard_fab2(sch_1):page173_i163@mstr_conn.conn72_g97614002_a(chips)!CONN72_G97614002_A_CP-CONN,G97A!!!F2240!SIDEBANDB_4!!!!
S!PU_DATAIN1_SATA_1_R!J8A1!2D1!@baseboard_fab2_lib.baseboard_fab2(sch_1):page173_i163@mstr_conn.conn72_g97614002_a(chips)!CONN72_G97614002_A_CP-CONN,G97A!!!F2240!SIDEBANDB_5!!!!
S!PD_SATA1_CONTROLLER_TYPE_R!J8A1!2D2!@baseboard_fab2_lib.baseboard_fab2(sch_1):page173_i163@mstr_conn.conn72_g97614002_a(chips)!CONN72_G97614002_A_CP-CONN,G97A!!!F2240!SIDEBANDB_6!!!!
S!TP_FM_QAT_CBL_PRSNT1_N_R!J8A1!2A1!@baseboard_fab2_lib.baseboard_fab2(sch_1):page173_i163@mstr_conn.conn72_g97614002_a(chips)!CONN72_G97614002_A_CP-CONN,G97A!!!F2240!SIDEBANDB_7!!!!
S!SATA6G_P0_TX_C_DN!J8A1!1D5!@baseboard_fab2_lib.baseboard_fab2(sch_1):page173_i163@mstr_conn.conn72_g97614002_a(chips)!CONN72_G97614002_A_CP-CONN,G97A!!!F2240!TXA0_DN!!!!
S!SATA6G_P0_TX_C_DP!J8A1!1D4!@baseboard_fab2_lib.baseboard_fab2(sch_1):page173_i163@mstr_conn.conn72_g97614002_a(chips)!CONN72_G97614002_A_CP-CONN,G97A!!!F2240!TXA0_DP!!!!
S!SATA6G_P1_TX_C_DN!J8A1!1C5!@baseboard_fab2_lib.baseboard_fab2(sch_1):page173_i163@mstr_conn.conn72_g97614002_a(chips)!CONN72_G97614002_A_CP-CONN,G97A!!!F2240!TXA1_DN!!!!
S!SATA6G_P1_TX_C_DP!J8A1!1C4!@baseboard_fab2_lib.baseboard_fab2(sch_1):page173_i163@mstr_conn.conn72_g97614002_a(chips)!CONN72_G97614002_A_CP-CONN,G97A!!!F2240!TXA1_DP!!!!
S!SATA6G_P2_TX_C_DN!J8A1!1D8!@baseboard_fab2_lib.baseboard_fab2(sch_1):page173_i163@mstr_conn.conn72_g97614002_a(chips)!CONN72_G97614002_A_CP-CONN,G97A!!!F2240!TXA2_DN!!!!
S!SATA6G_P2_TX_C_DP!J8A1!1D7!@baseboard_fab2_lib.baseboard_fab2(sch_1):page173_i163@mstr_conn.conn72_g97614002_a(chips)!CONN72_G97614002_A_CP-CONN,G97A!!!F2240!TXA2_DP!!!!
S!SATA6G_P3_TX_C_DN!J8A1!1C8!@baseboard_fab2_lib.baseboard_fab2(sch_1):page173_i163@mstr_conn.conn72_g97614002_a(chips)!CONN72_G97614002_A_CP-CONN,G97A!!!F2240!TXA3_DN!!!!
S!SATA6G_P3_TX_C_DP!J8A1!1C7!@baseboard_fab2_lib.baseboard_fab2(sch_1):page173_i163@mstr_conn.conn72_g97614002_a(chips)!CONN72_G97614002_A_CP-CONN,G97A!!!F2240!TXA3_DP!!!!
S!SATA6G_P4_TX_C_DN!J8A1!2D5!@baseboard_fab2_lib.baseboard_fab2(sch_1):page173_i163@mstr_conn.conn72_g97614002_a(chips)!CONN72_G97614002_A_CP-CONN,G97A!!!F2240!TXB0_DN!!!!
S!SATA6G_P4_TX_C_DP!J8A1!2D4!@baseboard_fab2_lib.baseboard_fab2(sch_1):page173_i163@mstr_conn.conn72_g97614002_a(chips)!CONN72_G97614002_A_CP-CONN,G97A!!!F2240!TXB0_DP!!!!
S!SATA6G_P5_TX_C_DN!J8A1!2C5!@baseboard_fab2_lib.baseboard_fab2(sch_1):page173_i163@mstr_conn.conn72_g97614002_a(chips)!CONN72_G97614002_A_CP-CONN,G97A!!!F2240!TXB1_DN!!!!
S!SATA6G_P5_TX_C_DP!J8A1!2C4!@baseboard_fab2_lib.baseboard_fab2(sch_1):page173_i163@mstr_conn.conn72_g97614002_a(chips)!CONN72_G97614002_A_CP-CONN,G97A!!!F2240!TXB1_DP!!!!
S!SATA6G_P6_TX_C_DN!J8A1!2D8!@baseboard_fab2_lib.baseboard_fab2(sch_1):page173_i163@mstr_conn.conn72_g97614002_a(chips)!CONN72_G97614002_A_CP-CONN,G97A!!!F2240!TXB2_DN!!!!
S!SATA6G_P6_TX_C_DP!J8A1!2D7!@baseboard_fab2_lib.baseboard_fab2(sch_1):page173_i163@mstr_conn.conn72_g97614002_a(chips)!CONN72_G97614002_A_CP-CONN,G97A!!!F2240!TXB2_DP!!!!
S!SATA6G_P7_TX_C_DN!J8A1!2C8!@baseboard_fab2_lib.baseboard_fab2(sch_1):page173_i163@mstr_conn.conn72_g97614002_a(chips)!CONN72_G97614002_A_CP-CONN,G97A!!!F2240!TXB3_DN!!!!
S!SATA6G_P7_TX_C_DP!J8A1!2C7!@baseboard_fab2_lib.baseboard_fab2(sch_1):page173_i163@mstr_conn.conn72_g97614002_a(chips)!CONN72_G97614002_A_CP-CONN,G97A!!!F2240!TXB3_DP!!!!
S!SPI_CLK_R0!U7F1!16!@baseboard_fab2_lib.baseboard_fab2(sch_1):page153_i146@mstr_memory.w25q256(chips)!W25Q256_XSOI-IC,H25002-001!!!F1!CLK!!!!
S!SPI_CS0_PRIMARY_R_N!U7F1!7!@baseboard_fab2_lib.baseboard_fab2(sch_1):page153_i146@mstr_memory.w25q256(chips)!W25Q256_XSOI-IC,H25002-001!!!F1!CS_N!!!!
S!SPI_SWITCH_MOSI_R0!U7F1!15!@baseboard_fab2_lib.baseboard_fab2(sch_1):page153_i146@mstr_memory.w25q256(chips)!W25Q256_XSOI-IC,H25002-001!!!F1!DI_IO(0)!!!!
S!SPI_MISO_R0!U7F1!8!@baseboard_fab2_lib.baseboard_fab2(sch_1):page153_i146@mstr_memory.w25q256(chips)!W25Q256_XSOI-IC,H25002-001!!!F1!DO_IO(1)!!!!
S!GND!U7F1!10!@baseboard_fab2_lib.baseboard_fab2(sch_1):page153_i146@mstr_memory.w25q256(chips)!W25Q256_XSOI-IC,H25002-001!!!F1!GND!!!!
S!PU_BIOS_SPI_HOLD0_N!U7F1!1!@baseboard_fab2_lib.baseboard_fab2(sch_1):page153_i146@mstr_memory.w25q256(chips)!W25Q256_XSOI-IC,H25002-001!!!F1!HOLD_N_IO(3)!!!!
S!TP_SPI_0_6!U7F1!4!@baseboard_fab2_lib.baseboard_fab2(sch_1):page153_i146@mstr_memory.w25q256(chips)!W25Q256_XSOI-IC,H25002-001!!!F1!NC(6)!!!!
S!TP_SPI_0_5!U7F1!5!@baseboard_fab2_lib.baseboard_fab2(sch_1):page153_i146@mstr_memory.w25q256(chips)!W25Q256_XSOI-IC,H25002-001!!!F1!NC(5)!!!!
S!TP_SPI_0_4!U7F1!6!@baseboard_fab2_lib.baseboard_fab2(sch_1):page153_i146@mstr_memory.w25q256(chips)!W25Q256_XSOI-IC,H25002-001!!!F1!NC(4)!!!!
S!TP_SPI_0_3!U7F1!11!@baseboard_fab2_lib.baseboard_fab2(sch_1):page153_i146@mstr_memory.w25q256(chips)!W25Q256_XSOI-IC,H25002-001!!!F1!NC(3)!!!!
S!TP_SPI_0_2!U7F1!12!@baseboard_fab2_lib.baseboard_fab2(sch_1):page153_i146@mstr_memory.w25q256(chips)!W25Q256_XSOI-IC,H25002-001!!!F1!NC(2)!!!!
S!TP_SPI_0_1!U7F1!13!@baseboard_fab2_lib.baseboard_fab2(sch_1):page153_i146@mstr_memory.w25q256(chips)!W25Q256_XSOI-IC,H25002-001!!!F1!NC(1)!!!!
S!TP_SPI_0_0!U7F1!14!@baseboard_fab2_lib.baseboard_fab2(sch_1):page153_i146@mstr_memory.w25q256(chips)!W25Q256_XSOI-IC,H25002-001!!!F1!NC(0)!!!!
S!PU_SPI0_RST!U7F1!3!@baseboard_fab2_lib.baseboard_fab2(sch_1):page153_i146@mstr_memory.w25q256(chips)!W25Q256_XSOI-IC,H25002-001!!!F1!RESET_N!!!!
S!P3V3_STBY!U7F1!2!@baseboard_fab2_lib.baseboard_fab2(sch_1):page153_i146@mstr_memory.w25q256(chips)!W25Q256_XSOI-IC,H25002-001!!!F1!VCC!!!!
S!PU_BIOS_SPI_WP0_N!U7F1!9!@baseboard_fab2_lib.baseboard_fab2(sch_1):page153_i146@mstr_memory.w25q256(chips)!W25Q256_XSOI-IC,H25002-001!!!F1!WP_N_IO(2)!!!!
S!SPI_CLK_R1!U3T1!16!@baseboard_fab2_lib.baseboard_fab2(sch_1):page153_i165@mstr_memory.w25q256(chips)!W25Q256_XSOI-IC,H25002-001!!!F2!CLK!!!!
S!SPI_CS0_SECONDARY_R_N!U3T1!7!@baseboard_fab2_lib.baseboard_fab2(sch_1):page153_i165@mstr_memory.w25q256(chips)!W25Q256_XSOI-IC,H25002-001!!!F2!CS_N!!!!
S!SPI_SWITCH_MOSI_R1!U3T1!15!@baseboard_fab2_lib.baseboard_fab2(sch_1):page153_i165@mstr_memory.w25q256(chips)!W25Q256_XSOI-IC,H25002-001!!!F2!DI_IO(0)!!!!
S!SPI_MISO_R1!U3T1!8!@baseboard_fab2_lib.baseboard_fab2(sch_1):page153_i165@mstr_memory.w25q256(chips)!W25Q256_XSOI-IC,H25002-001!!!F2!DO_IO(1)!!!!
S!GND!U3T1!10!@baseboard_fab2_lib.baseboard_fab2(sch_1):page153_i165@mstr_memory.w25q256(chips)!W25Q256_XSOI-IC,H25002-001!!!F2!GND!!!!
S!PU_BIOS_SPI_HOLD1_N!U3T1!1!@baseboard_fab2_lib.baseboard_fab2(sch_1):page153_i165@mstr_memory.w25q256(chips)!W25Q256_XSOI-IC,H25002-001!!!F2!HOLD_N_IO(3)!!!!
S!TP_SPI_1_6!U3T1!4!@baseboard_fab2_lib.baseboard_fab2(sch_1):page153_i165@mstr_memory.w25q256(chips)!W25Q256_XSOI-IC,H25002-001!!!F2!NC(6)!!!!
S!TP_SPI_1_5!U3T1!5!@baseboard_fab2_lib.baseboard_fab2(sch_1):page153_i165@mstr_memory.w25q256(chips)!W25Q256_XSOI-IC,H25002-001!!!F2!NC(5)!!!!
S!TP_SPI_1_4!U3T1!6!@baseboard_fab2_lib.baseboard_fab2(sch_1):page153_i165@mstr_memory.w25q256(chips)!W25Q256_XSOI-IC,H25002-001!!!F2!NC(4)!!!!
S!TP_SPI_1_3!U3T1!11!@baseboard_fab2_lib.baseboard_fab2(sch_1):page153_i165@mstr_memory.w25q256(chips)!W25Q256_XSOI-IC,H25002-001!!!F2!NC(3)!!!!
S!TP_SPI_1_2!U3T1!12!@baseboard_fab2_lib.baseboard_fab2(sch_1):page153_i165@mstr_memory.w25q256(chips)!W25Q256_XSOI-IC,H25002-001!!!F2!NC(2)!!!!
S!TP_SPI_1_1!U3T1!13!@baseboard_fab2_lib.baseboard_fab2(sch_1):page153_i165@mstr_memory.w25q256(chips)!W25Q256_XSOI-IC,H25002-001!!!F2!NC(1)!!!!
S!TP_SPI_1_0!U3T1!14!@baseboard_fab2_lib.baseboard_fab2(sch_1):page153_i165@mstr_memory.w25q256(chips)!W25Q256_XSOI-IC,H25002-001!!!F2!NC(0)!!!!
S!PU_SPI1_RST!U3T1!3!@baseboard_fab2_lib.baseboard_fab2(sch_1):page153_i165@mstr_memory.w25q256(chips)!W25Q256_XSOI-IC,H25002-001!!!F2!RESET_N!!!!
S!P3V3_STBY!U3T1!2!@baseboard_fab2_lib.baseboard_fab2(sch_1):page153_i165@mstr_memory.w25q256(chips)!W25Q256_XSOI-IC,H25002-001!!!F2!VCC!!!!
S!PU_BIOS_SPI_WP1_N!U3T1!9!@baseboard_fab2_lib.baseboard_fab2(sch_1):page153_i165@mstr_memory.w25q256(chips)!W25Q256_XSOI-IC,H25002-001!!!F2!WP_N_IO(2)!!!!
S!P5V_STBY!R1L8!1!@baseboard_fab2_lib.baseboard_fab2(sch_1):page175_i58@mstr_discrete.res(chips)!RES_0402-470.0,5%,1/16W,CHIP,GA!!!F468!A!!!!
S!FP_ID_LED_XOR_R!R1L8!2!@baseboard_fab2_lib.baseboard_fab2(sch_1):page175_i58@mstr_discrete.res(chips)!RES_0402-470.0,5%,1/16W,CHIP,GA!!!F468!B!!!!
S!GND!U2R1!2!!TTL2G14_SMLF-74LVC2G14,IC,D184B!!!!!!!!
S!P3V3_STBY!U2R1!5!!TTL2G14_SMLF-74LVC2G14,IC,D184B!!!!!!!!
S!FP_NMI_BTN!U2R1!1!@baseboard_fab2_lib.baseboard_fab2(sch_1):page157_i357@mstr_ttl.ttl2g14(chips)!TTL2G14_SMLF-74LVC2G14,IC,D184B!1!!F18!A(0)!!!!
S!FP_NMI_BTN_R_N!U2R1!6!@baseboard_fab2_lib.baseboard_fab2(sch_1):page157_i357@mstr_ttl.ttl2g14(chips)!TTL2G14_SMLF-74LVC2G14,IC,D184B!1!!F18!Y(0)!!!!
S!FP_NMI_BTN_OUT_N!U2R1!3!@baseboard_fab2_lib.baseboard_fab2(sch_1):page157_i356@mstr_ttl.ttl2g14(chips)!TTL2G14_SMLF-74LVC2G14,IC,D184B!1!!F17!A(0)!!!!
S!FP_NMI_BTN!U2R1!4!@baseboard_fab2_lib.baseboard_fab2(sch_1):page157_i356@mstr_ttl.ttl2g14(chips)!TTL2G14_SMLF-74LVC2G14,IC,D184B!1!!F17!Y(0)!!!!
S!GND!U9A4!2!!TTL2G14_SMLF-74LVC2G14,IC,D184B!!!!!!!!
S!P3V3_STBY!U9A4!5!!TTL2G14_SMLF-74LVC2G14,IC,D184B!!!!!!!!
S!FP_PWR_BTN_R1_N!U9A4!1!@baseboard_fab2_lib.baseboard_fab2(sch_1):page175_i9@mstr_ttl.ttl2g14(chips)!TTL2G14_SMLF-74LVC2G14,IC,D184B!1!!F14!A(0)!!!!
S!FP_PWR_BTN_BUF1_N!U9A4!6!@baseboard_fab2_lib.baseboard_fab2(sch_1):page175_i9@mstr_ttl.ttl2g14(chips)!TTL2G14_SMLF-74LVC2G14,IC,D184B!1!!F14!Y(0)!!!!
S!FP_PWR_BTN_BUF1_N!U9A4!3!@baseboard_fab2_lib.baseboard_fab2(sch_1):page175_i10@mstr_ttl.ttl2g14(chips)!TTL2G14_SMLF-74LVC2G14,IC,D184B!1!!F13!A(0)!!!!
S!FM_PWR_BTN_R_N!U9A4!4!@baseboard_fab2_lib.baseboard_fab2(sch_1):page175_i10@mstr_ttl.ttl2g14(chips)!TTL2G14_SMLF-74LVC2G14,IC,D184B!1!!F13!Y(0)!!!!
S!GND!U9A3!2!!TTL2G14_SMLF-74LVC2G14,IC,D184B!!!!!!!!
S!P3V3_STBY!U9A3!5!!TTL2G14_SMLF-74LVC2G14,IC,D184B!!!!!!!!
S!FP_RST_BTN_R_N!U9A3!1!@baseboard_fab2_lib.baseboard_fab2(sch_1):page175_i18@mstr_ttl.ttl2g14(chips)!TTL2G14_SMLF-74LVC2G14,IC,D184B!1!!F16!A(0)!!!!
S!FP_RST_BTN_BUF1_N!U9A3!6!@baseboard_fab2_lib.baseboard_fab2(sch_1):page175_i18@mstr_ttl.ttl2g14(chips)!TTL2G14_SMLF-74LVC2G14,IC,D184B!1!!F16!Y(0)!!!!
S!FP_RST_BTN_BUF1_N!U9A3!3!@baseboard_fab2_lib.baseboard_fab2(sch_1):page175_i15@mstr_ttl.ttl2g14(chips)!TTL2G14_SMLF-74LVC2G14,IC,D184B!1!!F15!A(0)!!!!
S!RST_SYSTEM_BTN_BUF_N!U9A3!4!@baseboard_fab2_lib.baseboard_fab2(sch_1):page175_i15@mstr_ttl.ttl2g14(chips)!TTL2G14_SMLF-74LVC2G14,IC,D184B!1!!F15!Y(0)!!!!
S!P3V3_STBY!U8G1!5!!TTL2G07_SOT23LF-74LVC2G07,IC,DB!!!!!!!!
S!GND!U8G1!2!!TTL2G07_SOT23LF-74LVC2G07,IC,DB!!!!!!!!
S!RST_PCH_SYSRST_BTN_OUT_N!U8G1!1!@baseboard_fab2_lib.baseboard_fab2(sch_1):page156_i269@mstr_ttl.ttl2g07(chips)!TTL2G07_SOT23LF-74LVC2G07,IC,DB!!!F19!\1a\!!!!
S!RST_BMC_SYSRST_BTN_OUT_B_R_N!U8G1!6!@baseboard_fab2_lib.baseboard_fab2(sch_1):page156_i269@mstr_ttl.ttl2g07(chips)!TTL2G07_SOT23LF-74LVC2G07,IC,DB!!!F19!\1y\!!!!
S!FM_PCH_PWRBTN_OUT_N!U8G1!3!@baseboard_fab2_lib.baseboard_fab2(sch_1):page156_i269@mstr_ttl.ttl2g07(chips)!TTL2G07_SOT23LF-74LVC2G07,IC,DB!!!F19!\2a\!!!!
S!FM_PCH_PWRBTN_R_N!U8G1!4!@baseboard_fab2_lib.baseboard_fab2(sch_1):page156_i269@mstr_ttl.ttl2g07(chips)!TTL2G07_SOT23LF-74LVC2G07,IC,DB!!!F19!\2y\!!!!
S!P3V3_STBY!U8F3!5!!TTL2G07_SOT23LF-74LVC2G07,IC,DB!!!!!!!!
S!GND!U8F3!2!!TTL2G07_SOT23LF-74LVC2G07,IC,DB!!!!!!!!
S!RST_BMC_SYSRST_BTN_OUT_N!U8F3!1!@baseboard_fab2_lib.baseboard_fab2(sch_1):page156_i201@mstr_ttl.ttl2g07(chips)!TTL2G07_SOT23LF-74LVC2G07,IC,DB!!!F20!\1a\!!!!
S!RST_BMC_SYSRST_BTN_OUT_B_R_N!U8F3!6!@baseboard_fab2_lib.baseboard_fab2(sch_1):page156_i201@mstr_ttl.ttl2g07(chips)!TTL2G07_SOT23LF-74LVC2G07,IC,DB!!!F20!\1y\!!!!
S!FM_BMC_PWRBTN_OUT_N!U8F3!3!@baseboard_fab2_lib.baseboard_fab2(sch_1):page156_i201@mstr_ttl.ttl2g07(chips)!TTL2G07_SOT23LF-74LVC2G07,IC,DB!!!F20!\2a\!!!!
S!FM_PCH_PWRBTN_R_N!U8F3!4!@baseboard_fab2_lib.baseboard_fab2(sch_1):page156_i201@mstr_ttl.ttl2g07(chips)!TTL2G07_SOT23LF-74LVC2G07,IC,DB!!!F20!\2y\!!!!
S!P3V3_STBY!FB1U2!1!@baseboard_fab2_lib.baseboard_fab2(sch_1):page165_i79@mstr_discrete.ferrite(chips)!FERRITE_SMLF-60,FB,693286-001!!!F2185!A!!!!
S!P3V3_FB_ADC128_VCC!FB1U2!2!@baseboard_fab2_lib.baseboard_fab2(sch_1):page165_i79@mstr_discrete.ferrite(chips)!FERRITE_SMLF-60,FB,693286-001!!!F2185!B!!!!
S!P3V3!J8F1!2!@baseboard_fab2_lib.baseboard_fab2(sch_1):page185_i53@mstr_sconn.sconn75k_h17033002(chips)!SCONN75K_H17033002_SMT1-SCONN,A!!!F133!\3_3v\(0)!!!!
S!P3V3!J8F1!4!@baseboard_fab2_lib.baseboard_fab2(sch_1):page185_i53@mstr_sconn.sconn75k_h17033002(chips)!SCONN75K_H17033002_SMT1-SCONN,A!!!F133!\3_3v\(1)!!!!
S!P3V3!J8F1!12!@baseboard_fab2_lib.baseboard_fab2(sch_1):page185_i53@mstr_sconn.sconn75k_h17033002(chips)!SCONN75K_H17033002_SMT1-SCONN,A!!!F133!\3_3v\(2)!!!!
S!P3V3!J8F1!14!@baseboard_fab2_lib.baseboard_fab2(sch_1):page185_i53@mstr_sconn.sconn75k_h17033002(chips)!SCONN75K_H17033002_SMT1-SCONN,A!!!F133!\3_3v\(3)!!!!
S!P3V3!J8F1!16!@baseboard_fab2_lib.baseboard_fab2(sch_1):page185_i53@mstr_sconn.sconn75k_h17033002(chips)!SCONN75K_H17033002_SMT1-SCONN,A!!!F133!\3_3v\(4)!!!!
S!P3V3!J8F1!18!@baseboard_fab2_lib.baseboard_fab2(sch_1):page185_i53@mstr_sconn.sconn75k_h17033002(chips)!SCONN75K_H17033002_SMT1-SCONN,A!!!F133!\3_3v\(5)!!!!
S!P3V3!J8F1!70!@baseboard_fab2_lib.baseboard_fab2(sch_1):page185_i53@mstr_sconn.sconn75k_h17033002(chips)!SCONN75K_H17033002_SMT1-SCONN,A!!!F133!\3_3v\(6)!!!!
S!P3V3!J8F1!72!@baseboard_fab2_lib.baseboard_fab2(sch_1):page185_i53@mstr_sconn.sconn75k_h17033002(chips)!SCONN75K_H17033002_SMT1-SCONN,A!!!F133!\3_3v\(7)!!!!
S!P3V3!J8F1!74!@baseboard_fab2_lib.baseboard_fab2(sch_1):page185_i53@mstr_sconn.sconn75k_h17033002(chips)!SCONN75K_H17033002_SMT1-SCONN,A!!!F133!\3_3v\(8)!!!!
S!PU_M2_CLK_REQ_N!J8F1!52!@baseboard_fab2_lib.baseboard_fab2(sch_1):page185_i53@mstr_sconn.sconn75k_h17033002(chips)!SCONN75K_H17033002_SMT1-SCONN,A!!!F133!CLKREQ_N_NC!!!!
S!TP_LED_M2_ACT_N!J8F1!10!@baseboard_fab2_lib.baseboard_fab2(sch_1):page185_i53@mstr_sconn.sconn75k_h17033002(chips)!SCONN75K_H17033002_SMT1-SCONN,A!!!F133!DAS_DSS_N!!!!
S!TP_M2_DEVSLP!J8F1!38!@baseboard_fab2_lib.baseboard_fab2(sch_1):page185_i53@mstr_sconn.sconn75k_h17033002(chips)!SCONN75K_H17033002_SMT1-SCONN,A!!!F133!DEVSLP!!!!
S!GND!J8F1!1!@baseboard_fab2_lib.baseboard_fab2(sch_1):page185_i53@mstr_sconn.sconn75k_h17033002(chips)!SCONN75K_H17033002_SMT1-SCONN,A!!!F133!GND(0)!!!!
S!GND!J8F1!57!@baseboard_fab2_lib.baseboard_fab2(sch_1):page185_i53@mstr_sconn.sconn75k_h17033002(chips)!SCONN75K_H17033002_SMT1-SCONN,A!!!F133!GND(10)!!!!
S!GND!J8F1!71!@baseboard_fab2_lib.baseboard_fab2(sch_1):page185_i53@mstr_sconn.sconn75k_h17033002(chips)!SCONN75K_H17033002_SMT1-SCONN,A!!!F133!GND(11)!!!!
S!GND!J8F1!73!@baseboard_fab2_lib.baseboard_fab2(sch_1):page185_i53@mstr_sconn.sconn75k_h17033002(chips)!SCONN75K_H17033002_SMT1-SCONN,A!!!F133!GND(12)!!!!
S!GND!J8F1!75!@baseboard_fab2_lib.baseboard_fab2(sch_1):page185_i53@mstr_sconn.sconn75k_h17033002(chips)!SCONN75K_H17033002_SMT1-SCONN,A!!!F133!GND(13)!!!!
S!GND!J8F1!3!@baseboard_fab2_lib.baseboard_fab2(sch_1):page185_i53@mstr_sconn.sconn75k_h17033002(chips)!SCONN75K_H17033002_SMT1-SCONN,A!!!F133!GND(1)!!!!
S!GND!J8F1!9!@baseboard_fab2_lib.baseboard_fab2(sch_1):page185_i53@mstr_sconn.sconn75k_h17033002(chips)!SCONN75K_H17033002_SMT1-SCONN,A!!!F133!GND(2)!!!!
S!GND!J8F1!15!@baseboard_fab2_lib.baseboard_fab2(sch_1):page185_i53@mstr_sconn.sconn75k_h17033002(chips)!SCONN75K_H17033002_SMT1-SCONN,A!!!F133!GND(3)!!!!
S!GND!J8F1!21!@baseboard_fab2_lib.baseboard_fab2(sch_1):page185_i53@mstr_sconn.sconn75k_h17033002(chips)!SCONN75K_H17033002_SMT1-SCONN,A!!!F133!GND(4)!!!!
S!GND!J8F1!27!@baseboard_fab2_lib.baseboard_fab2(sch_1):page185_i53@mstr_sconn.sconn75k_h17033002(chips)!SCONN75K_H17033002_SMT1-SCONN,A!!!F133!GND(5)!!!!
S!GND!J8F1!33!@baseboard_fab2_lib.baseboard_fab2(sch_1):page185_i53@mstr_sconn.sconn75k_h17033002(chips)!SCONN75K_H17033002_SMT1-SCONN,A!!!F133!GND(6)!!!!
S!GND!J8F1!39!@baseboard_fab2_lib.baseboard_fab2(sch_1):page185_i53@mstr_sconn.sconn75k_h17033002(chips)!SCONN75K_H17033002_SMT1-SCONN,A!!!F133!GND(7)!!!!
S!GND!J8F1!45!@baseboard_fab2_lib.baseboard_fab2(sch_1):page185_i53@mstr_sconn.sconn75k_h17033002(chips)!SCONN75K_H17033002_SMT1-SCONN,A!!!F133!GND(8)!!!!
S!GND!J8F1!51!@baseboard_fab2_lib.baseboard_fab2(sch_1):page185_i53@mstr_sconn.sconn75k_h17033002(chips)!SCONN75K_H17033002_SMT1-SCONN,A!!!F133!GND(9)!!!!
S!GND!J8F1!MP1!@baseboard_fab2_lib.baseboard_fab2(sch_1):page185_i53@mstr_sconn.sconn75k_h17033002(chips)!SCONN75K_H17033002_SMT1-SCONN,A!!!F133!MP1!!!!
S!GND!J8F1!MP2!@baseboard_fab2_lib.baseboard_fab2(sch_1):page185_i53@mstr_sconn.sconn75k_h17033002(chips)!SCONN75K_H17033002_SMT1-SCONN,A!!!F133!MP2!!!!
S!NC_M2<0>!J8F1!6!@baseboard_fab2_lib.baseboard_fab2(sch_1):page185_i53@mstr_sconn.sconn75k_h17033002(chips)!SCONN75K_H17033002_SMT1-SCONN,A!!!F133!NC(0)!!!!
S!NC_M2<10>!J8F1!36!@baseboard_fab2_lib.baseboard_fab2(sch_1):page185_i53@mstr_sconn.sconn75k_h17033002(chips)!SCONN75K_H17033002_SMT1-SCONN,A!!!F133!NC(10)!!!!
S!NC_M2<11>!J8F1!40!@baseboard_fab2_lib.baseboard_fab2(sch_1):page185_i53@mstr_sconn.sconn75k_h17033002(chips)!SCONN75K_H17033002_SMT1-SCONN,A!!!F133!NC(11)!!!!
S!NC_M2<12>!J8F1!42!@baseboard_fab2_lib.baseboard_fab2(sch_1):page185_i53@mstr_sconn.sconn75k_h17033002(chips)!SCONN75K_H17033002_SMT1-SCONN,A!!!F133!NC(12)!!!!
S!NC_M2<13>!J8F1!44!@baseboard_fab2_lib.baseboard_fab2(sch_1):page185_i53@mstr_sconn.sconn75k_h17033002(chips)!SCONN75K_H17033002_SMT1-SCONN,A!!!F133!NC(13)!!!!
S!NC_M2<14>!J8F1!46!@baseboard_fab2_lib.baseboard_fab2(sch_1):page185_i53@mstr_sconn.sconn75k_h17033002(chips)!SCONN75K_H17033002_SMT1-SCONN,A!!!F133!NC(14)!!!!
S!NC_M2<15>!J8F1!48!@baseboard_fab2_lib.baseboard_fab2(sch_1):page185_i53@mstr_sconn.sconn75k_h17033002(chips)!SCONN75K_H17033002_SMT1-SCONN,A!!!F133!NC(15)!!!!
S!NC_M2<16>!J8F1!56!@baseboard_fab2_lib.baseboard_fab2(sch_1):page185_i53@mstr_sconn.sconn75k_h17033002(chips)!SCONN75K_H17033002_SMT1-SCONN,A!!!F133!NC(16)!!!!
S!NC_M2<17>!J8F1!58!@baseboard_fab2_lib.baseboard_fab2(sch_1):page185_i53@mstr_sconn.sconn75k_h17033002(chips)!SCONN75K_H17033002_SMT1-SCONN,A!!!F133!NC(17)!!!!
S!NC_M2<18>!J8F1!67!@baseboard_fab2_lib.baseboard_fab2(sch_1):page185_i53@mstr_sconn.sconn75k_h17033002(chips)!SCONN75K_H17033002_SMT1-SCONN,A!!!F133!NC(18)!!!!
S!NC_M2<1>!J8F1!8!@baseboard_fab2_lib.baseboard_fab2(sch_1):page185_i53@mstr_sconn.sconn75k_h17033002(chips)!SCONN75K_H17033002_SMT1-SCONN,A!!!F133!NC(1)!!!!
S!NC_M2<2>!J8F1!20!@baseboard_fab2_lib.baseboard_fab2(sch_1):page185_i53@mstr_sconn.sconn75k_h17033002(chips)!SCONN75K_H17033002_SMT1-SCONN,A!!!F133!NC(2)!!!!
S!NC_M2<3>!J8F1!22!@baseboard_fab2_lib.baseboard_fab2(sch_1):page185_i53@mstr_sconn.sconn75k_h17033002(chips)!SCONN75K_H17033002_SMT1-SCONN,A!!!F133!NC(3)!!!!
S!NC_M2<4>!J8F1!24!@baseboard_fab2_lib.baseboard_fab2(sch_1):page185_i53@mstr_sconn.sconn75k_h17033002(chips)!SCONN75K_H17033002_SMT1-SCONN,A!!!F133!NC(4)!!!!
S!NC_M2<5>!J8F1!26!@baseboard_fab2_lib.baseboard_fab2(sch_1):page185_i53@mstr_sconn.sconn75k_h17033002(chips)!SCONN75K_H17033002_SMT1-SCONN,A!!!F133!NC(5)!!!!
S!NC_M2<6>!J8F1!28!@baseboard_fab2_lib.baseboard_fab2(sch_1):page185_i53@mstr_sconn.sconn75k_h17033002(chips)!SCONN75K_H17033002_SMT1-SCONN,A!!!F133!NC(6)!!!!
S!NC_M2<7>!J8F1!30!@baseboard_fab2_lib.baseboard_fab2(sch_1):page185_i53@mstr_sconn.sconn75k_h17033002(chips)!SCONN75K_H17033002_SMT1-SCONN,A!!!F133!NC(7)!!!!
S!NC_M2<8>!J8F1!32!@baseboard_fab2_lib.baseboard_fab2(sch_1):page185_i53@mstr_sconn.sconn75k_h17033002(chips)!SCONN75K_H17033002_SMT1-SCONN,A!!!F133!NC(8)!!!!
S!NC_M2<9>!J8F1!34!@baseboard_fab2_lib.baseboard_fab2(sch_1):page185_i53@mstr_sconn.sconn75k_h17033002(chips)!SCONN75K_H17033002_SMT1-SCONN,A!!!F133!NC(9)!!!!
S!FM_M2_SSD_PEDET!J8F1!69!@baseboard_fab2_lib.baseboard_fab2(sch_1):page185_i53@mstr_sconn.sconn75k_h17033002(chips)!SCONN75K_H17033002_SMT1-SCONN,A!!!F133!PEDET!!!!
S!P3E_PCH_M2_SATA6G_RX_R_DP!J8F1!41!@baseboard_fab2_lib.baseboard_fab2(sch_1):page185_i53@mstr_sconn.sconn75k_h17033002(chips)!SCONN75K_H17033002_SMT1-SCONN,A!!!F133!PERN0_SATA_BP!!!!
S!P3E_PCH_M2_RX_DN<1>!J8F1!29!@baseboard_fab2_lib.baseboard_fab2(sch_1):page185_i53@mstr_sconn.sconn75k_h17033002(chips)!SCONN75K_H17033002_SMT1-SCONN,A!!!F133!PERN1!!!!
S!P3E_PCH_M2_RX_DN<2>!J8F1!17!@baseboard_fab2_lib.baseboard_fab2(sch_1):page185_i53@mstr_sconn.sconn75k_h17033002(chips)!SCONN75K_H17033002_SMT1-SCONN,A!!!F133!PERN2!!!!
S!P3E_PCH_M2_RX_DN<3>!J8F1!5!@baseboard_fab2_lib.baseboard_fab2(sch_1):page185_i53@mstr_sconn.sconn75k_h17033002(chips)!SCONN75K_H17033002_SMT1-SCONN,A!!!F133!PERN3!!!!
S!P3E_PCH_M2_SATA6G_RX_R_DN!J8F1!43!@baseboard_fab2_lib.baseboard_fab2(sch_1):page185_i53@mstr_sconn.sconn75k_h17033002(chips)!SCONN75K_H17033002_SMT1-SCONN,A!!!F133!PERP0_SATA_BN!!!!
S!P3E_PCH_M2_RX_DP<1>!J8F1!31!@baseboard_fab2_lib.baseboard_fab2(sch_1):page185_i53@mstr_sconn.sconn75k_h17033002(chips)!SCONN75K_H17033002_SMT1-SCONN,A!!!F133!PERP1!!!!
S!P3E_PCH_M2_RX_DP<2>!J8F1!19!@baseboard_fab2_lib.baseboard_fab2(sch_1):page185_i53@mstr_sconn.sconn75k_h17033002(chips)!SCONN75K_H17033002_SMT1-SCONN,A!!!F133!PERP2!!!!
S!P3E_PCH_M2_RX_DP<3>!J8F1!7!@baseboard_fab2_lib.baseboard_fab2(sch_1):page185_i53@mstr_sconn.sconn75k_h17033002(chips)!SCONN75K_H17033002_SMT1-SCONN,A!!!F133!PERP3!!!!
S!RST_PCIE_M2_DEV_N!J8F1!50!@baseboard_fab2_lib.baseboard_fab2(sch_1):page185_i53@mstr_sconn.sconn75k_h17033002(chips)!SCONN75K_H17033002_SMT1-SCONN,A!!!F133!PERST_N_NC!!!!
S!P3E_PCH_M2_SATA6G_TX_R_DN!J8F1!47!@baseboard_fab2_lib.baseboard_fab2(sch_1):page185_i53@mstr_sconn.sconn75k_h17033002(chips)!SCONN75K_H17033002_SMT1-SCONN,A!!!F133!PETN0_SATA_AN!!!!
S!P3E_PCH_M2_TX_C_DN<1>!J8F1!35!@baseboard_fab2_lib.baseboard_fab2(sch_1):page185_i53@mstr_sconn.sconn75k_h17033002(chips)!SCONN75K_H17033002_SMT1-SCONN,A!!!F133!PETN1!!!!
S!P3E_PCH_M2_TX_C_DN<2>!J8F1!23!@baseboard_fab2_lib.baseboard_fab2(sch_1):page185_i53@mstr_sconn.sconn75k_h17033002(chips)!SCONN75K_H17033002_SMT1-SCONN,A!!!F133!PETN2!!!!
S!P3E_PCH_M2_TX_C_DN<3>!J8F1!11!@baseboard_fab2_lib.baseboard_fab2(sch_1):page185_i53@mstr_sconn.sconn75k_h17033002(chips)!SCONN75K_H17033002_SMT1-SCONN,A!!!F133!PETN3!!!!
S!P3E_PCH_M2_SATA6G_TX_R_DP!J8F1!49!@baseboard_fab2_lib.baseboard_fab2(sch_1):page185_i53@mstr_sconn.sconn75k_h17033002(chips)!SCONN75K_H17033002_SMT1-SCONN,A!!!F133!PETP0_SATA_AP!!!!
S!P3E_PCH_M2_TX_C_DP<1>!J8F1!37!@baseboard_fab2_lib.baseboard_fab2(sch_1):page185_i53@mstr_sconn.sconn75k_h17033002(chips)!SCONN75K_H17033002_SMT1-SCONN,A!!!F133!PETP1!!!!
S!P3E_PCH_M2_TX_C_DP<2>!J8F1!25!@baseboard_fab2_lib.baseboard_fab2(sch_1):page185_i53@mstr_sconn.sconn75k_h17033002(chips)!SCONN75K_H17033002_SMT1-SCONN,A!!!F133!PETP2!!!!
S!P3E_PCH_M2_TX_C_DP<3>!J8F1!13!@baseboard_fab2_lib.baseboard_fab2(sch_1):page185_i53@mstr_sconn.sconn75k_h17033002(chips)!SCONN75K_H17033002_SMT1-SCONN,A!!!F133!PETP3!!!!
S!FM_PE_M2_WAKE_N!J8F1!54!@baseboard_fab2_lib.baseboard_fab2(sch_1):page185_i53@mstr_sconn.sconn75k_h17033002(chips)!SCONN75K_H17033002_SMT1-SCONN,A!!!F133!PEWAKE_N_NC!!!!
S!CLK_100M_M2_DN!J8F1!53!@baseboard_fab2_lib.baseboard_fab2(sch_1):page185_i53@mstr_sconn.sconn75k_h17033002(chips)!SCONN75K_H17033002_SMT1-SCONN,A!!!F133!REFCLKN!!!!
S!CLK_100M_M2_DP!J8F1!55!@baseboard_fab2_lib.baseboard_fab2(sch_1):page185_i53@mstr_sconn.sconn75k_h17033002(chips)!SCONN75K_H17033002_SMT1-SCONN,A!!!F133!REFCLKP!!!!
S!TP_M2_32M_SUSCLK!J8F1!68!@baseboard_fab2_lib.baseboard_fab2(sch_1):page185_i53@mstr_sconn.sconn75k_h17033002(chips)!SCONN75K_H17033002_SMT1-SCONN,A!!!F133!SUSCLK!!!!
S!!U8D2!1!!TTL1G07_A_SOP-74LVC1G07,IC,C88B!!!!!!!!
S!GND!U8D2!3!!TTL1G07_A_SOP-74LVC1G07,IC,C88B!!!!!!!!
S!P3V3_STBY!U8D2!5!!TTL1G07_A_SOP-74LVC1G07,IC,C88B!!!!!!!!
S!PWRGD_DSW_PWROK!U8D2!2!@baseboard_fab2_lib.baseboard_fab2(sch_1):page157_i374@mstr_ttl.ttl1g07_a(chips)!TTL1G07_A_SOP-74LVC1G07,IC,C88B!!!F38!A!!!!
S!RST_BMC_SRST_R2_N!U8D2!4!@baseboard_fab2_lib.baseboard_fab2(sch_1):page157_i374@mstr_ttl.ttl1g07_a(chips)!TTL1G07_A_SOP-74LVC1G07,IC,C88B!!!F38!Y!!!!
S!!U9A1!1!!TTL1G07_A_SOP-74LVC1G07,IC,C88B!!!!!!!!
S!GND!U9A1!3!!TTL1G07_A_SOP-74LVC1G07,IC,C88B!!!!!!!!
S!P3V3_STBY!U9A1!5!!TTL1G07_A_SOP-74LVC1G07,IC,C88B!!!!!!!!
S!SPA_5V_SIN_SW!U9A1!2!@baseboard_fab2_lib.baseboard_fab2(sch_1):page155_i178@mstr_ttl.ttl1g07_a(chips)!TTL1G07_A_SOP-74LVC1G07,IC,C88B!!!F34!A!!!!
S!SPA_SIN_SW_R!U9A1!4!@baseboard_fab2_lib.baseboard_fab2(sch_1):page155_i178@mstr_ttl.ttl1g07_a(chips)!TTL1G07_A_SOP-74LVC1G07,IC,C88B!!!F34!Y!!!!
S!!U1L4!1!!TTL1G07_A_SOP-74LVC1G07,IC,C88B!!!!!!!!
S!GND!U1L4!3!!TTL1G07_A_SOP-74LVC1G07,IC,C88B!!!!!!!!
S!P3V3_STBY!U1L4!5!!TTL1G07_A_SOP-74LVC1G07,IC,C88B!!!!!!!!
S!XDP_RST_CO_N!U1L4!2!@baseboard_fab2_lib.baseboard_fab2(sch_1):page111_i85@mstr_ttl.ttl1g07_a(chips)!TTL1G07_A_SOP-74LVC1G07,IC,C88B!!!F41!A!!!!
S!FM_DEBUG_RST_BTN_R1_N!U1L4!4!@baseboard_fab2_lib.baseboard_fab2(sch_1):page111_i85@mstr_ttl.ttl1g07_a(chips)!TTL1G07_A_SOP-74LVC1G07,IC,C88B!!!F41!Y!!!!
S!!U1R1!1!!TTL1G07_A_SOP-74LVC1G07,IC,C88B!!!!!!!!
S!GND!U1R1!3!!TTL1G07_A_SOP-74LVC1G07,IC,C88B!!!!!!!!
S!P3V3_STBY!U1R1!5!!TTL1G07_A_SOP-74LVC1G07,IC,C88B!!!!!!!!
S!FM_FAST_PROCHOT_THROTTLE_DLY_BU!U1R1!2!@baseboard_fab2_lib.baseboard_fab2(sch_1):page170_i46@mstr_ttl.ttl1g07_a(chips)!TTL1G07_A_SOP-74LVC1G07,IC,C88B!!!F40!A!!!!
S!FM_THROTTLE_R1_N!U1R1!4!@baseboard_fab2_lib.baseboard_fab2(sch_1):page170_i46@mstr_ttl.ttl1g07_a(chips)!TTL1G07_A_SOP-74LVC1G07,IC,C88B!!!F40!Y!!!!
S!!U8D3!1!!TTL1G07_A_SOP-74LVC1G07,IC,C88B!!!!!!!!
S!GND!U8D3!3!!TTL1G07_A_SOP-74LVC1G07,IC,C88B!!!!!!!!
S!P3V3_STBY!U8D3!5!!TTL1G07_A_SOP-74LVC1G07,IC,C88B!!!!!!!!
S!IRQ_SML1_PMBUS_ALERT_BUF_N!U8D3!2!@baseboard_fab2_lib.baseboard_fab2(sch_1):page170_i4@mstr_ttl.ttl1g07_a(chips)!TTL1G07_A_SOP-74LVC1G07,IC,C88B!!!F37!A!!!!
S!IRQ_FORCE_NM_THROTTLE_R_N!U8D3!4!@baseboard_fab2_lib.baseboard_fab2(sch_1):page170_i4@mstr_ttl.ttl1g07_a(chips)!TTL1G07_A_SOP-74LVC1G07,IC,C88B!!!F37!Y!!!!
S!!U2P1!1!!TTL1G07_A_SOP-74LVC1G07,IC,C88B!!!!!!!!
S!GND!U2P1!3!!TTL1G07_A_SOP-74LVC1G07,IC,C88B!!!!!!!!
S!P3V3_STBY!U2P1!5!!TTL1G07_A_SOP-74LVC1G07,IC,C88B!!!!!!!!
S!FM_M2_SSD_PEDET!U2P1!2!@baseboard_fab2_lib.baseboard_fab2(sch_1):page185_i110@mstr_ttl.ttl1g07_a(chips)!TTL1G07_A_SOP-74LVC1G07,IC,C88B!!!F39!A!!!!
S!FM_M2_DET_LVC3!U2P1!4!@baseboard_fab2_lib.baseboard_fab2(sch_1):page185_i110@mstr_ttl.ttl1g07_a(chips)!TTL1G07_A_SOP-74LVC1G07,IC,C88B!!!F39!Y!!!!
S!!U8G2!1!!TTL1G07_A_SOP-74LVC1G07,IC,C88B!!!!!!!!
S!GND!U8G2!3!!TTL1G07_A_SOP-74LVC1G07,IC,C88B!!!!!!!!
S!P3V3_STBY!U8G2!5!!TTL1G07_A_SOP-74LVC1G07,IC,C88B!!!!!!!!
S!FAN_PWM_OUT_SYS0!U8G2!2!@baseboard_fab2_lib.baseboard_fab2(sch_1):page161_i88@mstr_ttl.ttl1g07_a(chips)!TTL1G07_A_SOP-74LVC1G07,IC,C88B!!!F36!A!!!!
S!FAN_PWM_OUT_SYS0_BUF!U8G2!4!@baseboard_fab2_lib.baseboard_fab2(sch_1):page161_i88@mstr_ttl.ttl1g07_a(chips)!TTL1G07_A_SOP-74LVC1G07,IC,C88B!!!F36!Y!!!!
S!!U8G3!1!!TTL1G07_A_SOP-74LVC1G07,IC,C88B!!!!!!!!
S!GND!U8G3!3!!TTL1G07_A_SOP-74LVC1G07,IC,C88B!!!!!!!!
S!P3V3_STBY!U8G3!5!!TTL1G07_A_SOP-74LVC1G07,IC,C88B!!!!!!!!
S!FAN_PWM_OUT_SYS1!U8G3!2!@baseboard_fab2_lib.baseboard_fab2(sch_1):page161_i92@mstr_ttl.ttl1g07_a(chips)!TTL1G07_A_SOP-74LVC1G07,IC,C88B!!!F35!A!!!!
S!FAN_PWM_OUT_SYS1_BUF!U8G3!4!@baseboard_fab2_lib.baseboard_fab2(sch_1):page161_i92@mstr_ttl.ttl1g07_a(chips)!TTL1G07_A_SOP-74LVC1G07,IC,C88B!!!F35!Y!!!!
S!!U9F3!1!!TTL1G07_A_SOP-74LVC1G07,IC,C88B!!!!!!!!
S!GND!U9F3!3!!TTL1G07_A_SOP-74LVC1G07,IC,C88B!!!!!!!!
S!P3V3_STBY!U9F3!5!!TTL1G07_A_SOP-74LVC1G07,IC,C88B!!!!!!!!
S!RST_BMC_DDR3_BUF_IN_N!U9F3!2!@baseboard_fab2_lib.baseboard_fab2(sch_1):page151_i69@mstr_ttl.ttl1g07_a(chips)!TTL1G07_A_SOP-74LVC1G07,IC,C88B!!!F33!A!!!!
S!RST_BMC_DDR3_R_N!U9F3!4!@baseboard_fab2_lib.baseboard_fab2(sch_1):page151_i69@mstr_ttl.ttl1g07_a(chips)!TTL1G07_A_SOP-74LVC1G07,IC,C88B!!!F33!Y!!!!
S!PWRGD_P12V_HSC_DLY!CR8E1!2!@baseboard_fab2_lib.baseboard_fab2(sch_1):page196_i128@mstr_discrete.diode(chips)!DIODE_SMLF-BAT54WS,IC,C73510-0A!!!F2208!A!!!!
S!PWRGD_P12V_HSC!CR8E1!1!@baseboard_fab2_lib.baseboard_fab2(sch_1):page196_i128@mstr_discrete.diode(chips)!DIODE_SMLF-BAT54WS,IC,C73510-0A!!!F2208!C!!!!
S!PWRGD_DSW_PWROK!CR7E1!2!@baseboard_fab2_lib.baseboard_fab2(sch_1):page196_i103@mstr_discrete.diode(chips)!DIODE_SMLF-BAT54WS,IC,C73510-0A!!!F2207!A!!!!
S!PWRGD_P3V3_STBY!CR7E1!1!@baseboard_fab2_lib.baseboard_fab2(sch_1):page196_i103@mstr_discrete.diode(chips)!DIODE_SMLF-BAT54WS,IC,C73510-0A!!!F2207!C!!!!
S!FM_DISABLE_FAN_N!CR9P2!2!@baseboard_fab2_lib.baseboard_fab2(sch_1):page200_i213@mstr_discrete.diode(chips)!DIODE_SMLF-BAT54WS,IC,C73510-0A!!!F2205!A!!!!
S!FM_UV_ADR_TRIGGER_N!CR9P2!1!@baseboard_fab2_lib.baseboard_fab2(sch_1):page200_i213@mstr_discrete.diode(chips)!DIODE_SMLF-BAT54WS,IC,C73510-0A!!!F2205!C!!!!
S!FM_DISABLE_FAN_N!CR9P1!2!@baseboard_fab2_lib.baseboard_fab2(sch_1):page200_i214@mstr_discrete.diode(chips)!DIODE_SMLF-BAT54WS,IC,C73510-0A!!!F2206!A!!!!
S!IRQ_UV_DETECT_N!CR9P1!1!@baseboard_fab2_lib.baseboard_fab2(sch_1):page200_i214@mstr_discrete.diode(chips)!DIODE_SMLF-BAT54WS,IC,C73510-0A!!!F2206!C!!!!
S!A_HSC_PSET!R1D40!1!@baseboard_fab2_lib.baseboard_fab2(sch_1):page199_i100@mstr_discrete.res(chips)!RES_0402-40.2K,1%,1/16W,CHIP,GA!!!F494!A!!!!
S!AGND_HSC!R1D40!2!@baseboard_fab2_lib.baseboard_fab2(sch_1):page199_i100@mstr_discrete.res(chips)!RES_0402-40.2K,1%,1/16W,CHIP,GA!!!F494!B!!!!
S!FM_UART_SWITCH_N!R1L4!1!@baseboard_fab2_lib.baseboard_fab2(sch_1):page168_i7@mstr_discrete.res(chips)!RES_0402-40.2K,1%,1/16W,CHIP,GA!!!F493!A!!!!
S!FM_UART_SEL_N!R1L4!2!@baseboard_fab2_lib.baseboard_fab2(sch_1):page168_i7@mstr_discrete.res(chips)!RES_0402-40.2K,1%,1/16W,CHIP,GA!!!F493!B!!!!
S!VR_PVDDQ_GHJ_XADDR1!R1G23!1!@baseboard_fab2_lib.baseboard_fab2(sch_1):page223_i77@mstr_discrete.res(chips)!RES_0402-4.02K,1%,1/16W,CHIP,GA!!!F658!A!!!!
S!GND!R1G23!2!@baseboard_fab2_lib.baseboard_fab2(sch_1):page223_i77@mstr_discrete.res(chips)!RES_0402-4.02K,1%,1/16W,CHIP,GA!!!F658!B!!!!
S!VR_PVNN_PCH_XADDR1!R2L9!1!@baseboard_fab2_lib.baseboard_fab2(sch_1):page235_i176@mstr_discrete.res(chips)!RES_0402-4.02K,1%,1/16W,CHIP,GA!!!F657!A!!!!
S!GND!R2L9!2!@baseboard_fab2_lib.baseboard_fab2(sch_1):page235_i176@mstr_discrete.res(chips)!RES_0402-4.02K,1%,1/16W,CHIP,GA!!!F657!B!!!!
S!VR_PVCCIO_CPU0_XADDR2!R3N22!1!@baseboard_fab2_lib.baseboard_fab2(sch_1):page211_i65@mstr_discrete.res(chips)!RES_0402-4.02K,1%,1/16W,CHIP,GA!!!F656!A!!!!
S!GND!R3N22!2!@baseboard_fab2_lib.baseboard_fab2(sch_1):page211_i65@mstr_discrete.res(chips)!RES_0402-4.02K,1%,1/16W,CHIP,GA!!!F656!B!!!!
S!VR_PVCCIN_CPU0_XADDR2!R6P27!1!@baseboard_fab2_lib.baseboard_fab2(sch_1):page201_i120@mstr_discrete.res(chips)!RES_0402-4.02K,1%,1/16W,CHIP,GA!!!F655!A!!!!
S!GND!R6P27!2!@baseboard_fab2_lib.baseboard_fab2(sch_1):page201_i120@mstr_discrete.res(chips)!RES_0402-4.02K,1%,1/16W,CHIP,GA!!!F655!B!!!!
S!VR_PVCCIN_CPU0_XADDR1!R6P28!1!@baseboard_fab2_lib.baseboard_fab2(sch_1):page201_i121@mstr_discrete.res(chips)!RES_0402-4.02K,1%,1/16W,CHIP,GA!!!F654!A!!!!
S!GND!R6P28!2!@baseboard_fab2_lib.baseboard_fab2(sch_1):page201_i121@mstr_discrete.res(chips)!RES_0402-4.02K,1%,1/16W,CHIP,GA!!!F654!B!!!!
S!VR_PVDDQ_ABC_XADDR1!R7G8!1!@baseboard_fab2_lib.baseboard_fab2(sch_1):page215_i321@mstr_discrete.res(chips)!RES_0402-4.02K,1%,1/16W,CHIP,GA!!!F653!A!!!!
S!GND!R7G8!2!@baseboard_fab2_lib.baseboard_fab2(sch_1):page215_i321@mstr_discrete.res(chips)!RES_0402-4.02K,1%,1/16W,CHIP,GA!!!F653!B!!!!
S!VR_PVCCIN_CPU1_XADDR1!R9N8!1!@baseboard_fab2_lib.baseboard_fab2(sch_1):page206_i112@mstr_discrete.res(chips)!RES_0402-4.02K,1%,1/16W,CHIP,GA!!!F652!A!!!!
S!GND!R9N8!2!@baseboard_fab2_lib.baseboard_fab2(sch_1):page206_i112@mstr_discrete.res(chips)!RES_0402-4.02K,1%,1/16W,CHIP,GA!!!F652!B!!!!
S!VR_PVCCMCP_CPU0_XADDR2!R7C24!1!@baseboard_fab2_lib.baseboard_fab2(sch_1):page194_i155@mstr_discrete.res(chips)!RES_0402-4.02K,1%,1/16W,CHIP,GA!!!F651!A!!!!
S!GND!R7C24!2!@baseboard_fab2_lib.baseboard_fab2(sch_1):page194_i155@mstr_discrete.res(chips)!RES_0402-4.02K,1%,1/16W,CHIP,GA!!!F651!B!!!!
S!VR_PVDDQ_DEF_XADDR2!R7A8!1!@baseboard_fab2_lib.baseboard_fab2(sch_1):page218_i37@mstr_discrete.res(chips)!RES_0402-8.06K,1%,1/16W,CHIP,GA!!!F298!A!!!!
S!GND!R7A8!2!@baseboard_fab2_lib.baseboard_fab2(sch_1):page218_i37@mstr_discrete.res(chips)!RES_0402-8.06K,1%,1/16W,CHIP,GA!!!F298!B!!!!
S!VR_PVDDQ_ABC_XADDR2!R7G10!1!@baseboard_fab2_lib.baseboard_fab2(sch_1):page215_i317@mstr_discrete.res(chips)!RES_0402-8.06K,1%,1/16W,CHIP,GA!!!F297!A!!!!
S!GND!R7G10!2!@baseboard_fab2_lib.baseboard_fab2(sch_1):page215_i317@mstr_discrete.res(chips)!RES_0402-8.06K,1%,1/16W,CHIP,GA!!!F297!B!!!!
S!VR_PVCCIOMCP_CPU1_XADDR1!R4C12!1!@baseboard_fab2_lib.baseboard_fab2(sch_1):page193_i169@mstr_discrete.res(chips)!RES_0402-8.06K,1%,1/16W,CHIP,GA!!!F296!A!!!!
S!GND!R4C12!2!@baseboard_fab2_lib.baseboard_fab2(sch_1):page193_i169@mstr_discrete.res(chips)!RES_0402-8.06K,1%,1/16W,CHIP,GA!!!F296!B!!!!
S!PVDDQ_ABC!C5G11!1!@baseboard_fab2_lib.baseboard_fab2(sch_1):page217_i250@mstr_discrete.cap(chips)!CAP_0603-22.0UF,4V,20%,X6S,E15A!!!F2864!A!!!!
S!GND!C5G11!2!@baseboard_fab2_lib.baseboard_fab2(sch_1):page217_i250@mstr_discrete.cap(chips)!CAP_0603-22.0UF,4V,20%,X6S,E15A!!!F2864!B!!!!
S!PVDDQ_ABC!C5G13!1!@baseboard_fab2_lib.baseboard_fab2(sch_1):page217_i240@mstr_discrete.cap(chips)!CAP_0603-22.0UF,4V,20%,X6S,E15A!!!F2862!A!!!!
S!GND!C5G13!2!@baseboard_fab2_lib.baseboard_fab2(sch_1):page217_i240@mstr_discrete.cap(chips)!CAP_0603-22.0UF,4V,20%,X6S,E15A!!!F2862!B!!!!
S!PVDDQ_GHJ!C8U3!1!@baseboard_fab2_lib.baseboard_fab2(sch_1):page225_i236@mstr_discrete.cap(chips)!CAP_0603-22.0UF,4V,20%,X6S,E15A!!!F2758!A!!!!
S!GND!C8U3!2!@baseboard_fab2_lib.baseboard_fab2(sch_1):page225_i236@mstr_discrete.cap(chips)!CAP_0603-22.0UF,4V,20%,X6S,E15A!!!F2758!B!!!!
S!PVDDQ_ABC!C5G1!1!@baseboard_fab2_lib.baseboard_fab2(sch_1):page217_i231@mstr_discrete.cap(chips)!CAP_0603-22.0UF,4V,20%,X6S,E15A!!!F2872!A!!!!
S!GND!C5G1!2!@baseboard_fab2_lib.baseboard_fab2(sch_1):page217_i231@mstr_discrete.cap(chips)!CAP_0603-22.0UF,4V,20%,X6S,E15A!!!F2872!B!!!!
S!PVDDQ_ABC!C5G14!1!@baseboard_fab2_lib.baseboard_fab2(sch_1):page217_i223@mstr_discrete.cap(chips)!CAP_0603-22.0UF,4V,20%,X6S,E15A!!!F2861!A!!!!
S!GND!C5G14!2!@baseboard_fab2_lib.baseboard_fab2(sch_1):page217_i223@mstr_discrete.cap(chips)!CAP_0603-22.0UF,4V,20%,X6S,E15A!!!F2861!B!!!!
S!PVDDQ_DEF!C5A1!1!@baseboard_fab2_lib.baseboard_fab2(sch_1):page220_i219@mstr_discrete.cap(chips)!CAP_0603-22.0UF,4V,20%,X6S,E15A!!!F2938!A!!!!
S!GND!C5A1!2!@baseboard_fab2_lib.baseboard_fab2(sch_1):page220_i219@mstr_discrete.cap(chips)!CAP_0603-22.0UF,4V,20%,X6S,E15A!!!F2938!B!!!!
S!PVDDQ_DEF!C5A2!1!@baseboard_fab2_lib.baseboard_fab2(sch_1):page220_i214@mstr_discrete.cap(chips)!CAP_0603-22.0UF,4V,20%,X6S,E15A!!!F2937!A!!!!
S!GND!C5A2!2!@baseboard_fab2_lib.baseboard_fab2(sch_1):page220_i214@mstr_discrete.cap(chips)!CAP_0603-22.0UF,4V,20%,X6S,E15A!!!F2937!B!!!!
S!PVDDQ_DEF!C5A3!1!@baseboard_fab2_lib.baseboard_fab2(sch_1):page220_i210@mstr_discrete.cap(chips)!CAP_0603-22.0UF,4V,20%,X6S,E15A!!!F2936!A!!!!
S!GND!C5A3!2!@baseboard_fab2_lib.baseboard_fab2(sch_1):page220_i210@mstr_discrete.cap(chips)!CAP_0603-22.0UF,4V,20%,X6S,E15A!!!F2936!B!!!!
S!PVDDQ_DEF!C5A4!1!@baseboard_fab2_lib.baseboard_fab2(sch_1):page220_i206@mstr_discrete.cap(chips)!CAP_0603-22.0UF,4V,20%,X6S,E15A!!!F2935!A!!!!
S!GND!C5A4!2!@baseboard_fab2_lib.baseboard_fab2(sch_1):page220_i206@mstr_discrete.cap(chips)!CAP_0603-22.0UF,4V,20%,X6S,E15A!!!F2935!B!!!!
S!PVDDQ_GHJ!C8U7!1!@baseboard_fab2_lib.baseboard_fab2(sch_1):page225_i241@mstr_discrete.cap(chips)!CAP_0603-22.0UF,4V,20%,X6S,E15A!!!F2754!A!!!!
S!GND!C8U7!2!@baseboard_fab2_lib.baseboard_fab2(sch_1):page225_i241@mstr_discrete.cap(chips)!CAP_0603-22.0UF,4V,20%,X6S,E15A!!!F2754!B!!!!
S!PVDDQ_GHJ!C8U6!1!@baseboard_fab2_lib.baseboard_fab2(sch_1):page225_i232@mstr_discrete.cap(chips)!CAP_0603-22.0UF,4V,20%,X6S,E15A!!!F2755!A!!!!
S!GND!C8U6!2!@baseboard_fab2_lib.baseboard_fab2(sch_1):page225_i232@mstr_discrete.cap(chips)!CAP_0603-22.0UF,4V,20%,X6S,E15A!!!F2755!B!!!!
S!PVDDQ_GHJ!C8U5!1!@baseboard_fab2_lib.baseboard_fab2(sch_1):page225_i228@mstr_discrete.cap(chips)!CAP_0603-22.0UF,4V,20%,X6S,E15A!!!F2756!A!!!!
S!GND!C8U5!2!@baseboard_fab2_lib.baseboard_fab2(sch_1):page225_i228@mstr_discrete.cap(chips)!CAP_0603-22.0UF,4V,20%,X6S,E15A!!!F2756!B!!!!
S!PVDDQ_KLM!C8M1!1!@baseboard_fab2_lib.baseboard_fab2(sch_1):page228_i243@mstr_discrete.cap(chips)!CAP_0603-22.0UF,4V,20%,X6S,E15A!!!F2770!A!!!!
S!GND!C8M1!2!@baseboard_fab2_lib.baseboard_fab2(sch_1):page228_i243@mstr_discrete.cap(chips)!CAP_0603-22.0UF,4V,20%,X6S,E15A!!!F2770!B!!!!
S!PVDDQ_KLM!C7L4!1!@baseboard_fab2_lib.baseboard_fab2(sch_1):page228_i238@mstr_discrete.cap(chips)!CAP_0603-22.0UF,4V,20%,X6S,E15A!!!F2796!A!!!!
S!GND!C7L4!2!@baseboard_fab2_lib.baseboard_fab2(sch_1):page228_i238@mstr_discrete.cap(chips)!CAP_0603-22.0UF,4V,20%,X6S,E15A!!!F2796!B!!!!
S!PVDDQ_KLM!C2A4!1!@baseboard_fab2_lib.baseboard_fab2(sch_1):page228_i234@mstr_discrete.cap(chips)!CAP_0603-22.0UF,4V,20%,X6S,E15A!!!F3057!A!!!!
S!GND!C2A4!2!@baseboard_fab2_lib.baseboard_fab2(sch_1):page228_i234@mstr_discrete.cap(chips)!CAP_0603-22.0UF,4V,20%,X6S,E15A!!!F3057!B!!!!
S!PVDDQ_KLM!C2A3!1!@baseboard_fab2_lib.baseboard_fab2(sch_1):page228_i230@mstr_discrete.cap(chips)!CAP_0603-22.0UF,4V,20%,X6S,E15A!!!F3058!A!!!!
S!GND!C2A3!2!@baseboard_fab2_lib.baseboard_fab2(sch_1):page228_i230@mstr_discrete.cap(chips)!CAP_0603-22.0UF,4V,20%,X6S,E15A!!!F3058!B!!!!
S!PVDDQ_ABC!C5G12!1!@baseboard_fab2_lib.baseboard_fab2(sch_1):page217_i246@mstr_discrete.cap(chips)!CAP_0603-22.0UF,4V,20%,X6S,E15A!!!F2863!A!!!!
S!GND!C5G12!2!@baseboard_fab2_lib.baseboard_fab2(sch_1):page217_i246@mstr_discrete.cap(chips)!CAP_0603-22.0UF,4V,20%,X6S,E15A!!!F2863!B!!!!
S!PVDDQ_ABC!C5G2!1!@baseboard_fab2_lib.baseboard_fab2(sch_1):page217_i245@mstr_discrete.cap(chips)!CAP_0603-22.0UF,4V,20%,X6S,E15A!!!F2871!A!!!!
S!GND!C5G2!2!@baseboard_fab2_lib.baseboard_fab2(sch_1):page217_i245@mstr_discrete.cap(chips)!CAP_0603-22.0UF,4V,20%,X6S,E15A!!!F2871!B!!!!
S!PVDDQ_ABC!C5G4!1!@baseboard_fab2_lib.baseboard_fab2(sch_1):page217_i241@mstr_discrete.cap(chips)!CAP_0603-22.0UF,4V,20%,X6S,E15A!!!F2869!A!!!!
S!GND!C5G4!2!@baseboard_fab2_lib.baseboard_fab2(sch_1):page217_i241@mstr_discrete.cap(chips)!CAP_0603-22.0UF,4V,20%,X6S,E15A!!!F2869!B!!!!
S!PVDDQ_ABC!C5G6!1!@baseboard_fab2_lib.baseboard_fab2(sch_1):page217_i237@mstr_discrete.cap(chips)!CAP_0603-22.0UF,4V,20%,X6S,E15A!!!F2867!A!!!!
S!GND!C5G6!2!@baseboard_fab2_lib.baseboard_fab2(sch_1):page217_i237@mstr_discrete.cap(chips)!CAP_0603-22.0UF,4V,20%,X6S,E15A!!!F2867!B!!!!
S!PVDDQ_ABC!C5G5!1!@baseboard_fab2_lib.baseboard_fab2(sch_1):page217_i235@mstr_discrete.cap(chips)!CAP_0603-22.0UF,4V,20%,X6S,E15A!!!F2868!A!!!!
S!GND!C5G5!2!@baseboard_fab2_lib.baseboard_fab2(sch_1):page217_i235@mstr_discrete.cap(chips)!CAP_0603-22.0UF,4V,20%,X6S,E15A!!!F2868!B!!!!
S!PVDDQ_ABC!C5G7!1!@baseboard_fab2_lib.baseboard_fab2(sch_1):page217_i234@mstr_discrete.cap(chips)!CAP_0603-22.0UF,4V,20%,X6S,E15A!!!F2866!A!!!!
S!GND!C5G7!2!@baseboard_fab2_lib.baseboard_fab2(sch_1):page217_i234@mstr_discrete.cap(chips)!CAP_0603-22.0UF,4V,20%,X6S,E15A!!!F2866!B!!!!
S!PVDDQ_ABC!C5G8!1!@baseboard_fab2_lib.baseboard_fab2(sch_1):page217_i230@mstr_discrete.cap(chips)!CAP_0603-22.0UF,4V,20%,X6S,E15A!!!F2865!A!!!!
S!GND!C5G8!2!@baseboard_fab2_lib.baseboard_fab2(sch_1):page217_i230@mstr_discrete.cap(chips)!CAP_0603-22.0UF,4V,20%,X6S,E15A!!!F2865!B!!!!
S!PVDDQ_ABC!C5G18!1!@baseboard_fab2_lib.baseboard_fab2(sch_1):page217_i227@mstr_discrete.cap(chips)!CAP_0603-22.0UF,4V,20%,X6S,E15A!!!F2857!A!!!!
S!GND!C5G18!2!@baseboard_fab2_lib.baseboard_fab2(sch_1):page217_i227@mstr_discrete.cap(chips)!CAP_0603-22.0UF,4V,20%,X6S,E15A!!!F2857!B!!!!
S!PVDDQ_ABC!C5G17!1!@baseboard_fab2_lib.baseboard_fab2(sch_1):page217_i226@mstr_discrete.cap(chips)!CAP_0603-22.0UF,4V,20%,X6S,E15A!!!F2858!A!!!!
S!GND!C5G17!2!@baseboard_fab2_lib.baseboard_fab2(sch_1):page217_i226@mstr_discrete.cap(chips)!CAP_0603-22.0UF,4V,20%,X6S,E15A!!!F2858!B!!!!
S!PVDDQ_ABC!C5G16!1!@baseboard_fab2_lib.baseboard_fab2(sch_1):page217_i221@mstr_discrete.cap(chips)!CAP_0603-22.0UF,4V,20%,X6S,E15A!!!F2859!A!!!!
S!GND!C5G16!2!@baseboard_fab2_lib.baseboard_fab2(sch_1):page217_i221@mstr_discrete.cap(chips)!CAP_0603-22.0UF,4V,20%,X6S,E15A!!!F2859!B!!!!
S!PVDDQ_ABC!C5G15!1!@baseboard_fab2_lib.baseboard_fab2(sch_1):page217_i220@mstr_discrete.cap(chips)!CAP_0603-22.0UF,4V,20%,X6S,E15A!!!F2860!A!!!!
S!GND!C5G15!2!@baseboard_fab2_lib.baseboard_fab2(sch_1):page217_i220@mstr_discrete.cap(chips)!CAP_0603-22.0UF,4V,20%,X6S,E15A!!!F2860!B!!!!
S!PVDDQ_ABC!C5G3!1!@baseboard_fab2_lib.baseboard_fab2(sch_1):page217_i217@mstr_discrete.cap(chips)!CAP_0603-22.0UF,4V,20%,X6S,E15A!!!F2870!A!!!!
S!GND!C5G3!2!@baseboard_fab2_lib.baseboard_fab2(sch_1):page217_i217@mstr_discrete.cap(chips)!CAP_0603-22.0UF,4V,20%,X6S,E15A!!!F2870!B!!!!
S!PVDDQ_DEF!C5A15!1!@baseboard_fab2_lib.baseboard_fab2(sch_1):page220_i217@mstr_discrete.cap(chips)!CAP_0603-22.0UF,4V,20%,X6S,E15A!!!F2926!A!!!!
S!GND!C5A15!2!@baseboard_fab2_lib.baseboard_fab2(sch_1):page220_i217@mstr_discrete.cap(chips)!CAP_0603-22.0UF,4V,20%,X6S,E15A!!!F2926!B!!!!
S!PVDDQ_DEF!C5A12!1!@baseboard_fab2_lib.baseboard_fab2(sch_1):page220_i216@mstr_discrete.cap(chips)!CAP_0603-22.0UF,4V,20%,X6S,E15A!!!F2929!A!!!!
S!GND!C5A12!2!@baseboard_fab2_lib.baseboard_fab2(sch_1):page220_i216@mstr_discrete.cap(chips)!CAP_0603-22.0UF,4V,20%,X6S,E15A!!!F2929!B!!!!
S!PVDDQ_DEF!C5A13!1!@baseboard_fab2_lib.baseboard_fab2(sch_1):page220_i215@mstr_discrete.cap(chips)!CAP_0603-22.0UF,4V,20%,X6S,E15A!!!F2928!A!!!!
S!GND!C5A13!2!@baseboard_fab2_lib.baseboard_fab2(sch_1):page220_i215@mstr_discrete.cap(chips)!CAP_0603-22.0UF,4V,20%,X6S,E15A!!!F2928!B!!!!
S!PVDDQ_DEF!C5A14!1!@baseboard_fab2_lib.baseboard_fab2(sch_1):page220_i213@mstr_discrete.cap(chips)!CAP_0603-22.0UF,4V,20%,X6S,E15A!!!F2927!A!!!!
S!GND!C5A14!2!@baseboard_fab2_lib.baseboard_fab2(sch_1):page220_i213@mstr_discrete.cap(chips)!CAP_0603-22.0UF,4V,20%,X6S,E15A!!!F2927!B!!!!
S!PVDDQ_DEF!C5A6!1!@baseboard_fab2_lib.baseboard_fab2(sch_1):page220_i212@mstr_discrete.cap(chips)!CAP_0603-22.0UF,4V,20%,X6S,E15A!!!F2934!A!!!!
S!GND!C5A6!2!@baseboard_fab2_lib.baseboard_fab2(sch_1):page220_i212@mstr_discrete.cap(chips)!CAP_0603-22.0UF,4V,20%,X6S,E15A!!!F2934!B!!!!
S!PVDDQ_DEF!C5A7!1!@baseboard_fab2_lib.baseboard_fab2(sch_1):page220_i211@mstr_discrete.cap(chips)!CAP_0603-22.0UF,4V,20%,X6S,E15A!!!F2933!A!!!!
S!GND!C5A7!2!@baseboard_fab2_lib.baseboard_fab2(sch_1):page220_i211@mstr_discrete.cap(chips)!CAP_0603-22.0UF,4V,20%,X6S,E15A!!!F2933!B!!!!
S!PVDDQ_DEF!C5A8!1!@baseboard_fab2_lib.baseboard_fab2(sch_1):page220_i209@mstr_discrete.cap(chips)!CAP_0603-22.0UF,4V,20%,X6S,E15A!!!F2932!A!!!!
S!GND!C5A8!2!@baseboard_fab2_lib.baseboard_fab2(sch_1):page220_i209@mstr_discrete.cap(chips)!CAP_0603-22.0UF,4V,20%,X6S,E15A!!!F2932!B!!!!
S!PVDDQ_DEF!C5A9!1!@baseboard_fab2_lib.baseboard_fab2(sch_1):page220_i208@mstr_discrete.cap(chips)!CAP_0603-22.0UF,4V,20%,X6S,E15A!!!F2931!A!!!!
S!GND!C5A9!2!@baseboard_fab2_lib.baseboard_fab2(sch_1):page220_i208@mstr_discrete.cap(chips)!CAP_0603-22.0UF,4V,20%,X6S,E15A!!!F2931!B!!!!
S!PVDDQ_DEF!C5A16!1!@baseboard_fab2_lib.baseboard_fab2(sch_1):page220_i207@mstr_discrete.cap(chips)!CAP_0603-22.0UF,4V,20%,X6S,E15A!!!F2925!A!!!!
S!GND!C5A16!2!@baseboard_fab2_lib.baseboard_fab2(sch_1):page220_i207@mstr_discrete.cap(chips)!CAP_0603-22.0UF,4V,20%,X6S,E15A!!!F2925!B!!!!
S!PVDDQ_DEF!C5A17!1!@baseboard_fab2_lib.baseboard_fab2(sch_1):page220_i205@mstr_discrete.cap(chips)!CAP_0603-22.0UF,4V,20%,X6S,E15A!!!F2924!A!!!!
S!GND!C5A17!2!@baseboard_fab2_lib.baseboard_fab2(sch_1):page220_i205@mstr_discrete.cap(chips)!CAP_0603-22.0UF,4V,20%,X6S,E15A!!!F2924!B!!!!
S!PVDDQ_DEF!C5A18!1!@baseboard_fab2_lib.baseboard_fab2(sch_1):page220_i204@mstr_discrete.cap(chips)!CAP_0603-22.0UF,4V,20%,X6S,E15A!!!F2923!A!!!!
S!GND!C5A18!2!@baseboard_fab2_lib.baseboard_fab2(sch_1):page220_i204@mstr_discrete.cap(chips)!CAP_0603-22.0UF,4V,20%,X6S,E15A!!!F2923!B!!!!
S!PVDDQ_DEF!C5A19!1!@baseboard_fab2_lib.baseboard_fab2(sch_1):page220_i203@mstr_discrete.cap(chips)!CAP_0603-22.0UF,4V,20%,X6S,E15A!!!F2922!A!!!!
S!GND!C5A19!2!@baseboard_fab2_lib.baseboard_fab2(sch_1):page220_i203@mstr_discrete.cap(chips)!CAP_0603-22.0UF,4V,20%,X6S,E15A!!!F2922!B!!!!
S!PVDDQ_GHJ!C8U2!1!@baseboard_fab2_lib.baseboard_fab2(sch_1):page225_i239@mstr_discrete.cap(chips)!CAP_0603-22.0UF,4V,20%,X6S,E15A!!!F2759!A!!!!
S!GND!C8U2!2!@baseboard_fab2_lib.baseboard_fab2(sch_1):page225_i239@mstr_discrete.cap(chips)!CAP_0603-22.0UF,4V,20%,X6S,E15A!!!F2759!B!!!!
S!PVDDQ_GHJ!C7U2!1!@baseboard_fab2_lib.baseboard_fab2(sch_1):page225_i238@mstr_discrete.cap(chips)!CAP_0603-22.0UF,4V,20%,X6S,E15A!!!F2786!A!!!!
S!GND!C7U2!2!@baseboard_fab2_lib.baseboard_fab2(sch_1):page225_i238@mstr_discrete.cap(chips)!CAP_0603-22.0UF,4V,20%,X6S,E15A!!!F2786!B!!!!
S!PVDDQ_GHJ!C7U1!1!@baseboard_fab2_lib.baseboard_fab2(sch_1):page225_i237@mstr_discrete.cap(chips)!CAP_0603-22.0UF,4V,20%,X6S,E15A!!!F2787!A!!!!
S!GND!C7U1!2!@baseboard_fab2_lib.baseboard_fab2(sch_1):page225_i237@mstr_discrete.cap(chips)!CAP_0603-22.0UF,4V,20%,X6S,E15A!!!F2787!B!!!!
S!PVDDQ_GHJ!C7T4!1!@baseboard_fab2_lib.baseboard_fab2(sch_1):page225_i235@mstr_discrete.cap(chips)!CAP_0603-22.0UF,4V,20%,X6S,E15A!!!F2789!A!!!!
S!GND!C7T4!2!@baseboard_fab2_lib.baseboard_fab2(sch_1):page225_i235@mstr_discrete.cap(chips)!CAP_0603-22.0UF,4V,20%,X6S,E15A!!!F2789!B!!!!
S!PVDDQ_GHJ!C7T5!1!@baseboard_fab2_lib.baseboard_fab2(sch_1):page225_i234@mstr_discrete.cap(chips)!CAP_0603-22.0UF,4V,20%,X6S,E15A!!!F2788!A!!!!
S!GND!C7T5!2!@baseboard_fab2_lib.baseboard_fab2(sch_1):page225_i234@mstr_discrete.cap(chips)!CAP_0603-22.0UF,4V,20%,X6S,E15A!!!F2788!B!!!!
S!PVDDQ_GHJ!C8T5!1!@baseboard_fab2_lib.baseboard_fab2(sch_1):page225_i233@mstr_discrete.cap(chips)!CAP_0603-22.0UF,4V,20%,X6S,E15A!!!F2765!A!!!!
S!GND!C8T5!2!@baseboard_fab2_lib.baseboard_fab2(sch_1):page225_i233@mstr_discrete.cap(chips)!CAP_0603-22.0UF,4V,20%,X6S,E15A!!!F2765!B!!!!
S!PVDDQ_GHJ!C8T6!1!@baseboard_fab2_lib.baseboard_fab2(sch_1):page225_i231@mstr_discrete.cap(chips)!CAP_0603-22.0UF,4V,20%,X6S,E15A!!!F2764!A!!!!
S!GND!C8T6!2!@baseboard_fab2_lib.baseboard_fab2(sch_1):page225_i231@mstr_discrete.cap(chips)!CAP_0603-22.0UF,4V,20%,X6S,E15A!!!F2764!B!!!!
S!PVDDQ_GHJ!C8T7!1!@baseboard_fab2_lib.baseboard_fab2(sch_1):page225_i230@mstr_discrete.cap(chips)!CAP_0603-22.0UF,4V,20%,X6S,E15A!!!F2763!A!!!!
S!GND!C8T7!2!@baseboard_fab2_lib.baseboard_fab2(sch_1):page225_i230@mstr_discrete.cap(chips)!CAP_0603-22.0UF,4V,20%,X6S,E15A!!!F2763!B!!!!
S!PVDDQ_GHJ!C8T8!1!@baseboard_fab2_lib.baseboard_fab2(sch_1):page225_i229@mstr_discrete.cap(chips)!CAP_0603-22.0UF,4V,20%,X6S,E15A!!!F2762!A!!!!
S!GND!C8T8!2!@baseboard_fab2_lib.baseboard_fab2(sch_1):page225_i229@mstr_discrete.cap(chips)!CAP_0603-22.0UF,4V,20%,X6S,E15A!!!F2762!B!!!!
S!PVDDQ_GHJ!C8T9!1!@baseboard_fab2_lib.baseboard_fab2(sch_1):page225_i227@mstr_discrete.cap(chips)!CAP_0603-22.0UF,4V,20%,X6S,E15A!!!F2761!A!!!!
S!GND!C8T9!2!@baseboard_fab2_lib.baseboard_fab2(sch_1):page225_i227@mstr_discrete.cap(chips)!CAP_0603-22.0UF,4V,20%,X6S,E15A!!!F2761!B!!!!
S!PVDDQ_GHJ!C8T10!1!@baseboard_fab2_lib.baseboard_fab2(sch_1):page225_i226@mstr_discrete.cap(chips)!CAP_0603-22.0UF,4V,20%,X6S,E15A!!!F2760!A!!!!
S!GND!C8T10!2!@baseboard_fab2_lib.baseboard_fab2(sch_1):page225_i226@mstr_discrete.cap(chips)!CAP_0603-22.0UF,4V,20%,X6S,E15A!!!F2760!B!!!!
S!PVDDQ_GHJ!C8U4!1!@baseboard_fab2_lib.baseboard_fab2(sch_1):page225_i225@mstr_discrete.cap(chips)!CAP_0603-22.0UF,4V,20%,X6S,E15A!!!F2757!A!!!!
S!GND!C8U4!2!@baseboard_fab2_lib.baseboard_fab2(sch_1):page225_i225@mstr_discrete.cap(chips)!CAP_0603-22.0UF,4V,20%,X6S,E15A!!!F2757!B!!!!
S!PVDDQ_KLM!C8L5!1!@baseboard_fab2_lib.baseboard_fab2(sch_1):page228_i241@mstr_discrete.cap(chips)!CAP_0603-22.0UF,4V,20%,X6S,E15A!!!F2776!A!!!!
S!GND!C8L5!2!@baseboard_fab2_lib.baseboard_fab2(sch_1):page228_i241@mstr_discrete.cap(chips)!CAP_0603-22.0UF,4V,20%,X6S,E15A!!!F2776!B!!!!
S!PVDDQ_KLM!C8L6!1!@baseboard_fab2_lib.baseboard_fab2(sch_1):page228_i240@mstr_discrete.cap(chips)!CAP_0603-22.0UF,4V,20%,X6S,E15A!!!F2775!A!!!!
S!GND!C8L6!2!@baseboard_fab2_lib.baseboard_fab2(sch_1):page228_i240@mstr_discrete.cap(chips)!CAP_0603-22.0UF,4V,20%,X6S,E15A!!!F2775!B!!!!
S!PVDDQ_KLM!C8L7!1!@baseboard_fab2_lib.baseboard_fab2(sch_1):page228_i239@mstr_discrete.cap(chips)!CAP_0603-22.0UF,4V,20%,X6S,E15A!!!F2774!A!!!!
S!GND!C8L7!2!@baseboard_fab2_lib.baseboard_fab2(sch_1):page228_i239@mstr_discrete.cap(chips)!CAP_0603-22.0UF,4V,20%,X6S,E15A!!!F2774!B!!!!
S!PVDDQ_KLM!C8L8!1!@baseboard_fab2_lib.baseboard_fab2(sch_1):page228_i237@mstr_discrete.cap(chips)!CAP_0603-22.0UF,4V,20%,X6S,E15A!!!F2773!A!!!!
S!GND!C8L8!2!@baseboard_fab2_lib.baseboard_fab2(sch_1):page228_i237@mstr_discrete.cap(chips)!CAP_0603-22.0UF,4V,20%,X6S,E15A!!!F2773!B!!!!
S!PVDDQ_KLM!C8L9!1!@baseboard_fab2_lib.baseboard_fab2(sch_1):page228_i236@mstr_discrete.cap(chips)!CAP_0603-22.0UF,4V,20%,X6S,E15A!!!F2772!A!!!!
S!GND!C8L9!2!@baseboard_fab2_lib.baseboard_fab2(sch_1):page228_i236@mstr_discrete.cap(chips)!CAP_0603-22.0UF,4V,20%,X6S,E15A!!!F2772!B!!!!
S!PVDDQ_KLM!C8M6!1!@baseboard_fab2_lib.baseboard_fab2(sch_1):page228_i235@mstr_discrete.cap(chips)!CAP_0603-22.0UF,4V,20%,X6S,E15A!!!F2766!A!!!!
S!GND!C8M6!2!@baseboard_fab2_lib.baseboard_fab2(sch_1):page228_i235@mstr_discrete.cap(chips)!CAP_0603-22.0UF,4V,20%,X6S,E15A!!!F2766!B!!!!
S!PVDDQ_KLM!C8M4!1!@baseboard_fab2_lib.baseboard_fab2(sch_1):page228_i233@mstr_discrete.cap(chips)!CAP_0603-22.0UF,4V,20%,X6S,E15A!!!F2768!A!!!!
S!GND!C8M4!2!@baseboard_fab2_lib.baseboard_fab2(sch_1):page228_i233@mstr_discrete.cap(chips)!CAP_0603-22.0UF,4V,20%,X6S,E15A!!!F2768!B!!!!
S!PVDDQ_KLM!C7M2!1!@baseboard_fab2_lib.baseboard_fab2(sch_1):page228_i232@mstr_discrete.cap(chips)!CAP_0603-22.0UF,4V,20%,X6S,E15A!!!F2793!A!!!!
S!GND!C7M2!2!@baseboard_fab2_lib.baseboard_fab2(sch_1):page228_i232@mstr_discrete.cap(chips)!CAP_0603-22.0UF,4V,20%,X6S,E15A!!!F2793!B!!!!
S!PVDDQ_KLM!C7M1!1!@baseboard_fab2_lib.baseboard_fab2(sch_1):page228_i231@mstr_discrete.cap(chips)!CAP_0603-22.0UF,4V,20%,X6S,E15A!!!F2794!A!!!!
S!GND!C7M1!2!@baseboard_fab2_lib.baseboard_fab2(sch_1):page228_i231@mstr_discrete.cap(chips)!CAP_0603-22.0UF,4V,20%,X6S,E15A!!!F2794!B!!!!
S!PVDDQ_KLM!C8L10!1!@baseboard_fab2_lib.baseboard_fab2(sch_1):page228_i229@mstr_discrete.cap(chips)!CAP_0603-22.0UF,4V,20%,X6S,E15A!!!F2771!A!!!!
S!GND!C8L10!2!@baseboard_fab2_lib.baseboard_fab2(sch_1):page228_i229@mstr_discrete.cap(chips)!CAP_0603-22.0UF,4V,20%,X6S,E15A!!!F2771!B!!!!
S!PVDDQ_KLM!C8M5!1!@baseboard_fab2_lib.baseboard_fab2(sch_1):page228_i228@mstr_discrete.cap(chips)!CAP_0603-22.0UF,4V,20%,X6S,E15A!!!F2767!A!!!!
S!GND!C8M5!2!@baseboard_fab2_lib.baseboard_fab2(sch_1):page228_i228@mstr_discrete.cap(chips)!CAP_0603-22.0UF,4V,20%,X6S,E15A!!!F2767!B!!!!
S!PVDDQ_KLM!C8M3!1!@baseboard_fab2_lib.baseboard_fab2(sch_1):page228_i227@mstr_discrete.cap(chips)!CAP_0603-22.0UF,4V,20%,X6S,E15A!!!F2769!A!!!!
S!GND!C8M3!2!@baseboard_fab2_lib.baseboard_fab2(sch_1):page228_i227@mstr_discrete.cap(chips)!CAP_0603-22.0UF,4V,20%,X6S,E15A!!!F2769!B!!!!
S!PVDDQ_GHJ!C2G9!1!@baseboard_fab2_lib.baseboard_fab2(sch_1):page225_i218@mstr_discrete.cap(chips)!CAP_0603-22.0UF,4V,20%,X6S,E15A!!!F3006!A!!!!
S!GND!C2G9!2!@baseboard_fab2_lib.baseboard_fab2(sch_1):page225_i218@mstr_discrete.cap(chips)!CAP_0603-22.0UF,4V,20%,X6S,E15A!!!F3006!B!!!!
S!PVDDQ_GHJ!C2G10!1!@baseboard_fab2_lib.baseboard_fab2(sch_1):page225_i223@mstr_discrete.cap(chips)!CAP_0603-22.0UF,4V,20%,X6S,E15A!!!F3005!A!!!!
S!GND!C2G10!2!@baseboard_fab2_lib.baseboard_fab2(sch_1):page225_i223@mstr_discrete.cap(chips)!CAP_0603-22.0UF,4V,20%,X6S,E15A!!!F3005!B!!!!
S!PVDDQ_GHJ!C2G11!1!@baseboard_fab2_lib.baseboard_fab2(sch_1):page225_i221@mstr_discrete.cap(chips)!CAP_0603-22.0UF,4V,20%,X6S,E15A!!!F3004!A!!!!
S!GND!C2G11!2!@baseboard_fab2_lib.baseboard_fab2(sch_1):page225_i221@mstr_discrete.cap(chips)!CAP_0603-22.0UF,4V,20%,X6S,E15A!!!F3004!B!!!!
S!PVDDQ_GHJ!C2G12!1!@baseboard_fab2_lib.baseboard_fab2(sch_1):page225_i220@mstr_discrete.cap(chips)!CAP_0603-22.0UF,4V,20%,X6S,E15A!!!F3003!A!!!!
S!GND!C2G12!2!@baseboard_fab2_lib.baseboard_fab2(sch_1):page225_i220@mstr_discrete.cap(chips)!CAP_0603-22.0UF,4V,20%,X6S,E15A!!!F3003!B!!!!
S!PVDDQ_GHJ!C2G1!1!@baseboard_fab2_lib.baseboard_fab2(sch_1):page225_i219@mstr_discrete.cap(chips)!CAP_0603-22.0UF,4V,20%,X6S,E15A!!!F3012!A!!!!
S!GND!C2G1!2!@baseboard_fab2_lib.baseboard_fab2(sch_1):page225_i219@mstr_discrete.cap(chips)!CAP_0603-22.0UF,4V,20%,X6S,E15A!!!F3012!B!!!!
S!PVDDQ_GHJ!C2G2!1!@baseboard_fab2_lib.baseboard_fab2(sch_1):page225_i217@mstr_discrete.cap(chips)!CAP_0603-22.0UF,4V,20%,X6S,E15A!!!F3011!A!!!!
S!GND!C2G2!2!@baseboard_fab2_lib.baseboard_fab2(sch_1):page225_i217@mstr_discrete.cap(chips)!CAP_0603-22.0UF,4V,20%,X6S,E15A!!!F3011!B!!!!
S!PVDDQ_GHJ!C2G3!1!@baseboard_fab2_lib.baseboard_fab2(sch_1):page225_i216@mstr_discrete.cap(chips)!CAP_0603-22.0UF,4V,20%,X6S,E15A!!!F3010!A!!!!
S!GND!C2G3!2!@baseboard_fab2_lib.baseboard_fab2(sch_1):page225_i216@mstr_discrete.cap(chips)!CAP_0603-22.0UF,4V,20%,X6S,E15A!!!F3010!B!!!!
S!PVDDQ_GHJ!C2G4!1!@baseboard_fab2_lib.baseboard_fab2(sch_1):page225_i215@mstr_discrete.cap(chips)!CAP_0603-22.0UF,4V,20%,X6S,E15A!!!F3009!A!!!!
S!GND!C2G4!2!@baseboard_fab2_lib.baseboard_fab2(sch_1):page225_i215@mstr_discrete.cap(chips)!CAP_0603-22.0UF,4V,20%,X6S,E15A!!!F3009!B!!!!
S!PVDDQ_GHJ!C2G5!1!@baseboard_fab2_lib.baseboard_fab2(sch_1):page225_i214@mstr_discrete.cap(chips)!CAP_0603-22.0UF,4V,20%,X6S,E15A!!!F3008!A!!!!
S!GND!C2G5!2!@baseboard_fab2_lib.baseboard_fab2(sch_1):page225_i214@mstr_discrete.cap(chips)!CAP_0603-22.0UF,4V,20%,X6S,E15A!!!F3008!B!!!!
S!PVDDQ_GHJ!C2G6!1!@baseboard_fab2_lib.baseboard_fab2(sch_1):page225_i213@mstr_discrete.cap(chips)!CAP_0603-22.0UF,4V,20%,X6S,E15A!!!F3007!A!!!!
S!GND!C2G6!2!@baseboard_fab2_lib.baseboard_fab2(sch_1):page225_i213@mstr_discrete.cap(chips)!CAP_0603-22.0UF,4V,20%,X6S,E15A!!!F3007!B!!!!
S!PVDDQ_GHJ!C3G1!1!@baseboard_fab2_lib.baseboard_fab2(sch_1):page225_i212@mstr_discrete.cap(chips)!CAP_0603-22.0UF,4V,20%,X6S,E15A!!!F2967!A!!!!
S!GND!C3G1!2!@baseboard_fab2_lib.baseboard_fab2(sch_1):page225_i212@mstr_discrete.cap(chips)!CAP_0603-22.0UF,4V,20%,X6S,E15A!!!F2967!B!!!!
S!PVDDQ_GHJ!C3G2!1!@baseboard_fab2_lib.baseboard_fab2(sch_1):page225_i211@mstr_discrete.cap(chips)!CAP_0603-22.0UF,4V,20%,X6S,E15A!!!F2966!A!!!!
S!GND!C3G2!2!@baseboard_fab2_lib.baseboard_fab2(sch_1):page225_i211@mstr_discrete.cap(chips)!CAP_0603-22.0UF,4V,20%,X6S,E15A!!!F2966!B!!!!
S!PVDDQ_GHJ!C2G13!1!@baseboard_fab2_lib.baseboard_fab2(sch_1):page225_i210@mstr_discrete.cap(chips)!CAP_0603-22.0UF,4V,20%,X6S,E15A!!!F3002!A!!!!
S!GND!C2G13!2!@baseboard_fab2_lib.baseboard_fab2(sch_1):page225_i210@mstr_discrete.cap(chips)!CAP_0603-22.0UF,4V,20%,X6S,E15A!!!F3002!B!!!!
S!PVDDQ_GHJ!C2G14!1!@baseboard_fab2_lib.baseboard_fab2(sch_1):page225_i209@mstr_discrete.cap(chips)!CAP_0603-22.0UF,4V,20%,X6S,E15A!!!F3001!A!!!!
S!GND!C2G14!2!@baseboard_fab2_lib.baseboard_fab2(sch_1):page225_i209@mstr_discrete.cap(chips)!CAP_0603-22.0UF,4V,20%,X6S,E15A!!!F3001!B!!!!
S!PVDDQ_GHJ!C3G5!1!@baseboard_fab2_lib.baseboard_fab2(sch_1):page225_i208@mstr_discrete.cap(chips)!CAP_0603-22.0UF,4V,20%,X6S,E15A!!!F2965!A!!!!
S!GND!C3G5!2!@baseboard_fab2_lib.baseboard_fab2(sch_1):page225_i208@mstr_discrete.cap(chips)!CAP_0603-22.0UF,4V,20%,X6S,E15A!!!F2965!B!!!!
S!PVDDQ_GHJ!C3G6!1!@baseboard_fab2_lib.baseboard_fab2(sch_1):page225_i207@mstr_discrete.cap(chips)!CAP_0603-22.0UF,4V,20%,X6S,E15A!!!F2964!A!!!!
S!GND!C3G6!2!@baseboard_fab2_lib.baseboard_fab2(sch_1):page225_i207@mstr_discrete.cap(chips)!CAP_0603-22.0UF,4V,20%,X6S,E15A!!!F2964!B!!!!
S!PVDDQ_KLM!C7L5!1!@baseboard_fab2_lib.baseboard_fab2(sch_1):page228_i225@mstr_discrete.cap(chips)!CAP_0603-22.0UF,4V,20%,X6S,E15A!!!F2795!A!!!!
S!GND!C7L5!2!@baseboard_fab2_lib.baseboard_fab2(sch_1):page228_i225@mstr_discrete.cap(chips)!CAP_0603-22.0UF,4V,20%,X6S,E15A!!!F2795!B!!!!
S!PVDDQ_KLM!C3A6!1!@baseboard_fab2_lib.baseboard_fab2(sch_1):page228_i223@mstr_discrete.cap(chips)!CAP_0603-22.0UF,4V,20%,X6S,E15A!!!F2992!A!!!!
S!GND!C3A6!2!@baseboard_fab2_lib.baseboard_fab2(sch_1):page228_i223@mstr_discrete.cap(chips)!CAP_0603-22.0UF,4V,20%,X6S,E15A!!!F2992!B!!!!
S!PVDDQ_KLM!C3A5!1!@baseboard_fab2_lib.baseboard_fab2(sch_1):page228_i222@mstr_discrete.cap(chips)!CAP_0603-22.0UF,4V,20%,X6S,E15A!!!F2993!A!!!!
S!GND!C3A5!2!@baseboard_fab2_lib.baseboard_fab2(sch_1):page228_i222@mstr_discrete.cap(chips)!CAP_0603-22.0UF,4V,20%,X6S,E15A!!!F2993!B!!!!
S!PVDDQ_KLM!C2A15!1!@baseboard_fab2_lib.baseboard_fab2(sch_1):page228_i221@mstr_discrete.cap(chips)!CAP_0603-22.0UF,4V,20%,X6S,E15A!!!F3048!A!!!!
S!GND!C2A15!2!@baseboard_fab2_lib.baseboard_fab2(sch_1):page228_i221@mstr_discrete.cap(chips)!CAP_0603-22.0UF,4V,20%,X6S,E15A!!!F3048!B!!!!
S!PVDDQ_KLM!C2A14!1!@baseboard_fab2_lib.baseboard_fab2(sch_1):page228_i220@mstr_discrete.cap(chips)!CAP_0603-22.0UF,4V,20%,X6S,E15A!!!F3049!A!!!!
S!GND!C2A14!2!@baseboard_fab2_lib.baseboard_fab2(sch_1):page228_i220@mstr_discrete.cap(chips)!CAP_0603-22.0UF,4V,20%,X6S,E15A!!!F3049!B!!!!
S!PVDDQ_KLM!C2A6!1!@baseboard_fab2_lib.baseboard_fab2(sch_1):page228_i219@mstr_discrete.cap(chips)!CAP_0603-22.0UF,4V,20%,X6S,E15A!!!F3056!A!!!!
S!GND!C2A6!2!@baseboard_fab2_lib.baseboard_fab2(sch_1):page228_i219@mstr_discrete.cap(chips)!CAP_0603-22.0UF,4V,20%,X6S,E15A!!!F3056!B!!!!
S!PVDDQ_KLM!C2A7!1!@baseboard_fab2_lib.baseboard_fab2(sch_1):page228_i218@mstr_discrete.cap(chips)!CAP_0603-22.0UF,4V,20%,X6S,E15A!!!F3055!A!!!!
S!GND!C2A7!2!@baseboard_fab2_lib.baseboard_fab2(sch_1):page228_i218@mstr_discrete.cap(chips)!CAP_0603-22.0UF,4V,20%,X6S,E15A!!!F3055!B!!!!
S!PVDDQ_KLM!C3A1!1!@baseboard_fab2_lib.baseboard_fab2(sch_1):page228_i217@mstr_discrete.cap(chips)!CAP_0603-22.0UF,4V,20%,X6S,E15A!!!F2995!A!!!!
S!GND!C3A1!2!@baseboard_fab2_lib.baseboard_fab2(sch_1):page228_i217@mstr_discrete.cap(chips)!CAP_0603-22.0UF,4V,20%,X6S,E15A!!!F2995!B!!!!
S!PVDDQ_KLM!C3A2!1!@baseboard_fab2_lib.baseboard_fab2(sch_1):page228_i216@mstr_discrete.cap(chips)!CAP_0603-22.0UF,4V,20%,X6S,E15A!!!F2994!A!!!!
S!GND!C3A2!2!@baseboard_fab2_lib.baseboard_fab2(sch_1):page228_i216@mstr_discrete.cap(chips)!CAP_0603-22.0UF,4V,20%,X6S,E15A!!!F2994!B!!!!
S!PVDDQ_KLM!C2A9!1!@baseboard_fab2_lib.baseboard_fab2(sch_1):page228_i215@mstr_discrete.cap(chips)!CAP_0603-22.0UF,4V,20%,X6S,E15A!!!F3054!A!!!!
S!GND!C2A9!2!@baseboard_fab2_lib.baseboard_fab2(sch_1):page228_i215@mstr_discrete.cap(chips)!CAP_0603-22.0UF,4V,20%,X6S,E15A!!!F3054!B!!!!
S!PVDDQ_KLM!C2A10!1!@baseboard_fab2_lib.baseboard_fab2(sch_1):page228_i214@mstr_discrete.cap(chips)!CAP_0603-22.0UF,4V,20%,X6S,E15A!!!F3053!A!!!!
S!GND!C2A10!2!@baseboard_fab2_lib.baseboard_fab2(sch_1):page228_i214@mstr_discrete.cap(chips)!CAP_0603-22.0UF,4V,20%,X6S,E15A!!!F3053!B!!!!
S!PVDDQ_KLM!C2A11!1!@baseboard_fab2_lib.baseboard_fab2(sch_1):page228_i213@mstr_discrete.cap(chips)!CAP_0603-22.0UF,4V,20%,X6S,E15A!!!F3052!A!!!!
S!GND!C2A11!2!@baseboard_fab2_lib.baseboard_fab2(sch_1):page228_i213@mstr_discrete.cap(chips)!CAP_0603-22.0UF,4V,20%,X6S,E15A!!!F3052!B!!!!
S!PVDDQ_KLM!C2A13!1!@baseboard_fab2_lib.baseboard_fab2(sch_1):page228_i212@mstr_discrete.cap(chips)!CAP_0603-22.0UF,4V,20%,X6S,E15A!!!F3050!A!!!!
S!GND!C2A13!2!@baseboard_fab2_lib.baseboard_fab2(sch_1):page228_i212@mstr_discrete.cap(chips)!CAP_0603-22.0UF,4V,20%,X6S,E15A!!!F3050!B!!!!
S!PVDDQ_KLM!C2A12!1!@baseboard_fab2_lib.baseboard_fab2(sch_1):page228_i211@mstr_discrete.cap(chips)!CAP_0603-22.0UF,4V,20%,X6S,E15A!!!F3051!A!!!!
S!GND!C2A12!2!@baseboard_fab2_lib.baseboard_fab2(sch_1):page228_i211@mstr_discrete.cap(chips)!CAP_0603-22.0UF,4V,20%,X6S,E15A!!!F3051!B!!!!
S!PVDDQ_KLM!C2A1!1!@baseboard_fab2_lib.baseboard_fab2(sch_1):page228_i210@mstr_discrete.cap(chips)!CAP_0603-22.0UF,4V,20%,X6S,E15A!!!F3060!A!!!!
S!GND!C2A1!2!@baseboard_fab2_lib.baseboard_fab2(sch_1):page228_i210@mstr_discrete.cap(chips)!CAP_0603-22.0UF,4V,20%,X6S,E15A!!!F3060!B!!!!
S!PVDDQ_KLM!C2A2!1!@baseboard_fab2_lib.baseboard_fab2(sch_1):page228_i209@mstr_discrete.cap(chips)!CAP_0603-22.0UF,4V,20%,X6S,E15A!!!F3059!A!!!!
S!GND!C2A2!2!@baseboard_fab2_lib.baseboard_fab2(sch_1):page228_i209@mstr_discrete.cap(chips)!CAP_0603-22.0UF,4V,20%,X6S,E15A!!!F3059!B!!!!
S!PVDDQ_ABC!C5U2!1!@baseboard_fab2_lib.baseboard_fab2(sch_1):page217_i247@mstr_discrete.cap(chips)!CAP_0603-22.0UF,4V,20%,X6S,E15A!!!F2834!A!!!!
S!GND!C5U2!2!@baseboard_fab2_lib.baseboard_fab2(sch_1):page217_i247@mstr_discrete.cap(chips)!CAP_0603-22.0UF,4V,20%,X6S,E15A!!!F2834!B!!!!
S!PVDDQ_ABC!C5U3!1!@baseboard_fab2_lib.baseboard_fab2(sch_1):page217_i244@mstr_discrete.cap(chips)!CAP_0603-22.0UF,4V,20%,X6S,E15A!!!F2833!A!!!!
S!GND!C5U3!2!@baseboard_fab2_lib.baseboard_fab2(sch_1):page217_i244@mstr_discrete.cap(chips)!CAP_0603-22.0UF,4V,20%,X6S,E15A!!!F2833!B!!!!
S!PVDDQ_ABC!C5U4!1!@baseboard_fab2_lib.baseboard_fab2(sch_1):page217_i243@mstr_discrete.cap(chips)!CAP_0603-22.0UF,4V,20%,X6S,E15A!!!F2832!A!!!!
S!GND!C5U4!2!@baseboard_fab2_lib.baseboard_fab2(sch_1):page217_i243@mstr_discrete.cap(chips)!CAP_0603-22.0UF,4V,20%,X6S,E15A!!!F2832!B!!!!
S!PVDDQ_ABC!C5U5!1!@baseboard_fab2_lib.baseboard_fab2(sch_1):page217_i239@mstr_discrete.cap(chips)!CAP_0603-22.0UF,4V,20%,X6S,E15A!!!F2831!A!!!!
S!GND!C5U5!2!@baseboard_fab2_lib.baseboard_fab2(sch_1):page217_i239@mstr_discrete.cap(chips)!CAP_0603-22.0UF,4V,20%,X6S,E15A!!!F2831!B!!!!
S!PVDDQ_ABC!C5U6!1!@baseboard_fab2_lib.baseboard_fab2(sch_1):page217_i238@mstr_discrete.cap(chips)!CAP_0603-22.0UF,4V,20%,X6S,E15A!!!F2830!A!!!!
S!GND!C5U6!2!@baseboard_fab2_lib.baseboard_fab2(sch_1):page217_i238@mstr_discrete.cap(chips)!CAP_0603-22.0UF,4V,20%,X6S,E15A!!!F2830!B!!!!
S!PVDDQ_ABC!C5U7!1!@baseboard_fab2_lib.baseboard_fab2(sch_1):page217_i236@mstr_discrete.cap(chips)!CAP_0603-22.0UF,4V,20%,X6S,E15A!!!F2829!A!!!!
S!GND!C5U7!2!@baseboard_fab2_lib.baseboard_fab2(sch_1):page217_i236@mstr_discrete.cap(chips)!CAP_0603-22.0UF,4V,20%,X6S,E15A!!!F2829!B!!!!
S!PVDDQ_ABC!C5U8!1!@baseboard_fab2_lib.baseboard_fab2(sch_1):page217_i233@mstr_discrete.cap(chips)!CAP_0603-22.0UF,4V,20%,X6S,E15A!!!F2828!A!!!!
S!GND!C5U8!2!@baseboard_fab2_lib.baseboard_fab2(sch_1):page217_i233@mstr_discrete.cap(chips)!CAP_0603-22.0UF,4V,20%,X6S,E15A!!!F2828!B!!!!
S!PVDDQ_ABC!C5U9!1!@baseboard_fab2_lib.baseboard_fab2(sch_1):page217_i232@mstr_discrete.cap(chips)!CAP_0603-22.0UF,4V,20%,X6S,E15A!!!F2827!A!!!!
S!GND!C5U9!2!@baseboard_fab2_lib.baseboard_fab2(sch_1):page217_i232@mstr_discrete.cap(chips)!CAP_0603-22.0UF,4V,20%,X6S,E15A!!!F2827!B!!!!
S!PVDDQ_ABC!C5T12!1!@baseboard_fab2_lib.baseboard_fab2(sch_1):page217_i229@mstr_discrete.cap(chips)!CAP_0603-22.0UF,4V,20%,X6S,E15A!!!F2835!A!!!!
S!GND!C5T12!2!@baseboard_fab2_lib.baseboard_fab2(sch_1):page217_i229@mstr_discrete.cap(chips)!CAP_0603-22.0UF,4V,20%,X6S,E15A!!!F2835!B!!!!
S!PVDDQ_ABC!C5T11!1!@baseboard_fab2_lib.baseboard_fab2(sch_1):page217_i228@mstr_discrete.cap(chips)!CAP_0603-22.0UF,4V,20%,X6S,E15A!!!F2836!A!!!!
S!GND!C5T11!2!@baseboard_fab2_lib.baseboard_fab2(sch_1):page217_i228@mstr_discrete.cap(chips)!CAP_0603-22.0UF,4V,20%,X6S,E15A!!!F2836!B!!!!
S!PVDDQ_ABC!C5T10!1!@baseboard_fab2_lib.baseboard_fab2(sch_1):page217_i225@mstr_discrete.cap(chips)!CAP_0603-22.0UF,4V,20%,X6S,E15A!!!F2837!A!!!!
S!GND!C5T10!2!@baseboard_fab2_lib.baseboard_fab2(sch_1):page217_i225@mstr_discrete.cap(chips)!CAP_0603-22.0UF,4V,20%,X6S,E15A!!!F2837!B!!!!
S!PVDDQ_ABC!C5T9!1!@baseboard_fab2_lib.baseboard_fab2(sch_1):page217_i224@mstr_discrete.cap(chips)!CAP_0603-22.0UF,4V,20%,X6S,E15A!!!F2838!A!!!!
S!GND!C5T9!2!@baseboard_fab2_lib.baseboard_fab2(sch_1):page217_i224@mstr_discrete.cap(chips)!CAP_0603-22.0UF,4V,20%,X6S,E15A!!!F2838!B!!!!
S!PVDDQ_ABC!C5T8!1!@baseboard_fab2_lib.baseboard_fab2(sch_1):page217_i222@mstr_discrete.cap(chips)!CAP_0603-22.0UF,4V,20%,X6S,E15A!!!F2839!A!!!!
S!GND!C5T8!2!@baseboard_fab2_lib.baseboard_fab2(sch_1):page217_i222@mstr_discrete.cap(chips)!CAP_0603-22.0UF,4V,20%,X6S,E15A!!!F2839!B!!!!
S!PVDDQ_ABC!C5T7!1!@baseboard_fab2_lib.baseboard_fab2(sch_1):page217_i219@mstr_discrete.cap(chips)!CAP_0603-22.0UF,4V,20%,X6S,E15A!!!F2840!A!!!!
S!GND!C5T7!2!@baseboard_fab2_lib.baseboard_fab2(sch_1):page217_i219@mstr_discrete.cap(chips)!CAP_0603-22.0UF,4V,20%,X6S,E15A!!!F2840!B!!!!
S!PVDDQ_ABC!C5T6!1!@baseboard_fab2_lib.baseboard_fab2(sch_1):page217_i218@mstr_discrete.cap(chips)!CAP_0603-22.0UF,4V,20%,X6S,E15A!!!F2841!A!!!!
S!GND!C5T6!2!@baseboard_fab2_lib.baseboard_fab2(sch_1):page217_i218@mstr_discrete.cap(chips)!CAP_0603-22.0UF,4V,20%,X6S,E15A!!!F2841!B!!!!
S!PVDDQ_ABC!C5T5!1!@baseboard_fab2_lib.baseboard_fab2(sch_1):page217_i216@mstr_discrete.cap(chips)!CAP_0603-22.0UF,4V,20%,X6S,E15A!!!F2842!A!!!!
S!GND!C5T5!2!@baseboard_fab2_lib.baseboard_fab2(sch_1):page217_i216@mstr_discrete.cap(chips)!CAP_0603-22.0UF,4V,20%,X6S,E15A!!!F2842!B!!!!
S!PVDDQ_DEF!C5L6!1!@baseboard_fab2_lib.baseboard_fab2(sch_1):page220_i237@mstr_discrete.cap(chips)!CAP_0603-22.0UF,4V,20%,X6S,E15A!!!F2856!A!!!!
S!GND!C5L6!2!@baseboard_fab2_lib.baseboard_fab2(sch_1):page220_i237@mstr_discrete.cap(chips)!CAP_0603-22.0UF,4V,20%,X6S,E15A!!!F2856!B!!!!
S!PVDDQ_DEF!C5L7!1!@baseboard_fab2_lib.baseboard_fab2(sch_1):page220_i236@mstr_discrete.cap(chips)!CAP_0603-22.0UF,4V,20%,X6S,E15A!!!F2855!A!!!!
S!GND!C5L7!2!@baseboard_fab2_lib.baseboard_fab2(sch_1):page220_i236@mstr_discrete.cap(chips)!CAP_0603-22.0UF,4V,20%,X6S,E15A!!!F2855!B!!!!
S!PVDDQ_DEF!C5L8!1!@baseboard_fab2_lib.baseboard_fab2(sch_1):page220_i234@mstr_discrete.cap(chips)!CAP_0603-22.0UF,4V,20%,X6S,E15A!!!F2854!A!!!!
S!GND!C5L8!2!@baseboard_fab2_lib.baseboard_fab2(sch_1):page220_i234@mstr_discrete.cap(chips)!CAP_0603-22.0UF,4V,20%,X6S,E15A!!!F2854!B!!!!
S!PVDDQ_DEF!C5L9!1!@baseboard_fab2_lib.baseboard_fab2(sch_1):page220_i233@mstr_discrete.cap(chips)!CAP_0603-22.0UF,4V,20%,X6S,E15A!!!F2853!A!!!!
S!GND!C5L9!2!@baseboard_fab2_lib.baseboard_fab2(sch_1):page220_i233@mstr_discrete.cap(chips)!CAP_0603-22.0UF,4V,20%,X6S,E15A!!!F2853!B!!!!
S!PVDDQ_DEF!C5L10!1!@baseboard_fab2_lib.baseboard_fab2(sch_1):page220_i232@mstr_discrete.cap(chips)!CAP_0603-22.0UF,4V,20%,X6S,E15A!!!F2852!A!!!!
S!GND!C5L10!2!@baseboard_fab2_lib.baseboard_fab2(sch_1):page220_i232@mstr_discrete.cap(chips)!CAP_0603-22.0UF,4V,20%,X6S,E15A!!!F2852!B!!!!
S!PVDDQ_DEF!C5L11!1!@baseboard_fab2_lib.baseboard_fab2(sch_1):page220_i231@mstr_discrete.cap(chips)!CAP_0603-22.0UF,4V,20%,X6S,E15A!!!F2851!A!!!!
S!GND!C5L11!2!@baseboard_fab2_lib.baseboard_fab2(sch_1):page220_i231@mstr_discrete.cap(chips)!CAP_0603-22.0UF,4V,20%,X6S,E15A!!!F2851!B!!!!
S!PVDDQ_DEF!C5L12!1!@baseboard_fab2_lib.baseboard_fab2(sch_1):page220_i230@mstr_discrete.cap(chips)!CAP_0603-22.0UF,4V,20%,X6S,E15A!!!F2850!A!!!!
S!GND!C5L12!2!@baseboard_fab2_lib.baseboard_fab2(sch_1):page220_i230@mstr_discrete.cap(chips)!CAP_0603-22.0UF,4V,20%,X6S,E15A!!!F2850!B!!!!
S!PVDDQ_DEF!C5L13!1!@baseboard_fab2_lib.baseboard_fab2(sch_1):page220_i229@mstr_discrete.cap(chips)!CAP_0603-22.0UF,4V,20%,X6S,E15A!!!F2849!A!!!!
S!GND!C5L13!2!@baseboard_fab2_lib.baseboard_fab2(sch_1):page220_i229@mstr_discrete.cap(chips)!CAP_0603-22.0UF,4V,20%,X6S,E15A!!!F2849!B!!!!
S!PVDDQ_DEF!C5M7!1!@baseboard_fab2_lib.baseboard_fab2(sch_1):page220_i228@mstr_discrete.cap(chips)!CAP_0603-22.0UF,4V,20%,X6S,E15A!!!F2843!A!!!!
S!GND!C5M7!2!@baseboard_fab2_lib.baseboard_fab2(sch_1):page220_i228@mstr_discrete.cap(chips)!CAP_0603-22.0UF,4V,20%,X6S,E15A!!!F2843!B!!!!
S!PVDDQ_DEF!C5M6!1!@baseboard_fab2_lib.baseboard_fab2(sch_1):page220_i227@mstr_discrete.cap(chips)!CAP_0603-22.0UF,4V,20%,X6S,E15A!!!F2844!A!!!!
S!GND!C5M6!2!@baseboard_fab2_lib.baseboard_fab2(sch_1):page220_i227@mstr_discrete.cap(chips)!CAP_0603-22.0UF,4V,20%,X6S,E15A!!!F2844!B!!!!
S!PVDDQ_DEF!C5M5!1!@baseboard_fab2_lib.baseboard_fab2(sch_1):page220_i226@mstr_discrete.cap(chips)!CAP_0603-22.0UF,4V,20%,X6S,E15A!!!F2845!A!!!!
S!GND!C5M5!2!@baseboard_fab2_lib.baseboard_fab2(sch_1):page220_i226@mstr_discrete.cap(chips)!CAP_0603-22.0UF,4V,20%,X6S,E15A!!!F2845!B!!!!
S!PVDDQ_DEF!C5M4!1!@baseboard_fab2_lib.baseboard_fab2(sch_1):page220_i225@mstr_discrete.cap(chips)!CAP_0603-22.0UF,4V,20%,X6S,E15A!!!F2846!A!!!!
S!GND!C5M4!2!@baseboard_fab2_lib.baseboard_fab2(sch_1):page220_i225@mstr_discrete.cap(chips)!CAP_0603-22.0UF,4V,20%,X6S,E15A!!!F2846!B!!!!
S!PVDDQ_DEF!C5M2!1!@baseboard_fab2_lib.baseboard_fab2(sch_1):page220_i224@mstr_discrete.cap(chips)!CAP_0603-22.0UF,4V,20%,X6S,E15A!!!F2847!A!!!!
S!GND!C5M2!2!@baseboard_fab2_lib.baseboard_fab2(sch_1):page220_i224@mstr_discrete.cap(chips)!CAP_0603-22.0UF,4V,20%,X6S,E15A!!!F2847!B!!!!
S!PVDDQ_DEF!C5M1!1!@baseboard_fab2_lib.baseboard_fab2(sch_1):page220_i223@mstr_discrete.cap(chips)!CAP_0603-22.0UF,4V,20%,X6S,E15A!!!F2848!A!!!!
S!GND!C5M1!2!@baseboard_fab2_lib.baseboard_fab2(sch_1):page220_i223@mstr_discrete.cap(chips)!CAP_0603-22.0UF,4V,20%,X6S,E15A!!!F2848!B!!!!
S!PVDDQ_DEF!C4M2!1!@baseboard_fab2_lib.baseboard_fab2(sch_1):page220_i222@mstr_discrete.cap(chips)!CAP_0603-22.0UF,4V,20%,X6S,E15A!!!F2941!A!!!!
S!GND!C4M2!2!@baseboard_fab2_lib.baseboard_fab2(sch_1):page220_i222@mstr_discrete.cap(chips)!CAP_0603-22.0UF,4V,20%,X6S,E15A!!!F2941!B!!!!
S!PVDDQ_DEF!C5A11!1!@baseboard_fab2_lib.baseboard_fab2(sch_1):page220_i221@mstr_discrete.cap(chips)!CAP_0603-22.0UF,4V,20%,X6S,E15A!!!F2930!A!!!!
S!GND!C5A11!2!@baseboard_fab2_lib.baseboard_fab2(sch_1):page220_i221@mstr_discrete.cap(chips)!CAP_0603-22.0UF,4V,20%,X6S,E15A!!!F2930!B!!!!
S!PVCCIN_CPU0!C5D44!1!@baseboard_fab2_lib.baseboard_fab2(sch_1):page42_i142@mstr_discrete.cap(chips)!CAP_0603-22.0UF,4V,20%,X6S,E15A!!!F2886!A!!!!
S!GND!C5D44!2!@baseboard_fab2_lib.baseboard_fab2(sch_1):page42_i142@mstr_discrete.cap(chips)!CAP_0603-22.0UF,4V,20%,X6S,E15A!!!F2886!B!!!!
S!PVCCIN_CPU0!C5D4!1!@baseboard_fab2_lib.baseboard_fab2(sch_1):page42_i127@mstr_discrete.cap(chips)!CAP_0603-22.0UF,4V,20%,X6S,E15A!!!F2918!A!!!!
S!GND!C5D4!2!@baseboard_fab2_lib.baseboard_fab2(sch_1):page42_i127@mstr_discrete.cap(chips)!CAP_0603-22.0UF,4V,20%,X6S,E15A!!!F2918!B!!!!
S!PVCCIN_CPU0!C5D3!1!@baseboard_fab2_lib.baseboard_fab2(sch_1):page42_i130@mstr_discrete.cap(chips)!CAP_0603-22.0UF,4V,20%,X6S,E15A!!!F2919!A!!!!
S!GND!C5D3!2!@baseboard_fab2_lib.baseboard_fab2(sch_1):page42_i130@mstr_discrete.cap(chips)!CAP_0603-22.0UF,4V,20%,X6S,E15A!!!F2919!B!!!!
S!PVCCIN_CPU0!C5D2!1!@baseboard_fab2_lib.baseboard_fab2(sch_1):page42_i136@mstr_discrete.cap(chips)!CAP_0603-22.0UF,4V,20%,X6S,E15A!!!F2920!A!!!!
S!GND!C5D2!2!@baseboard_fab2_lib.baseboard_fab2(sch_1):page42_i136@mstr_discrete.cap(chips)!CAP_0603-22.0UF,4V,20%,X6S,E15A!!!F2920!B!!!!
S!PVCCIN_CPU0!C5D1!1!@baseboard_fab2_lib.baseboard_fab2(sch_1):page42_i126@mstr_discrete.cap(chips)!CAP_0603-22.0UF,4V,20%,X6S,E15A!!!F2921!A!!!!
S!GND!C5D1!2!@baseboard_fab2_lib.baseboard_fab2(sch_1):page42_i126@mstr_discrete.cap(chips)!CAP_0603-22.0UF,4V,20%,X6S,E15A!!!F2921!B!!!!
S!PVCCIN_CPU0!C5D59!1!@baseboard_fab2_lib.baseboard_fab2(sch_1):page42_i129@mstr_discrete.cap(chips)!CAP_0603-22.0UF,4V,20%,X6S,E15A!!!F2875!A!!!!
S!GND!C5D59!2!@baseboard_fab2_lib.baseboard_fab2(sch_1):page42_i129@mstr_discrete.cap(chips)!CAP_0603-22.0UF,4V,20%,X6S,E15A!!!F2875!B!!!!
S!PVCCIN_CPU0!C5D42!1!@baseboard_fab2_lib.baseboard_fab2(sch_1):page42_i135@mstr_discrete.cap(chips)!CAP_0603-22.0UF,4V,20%,X6S,E15A!!!F2888!A!!!!
S!GND!C5D42!2!@baseboard_fab2_lib.baseboard_fab2(sch_1):page42_i135@mstr_discrete.cap(chips)!CAP_0603-22.0UF,4V,20%,X6S,E15A!!!F2888!B!!!!
S!PVCCIN_CPU0!C5D5!1!@baseboard_fab2_lib.baseboard_fab2(sch_1):page42_i125@mstr_discrete.cap(chips)!CAP_0603-22.0UF,4V,20%,X6S,E15A!!!F2917!A!!!!
S!GND!C5D5!2!@baseboard_fab2_lib.baseboard_fab2(sch_1):page42_i125@mstr_discrete.cap(chips)!CAP_0603-22.0UF,4V,20%,X6S,E15A!!!F2917!B!!!!
S!PVCCIN_CPU0!C5D19!1!@baseboard_fab2_lib.baseboard_fab2(sch_1):page42_i128@mstr_discrete.cap(chips)!CAP_0603-22.0UF,4V,20%,X6S,E15A!!!F2911!A!!!!
S!GND!C5D19!2!@baseboard_fab2_lib.baseboard_fab2(sch_1):page42_i128@mstr_discrete.cap(chips)!CAP_0603-22.0UF,4V,20%,X6S,E15A!!!F2911!B!!!!
S!PVCCIN_CPU0!C5D18!1!@baseboard_fab2_lib.baseboard_fab2(sch_1):page42_i134@mstr_discrete.cap(chips)!CAP_0603-22.0UF,4V,20%,X6S,E15A!!!F2912!A!!!!
S!GND!C5D18!2!@baseboard_fab2_lib.baseboard_fab2(sch_1):page42_i134@mstr_discrete.cap(chips)!CAP_0603-22.0UF,4V,20%,X6S,E15A!!!F2912!B!!!!
S!PVCCIN_CPU0!C5D17!1!@baseboard_fab2_lib.baseboard_fab2(sch_1):page42_i118@mstr_discrete.cap(chips)!CAP_0603-22.0UF,4V,20%,X6S,E15A!!!F2913!A!!!!
S!GND!C5D17!2!@baseboard_fab2_lib.baseboard_fab2(sch_1):page42_i118@mstr_discrete.cap(chips)!CAP_0603-22.0UF,4V,20%,X6S,E15A!!!F2913!B!!!!
S!PVCCIN_CPU0!C5D16!1!@baseboard_fab2_lib.baseboard_fab2(sch_1):page42_i123@mstr_discrete.cap(chips)!CAP_0603-22.0UF,4V,20%,X6S,E15A!!!F2914!A!!!!
S!GND!C5D16!2!@baseboard_fab2_lib.baseboard_fab2(sch_1):page42_i123@mstr_discrete.cap(chips)!CAP_0603-22.0UF,4V,20%,X6S,E15A!!!F2914!B!!!!
S!PVCCIN_CPU0!C5D15!1!@baseboard_fab2_lib.baseboard_fab2(sch_1):page42_i132@mstr_discrete.cap(chips)!CAP_0603-22.0UF,4V,20%,X6S,E15A!!!F2915!A!!!!
S!GND!C5D15!2!@baseboard_fab2_lib.baseboard_fab2(sch_1):page42_i132@mstr_discrete.cap(chips)!CAP_0603-22.0UF,4V,20%,X6S,E15A!!!F2915!B!!!!
S!PVCCIN_CPU0!C5D14!1!@baseboard_fab2_lib.baseboard_fab2(sch_1):page42_i117@mstr_discrete.cap(chips)!CAP_0603-22.0UF,4V,20%,X6S,E15A!!!F2916!A!!!!
S!GND!C5D14!2!@baseboard_fab2_lib.baseboard_fab2(sch_1):page42_i117@mstr_discrete.cap(chips)!CAP_0603-22.0UF,4V,20%,X6S,E15A!!!F2916!B!!!!
S!PVCCIN_CPU0!C5D58!1!@baseboard_fab2_lib.baseboard_fab2(sch_1):page42_i120@mstr_discrete.cap(chips)!CAP_0603-22.0UF,4V,20%,X6S,E15A!!!F2876!A!!!!
S!GND!C5D58!2!@baseboard_fab2_lib.baseboard_fab2(sch_1):page42_i120@mstr_discrete.cap(chips)!CAP_0603-22.0UF,4V,20%,X6S,E15A!!!F2876!B!!!!
S!PVCCIN_CPU0!C5D43!1!@baseboard_fab2_lib.baseboard_fab2(sch_1):page42_i131@mstr_discrete.cap(chips)!CAP_0603-22.0UF,4V,20%,X6S,E15A!!!F2887!A!!!!
S!GND!C5D43!2!@baseboard_fab2_lib.baseboard_fab2(sch_1):page42_i131@mstr_discrete.cap(chips)!CAP_0603-22.0UF,4V,20%,X6S,E15A!!!F2887!B!!!!
S!PVCCIN_CPU0!C5D60!1!@baseboard_fab2_lib.baseboard_fab2(sch_1):page42_i112@mstr_discrete.cap(chips)!CAP_0603-22.0UF,4V,20%,X6S,E15A!!!F2874!A!!!!
S!GND!C5D60!2!@baseboard_fab2_lib.baseboard_fab2(sch_1):page42_i112@mstr_discrete.cap(chips)!CAP_0603-22.0UF,4V,20%,X6S,E15A!!!F2874!B!!!!
S!PVCCIN_CPU0!C5D32!1!@baseboard_fab2_lib.baseboard_fab2(sch_1):page42_i103@mstr_discrete.cap(chips)!CAP_0603-22.0UF,4V,20%,X6S,E15A!!!F2898!A!!!!
S!GND!C5D32!2!@baseboard_fab2_lib.baseboard_fab2(sch_1):page42_i103@mstr_discrete.cap(chips)!CAP_0603-22.0UF,4V,20%,X6S,E15A!!!F2898!B!!!!
S!PVCCIN_CPU0!C5D31!1!@baseboard_fab2_lib.baseboard_fab2(sch_1):page42_i106@mstr_discrete.cap(chips)!CAP_0603-22.0UF,4V,20%,X6S,E15A!!!F2899!A!!!!
S!GND!C5D31!2!@baseboard_fab2_lib.baseboard_fab2(sch_1):page42_i106@mstr_discrete.cap(chips)!CAP_0603-22.0UF,4V,20%,X6S,E15A!!!F2899!B!!!!
S!PVCCIN_CPU0!C5D30!1!@baseboard_fab2_lib.baseboard_fab2(sch_1):page42_i111@mstr_discrete.cap(chips)!CAP_0603-22.0UF,4V,20%,X6S,E15A!!!F2900!A!!!!
S!GND!C5D30!2!@baseboard_fab2_lib.baseboard_fab2(sch_1):page42_i111@mstr_discrete.cap(chips)!CAP_0603-22.0UF,4V,20%,X6S,E15A!!!F2900!B!!!!
S!PVCCIN_CPU0!C5D29!1!@baseboard_fab2_lib.baseboard_fab2(sch_1):page42_i102@mstr_discrete.cap(chips)!CAP_0603-22.0UF,4V,20%,X6S,E15A!!!F2901!A!!!!
S!GND!C5D29!2!@baseboard_fab2_lib.baseboard_fab2(sch_1):page42_i102@mstr_discrete.cap(chips)!CAP_0603-22.0UF,4V,20%,X6S,E15A!!!F2901!B!!!!
S!PVCCIN_CPU0!C5D26!1!@baseboard_fab2_lib.baseboard_fab2(sch_1):page42_i154@mstr_discrete.cap(chips)!CAP_0603-22.0UF,4V,20%,X6S,E15A!!!F2904!A!!!!
S!GND!C5D26!2!@baseboard_fab2_lib.baseboard_fab2(sch_1):page42_i154@mstr_discrete.cap(chips)!CAP_0603-22.0UF,4V,20%,X6S,E15A!!!F2904!B!!!!
S!PVCCIN_CPU0!C5D24!1!@baseboard_fab2_lib.baseboard_fab2(sch_1):page42_i138@mstr_discrete.cap(chips)!CAP_0603-22.0UF,4V,20%,X6S,E15A!!!F2906!A!!!!
S!GND!C5D24!2!@baseboard_fab2_lib.baseboard_fab2(sch_1):page42_i138@mstr_discrete.cap(chips)!CAP_0603-22.0UF,4V,20%,X6S,E15A!!!F2906!B!!!!
S!PVCCIN_CPU0!C5D39!1!@baseboard_fab2_lib.baseboard_fab2(sch_1):page42_i140@mstr_discrete.cap(chips)!CAP_0603-22.0UF,4V,20%,X6S,E15A!!!F2891!A!!!!
S!GND!C5D39!2!@baseboard_fab2_lib.baseboard_fab2(sch_1):page42_i140@mstr_discrete.cap(chips)!CAP_0603-22.0UF,4V,20%,X6S,E15A!!!F2891!B!!!!
S!PVCCIN_CPU0!C5D40!1!@baseboard_fab2_lib.baseboard_fab2(sch_1):page42_i115@mstr_discrete.cap(chips)!CAP_0603-22.0UF,4V,20%,X6S,E15A!!!F2890!A!!!!
S!GND!C5D40!2!@baseboard_fab2_lib.baseboard_fab2(sch_1):page42_i115@mstr_discrete.cap(chips)!CAP_0603-22.0UF,4V,20%,X6S,E15A!!!F2890!B!!!!
S!PVCCIN_CPU0!C5D41!1!@baseboard_fab2_lib.baseboard_fab2(sch_1):page42_i114@mstr_discrete.cap(chips)!CAP_0603-22.0UF,4V,20%,X6S,E15A!!!F2889!A!!!!
S!GND!C5D41!2!@baseboard_fab2_lib.baseboard_fab2(sch_1):page42_i114@mstr_discrete.cap(chips)!CAP_0603-22.0UF,4V,20%,X6S,E15A!!!F2889!B!!!!
S!PVCCIN_CPU0!C5D61!1!@baseboard_fab2_lib.baseboard_fab2(sch_1):page42_i113@mstr_discrete.cap(chips)!CAP_0603-22.0UF,4V,20%,X6S,E15A!!!F2873!A!!!!
S!GND!C5D61!2!@baseboard_fab2_lib.baseboard_fab2(sch_1):page42_i113@mstr_discrete.cap(chips)!CAP_0603-22.0UF,4V,20%,X6S,E15A!!!F2873!B!!!!
S!PVCCIN_CPU0!C5D47!1!@baseboard_fab2_lib.baseboard_fab2(sch_1):page42_i104@mstr_discrete.cap(chips)!CAP_0603-22.0UF,4V,20%,X6S,E15A!!!F2883!A!!!!
S!GND!C5D47!2!@baseboard_fab2_lib.baseboard_fab2(sch_1):page42_i104@mstr_discrete.cap(chips)!CAP_0603-22.0UF,4V,20%,X6S,E15A!!!F2883!B!!!!
S!PVCCIN_CPU0!C5D46!1!@baseboard_fab2_lib.baseboard_fab2(sch_1):page42_i107@mstr_discrete.cap(chips)!CAP_0603-22.0UF,4V,20%,X6S,E15A!!!F2884!A!!!!
S!GND!C5D46!2!@baseboard_fab2_lib.baseboard_fab2(sch_1):page42_i107@mstr_discrete.cap(chips)!CAP_0603-22.0UF,4V,20%,X6S,E15A!!!F2884!B!!!!
S!PVCCMCP_CPU1!C3D10!1!@baseboard_fab2_lib.baseboard_fab2(sch_1):page76_i196@mstr_discrete.cap(chips)!CAP_0603-22.0UF,4V,20%,X6S,E15A!!!F2983!A!!!!
S!GND!C3D10!2!@baseboard_fab2_lib.baseboard_fab2(sch_1):page76_i196@mstr_discrete.cap(chips)!CAP_0603-22.0UF,4V,20%,X6S,E15A!!!F2983!B!!!!
S!PVCCIN_CPU1!C2D34!1!@baseboard_fab2_lib.baseboard_fab2(sch_1):page76_i122@mstr_discrete.cap(chips)!CAP_0603-22.0UF,4V,20%,X6S,E15A!!!F3022!A!!!!
S!GND!C2D34!2!@baseboard_fab2_lib.baseboard_fab2(sch_1):page76_i122@mstr_discrete.cap(chips)!CAP_0603-22.0UF,4V,20%,X6S,E15A!!!F3022!B!!!!
S!PVCCIN_CPU1!C2D16!1!@baseboard_fab2_lib.baseboard_fab2(sch_1):page76_i124@mstr_discrete.cap(chips)!CAP_0603-22.0UF,4V,20%,X6S,E15A!!!F3040!A!!!!
S!GND!C2D16!2!@baseboard_fab2_lib.baseboard_fab2(sch_1):page76_i124@mstr_discrete.cap(chips)!CAP_0603-22.0UF,4V,20%,X6S,E15A!!!F3040!B!!!!
S!PVCCIN_CPU1!C2D36!1!@baseboard_fab2_lib.baseboard_fab2(sch_1):page76_i70@mstr_discrete.cap(chips)!CAP_0603-22.0UF,4V,20%,X6S,E15A!!!F3020!A!!!!
S!GND!C2D36!2!@baseboard_fab2_lib.baseboard_fab2(sch_1):page76_i70@mstr_discrete.cap(chips)!CAP_0603-22.0UF,4V,20%,X6S,E15A!!!F3020!B!!!!
S!PVCCIN_CPU1!C2D37!1!@baseboard_fab2_lib.baseboard_fab2(sch_1):page76_i119@mstr_discrete.cap(chips)!CAP_0603-22.0UF,4V,20%,X6S,E15A!!!F3019!A!!!!
S!GND!C2D37!2!@baseboard_fab2_lib.baseboard_fab2(sch_1):page76_i119@mstr_discrete.cap(chips)!CAP_0603-22.0UF,4V,20%,X6S,E15A!!!F3019!B!!!!
S!PVCCIN_CPU1!C2D45!1!@baseboard_fab2_lib.baseboard_fab2(sch_1):page76_i123@mstr_discrete.cap(chips)!CAP_0603-22.0UF,4V,20%,X6S,E15A!!!F3015!A!!!!
S!GND!C2D45!2!@baseboard_fab2_lib.baseboard_fab2(sch_1):page76_i123@mstr_discrete.cap(chips)!CAP_0603-22.0UF,4V,20%,X6S,E15A!!!F3015!B!!!!
S!PVCCIN_CPU1!C3D2!1!@baseboard_fab2_lib.baseboard_fab2(sch_1):page76_i69@mstr_discrete.cap(chips)!CAP_0603-22.0UF,4V,20%,X6S,E15A!!!F2990!A!!!!
S!GND!C3D2!2!@baseboard_fab2_lib.baseboard_fab2(sch_1):page76_i69@mstr_discrete.cap(chips)!CAP_0603-22.0UF,4V,20%,X6S,E15A!!!F2990!B!!!!
S!PVCCIN_CPU1!C3D1!1!@baseboard_fab2_lib.baseboard_fab2(sch_1):page76_i111@mstr_discrete.cap(chips)!CAP_0603-22.0UF,4V,20%,X6S,E15A!!!F2991!A!!!!
S!GND!C3D1!2!@baseboard_fab2_lib.baseboard_fab2(sch_1):page76_i111@mstr_discrete.cap(chips)!CAP_0603-22.0UF,4V,20%,X6S,E15A!!!F2991!B!!!!
S!PVCCIN_CPU1!C2D1!1!@baseboard_fab2_lib.baseboard_fab2(sch_1):page76_i116@mstr_discrete.cap(chips)!CAP_0603-22.0UF,4V,20%,X6S,E15A!!!F3047!A!!!!
S!GND!C2D1!2!@baseboard_fab2_lib.baseboard_fab2(sch_1):page76_i116@mstr_discrete.cap(chips)!CAP_0603-22.0UF,4V,20%,X6S,E15A!!!F3047!B!!!!
S!PVCCMCP_CPU1!C2D18!1!@baseboard_fab2_lib.baseboard_fab2(sch_1):page76_i197@mstr_discrete.cap(chips)!CAP_0603-22.0UF,4V,20%,X6S,E15A!!!F3038!A!!!!
S!GND!C2D18!2!@baseboard_fab2_lib.baseboard_fab2(sch_1):page76_i197@mstr_discrete.cap(chips)!CAP_0603-22.0UF,4V,20%,X6S,E15A!!!F3038!B!!!!
S!PVCCIN_CPU1!C2D17!1!@baseboard_fab2_lib.baseboard_fab2(sch_1):page76_i114@mstr_discrete.cap(chips)!CAP_0603-22.0UF,4V,20%,X6S,E15A!!!F3039!A!!!!
S!GND!C2D17!2!@baseboard_fab2_lib.baseboard_fab2(sch_1):page76_i114@mstr_discrete.cap(chips)!CAP_0603-22.0UF,4V,20%,X6S,E15A!!!F3039!B!!!!
S!PVCCIN_CPU1!C2D27!1!@baseboard_fab2_lib.baseboard_fab2(sch_1):page76_i66@mstr_discrete.cap(chips)!CAP_0603-22.0UF,4V,20%,X6S,E15A!!!F3029!A!!!!
S!GND!C2D27!2!@baseboard_fab2_lib.baseboard_fab2(sch_1):page76_i66@mstr_discrete.cap(chips)!CAP_0603-22.0UF,4V,20%,X6S,E15A!!!F3029!B!!!!
S!PVCCIN_CPU1!C2D26!1!@baseboard_fab2_lib.baseboard_fab2(sch_1):page76_i108@mstr_discrete.cap(chips)!CAP_0603-22.0UF,4V,20%,X6S,E15A!!!F3030!A!!!!
S!GND!C2D26!2!@baseboard_fab2_lib.baseboard_fab2(sch_1):page76_i108@mstr_discrete.cap(chips)!CAP_0603-22.0UF,4V,20%,X6S,E15A!!!F3030!B!!!!
S!PVCCIN_CPU1!C2D23!1!@baseboard_fab2_lib.baseboard_fab2(sch_1):page76_i112@mstr_discrete.cap(chips)!CAP_0603-22.0UF,4V,20%,X6S,E15A!!!F3033!A!!!!
S!GND!C2D23!2!@baseboard_fab2_lib.baseboard_fab2(sch_1):page76_i112@mstr_discrete.cap(chips)!CAP_0603-22.0UF,4V,20%,X6S,E15A!!!F3033!B!!!!
S!PVCCIN_CPU1!C2D21!1!@baseboard_fab2_lib.baseboard_fab2(sch_1):page76_i65@mstr_discrete.cap(chips)!CAP_0603-22.0UF,4V,20%,X6S,E15A!!!F3035!A!!!!
S!GND!C2D21!2!@baseboard_fab2_lib.baseboard_fab2(sch_1):page76_i65@mstr_discrete.cap(chips)!CAP_0603-22.0UF,4V,20%,X6S,E15A!!!F3035!B!!!!
S!PVCCIN_CPU1!C2D33!1!@baseboard_fab2_lib.baseboard_fab2(sch_1):page76_i85@mstr_discrete.cap(chips)!CAP_0603-22.0UF,4V,20%,X6S,E15A!!!F3023!A!!!!
S!GND!C2D33!2!@baseboard_fab2_lib.baseboard_fab2(sch_1):page76_i85@mstr_discrete.cap(chips)!CAP_0603-22.0UF,4V,20%,X6S,E15A!!!F3023!B!!!!
S!PVCCIN_CPU1!C2D32!1!@baseboard_fab2_lib.baseboard_fab2(sch_1):page76_i90@mstr_discrete.cap(chips)!CAP_0603-22.0UF,4V,20%,X6S,E15A!!!F3024!A!!!!
S!GND!C2D32!2!@baseboard_fab2_lib.baseboard_fab2(sch_1):page76_i90@mstr_discrete.cap(chips)!CAP_0603-22.0UF,4V,20%,X6S,E15A!!!F3024!B!!!!
S!PVCCIN_CPU1!C2D31!1!@baseboard_fab2_lib.baseboard_fab2(sch_1):page76_i63@mstr_discrete.cap(chips)!CAP_0603-22.0UF,4V,20%,X6S,E15A!!!F3025!A!!!!
S!GND!C2D31!2!@baseboard_fab2_lib.baseboard_fab2(sch_1):page76_i63@mstr_discrete.cap(chips)!CAP_0603-22.0UF,4V,20%,X6S,E15A!!!F3025!B!!!!
S!PVCCIN_CPU1!C2D30!1!@baseboard_fab2_lib.baseboard_fab2(sch_1):page76_i83@mstr_discrete.cap(chips)!CAP_0603-22.0UF,4V,20%,X6S,E15A!!!F3026!A!!!!
S!GND!C2D30!2!@baseboard_fab2_lib.baseboard_fab2(sch_1):page76_i83@mstr_discrete.cap(chips)!CAP_0603-22.0UF,4V,20%,X6S,E15A!!!F3026!B!!!!
S!PVCCMCP_CPU1!C2D29!1!@baseboard_fab2_lib.baseboard_fab2(sch_1):page76_i199@mstr_discrete.cap(chips)!CAP_0603-22.0UF,4V,20%,X6S,E15A!!!F3027!A!!!!
S!GND!C2D29!2!@baseboard_fab2_lib.baseboard_fab2(sch_1):page76_i199@mstr_discrete.cap(chips)!CAP_0603-22.0UF,4V,20%,X6S,E15A!!!F3027!B!!!!
S!PVCCMCP_CPU1!C2D28!1!@baseboard_fab2_lib.baseboard_fab2(sch_1):page76_i198@mstr_discrete.cap(chips)!CAP_0603-22.0UF,4V,20%,X6S,E15A!!!F3028!A!!!!
S!GND!C2D28!2!@baseboard_fab2_lib.baseboard_fab2(sch_1):page76_i198@mstr_discrete.cap(chips)!CAP_0603-22.0UF,4V,20%,X6S,E15A!!!F3028!B!!!!
S!PVCCIN_CPU1!C2D25!1!@baseboard_fab2_lib.baseboard_fab2(sch_1):page76_i82@mstr_discrete.cap(chips)!CAP_0603-22.0UF,4V,20%,X6S,E15A!!!F3031!A!!!!
S!GND!C2D25!2!@baseboard_fab2_lib.baseboard_fab2(sch_1):page76_i82@mstr_discrete.cap(chips)!CAP_0603-22.0UF,4V,20%,X6S,E15A!!!F3031!B!!!!
S!PVCCIN_CPU1!C2D24!1!@baseboard_fab2_lib.baseboard_fab2(sch_1):page76_i80@mstr_discrete.cap(chips)!CAP_0603-22.0UF,4V,20%,X6S,E15A!!!F3032!A!!!!
S!GND!C2D24!2!@baseboard_fab2_lib.baseboard_fab2(sch_1):page76_i80@mstr_discrete.cap(chips)!CAP_0603-22.0UF,4V,20%,X6S,E15A!!!F3032!B!!!!
S!PVCCIN_CPU1!C2D22!1!@baseboard_fab2_lib.baseboard_fab2(sch_1):page76_i61@mstr_discrete.cap(chips)!CAP_0603-22.0UF,4V,20%,X6S,E15A!!!F3034!A!!!!
S!GND!C2D22!2!@baseboard_fab2_lib.baseboard_fab2(sch_1):page76_i61@mstr_discrete.cap(chips)!CAP_0603-22.0UF,4V,20%,X6S,E15A!!!F3034!B!!!!
S!PVCCIN_CPU1!C2D19!1!@baseboard_fab2_lib.baseboard_fab2(sch_1):page76_i75@mstr_discrete.cap(chips)!CAP_0603-22.0UF,4V,20%,X6S,E15A!!!F3037!A!!!!
S!GND!C2D19!2!@baseboard_fab2_lib.baseboard_fab2(sch_1):page76_i75@mstr_discrete.cap(chips)!CAP_0603-22.0UF,4V,20%,X6S,E15A!!!F3037!B!!!!
S!PVCCIN_CPU1!C2D20!1!@baseboard_fab2_lib.baseboard_fab2(sch_1):page76_i79@mstr_discrete.cap(chips)!CAP_0603-22.0UF,4V,20%,X6S,E15A!!!F3036!A!!!!
S!GND!C2D20!2!@baseboard_fab2_lib.baseboard_fab2(sch_1):page76_i79@mstr_discrete.cap(chips)!CAP_0603-22.0UF,4V,20%,X6S,E15A!!!F3036!B!!!!
S!PVCCIN_CPU1!C2D12!1!@baseboard_fab2_lib.baseboard_fab2(sch_1):page76_i59@mstr_discrete.cap(chips)!CAP_0603-22.0UF,4V,20%,X6S,E15A!!!F3044!A!!!!
S!GND!C2D12!2!@baseboard_fab2_lib.baseboard_fab2(sch_1):page76_i59@mstr_discrete.cap(chips)!CAP_0603-22.0UF,4V,20%,X6S,E15A!!!F3044!B!!!!
S!PVCCIN_CPU1!C2D15!1!@baseboard_fab2_lib.baseboard_fab2(sch_1):page76_i159@mstr_discrete.cap(chips)!CAP_0603-22.0UF,4V,20%,X6S,E15A!!!F3041!A!!!!
S!GND!C2D15!2!@baseboard_fab2_lib.baseboard_fab2(sch_1):page76_i159@mstr_discrete.cap(chips)!CAP_0603-22.0UF,4V,20%,X6S,E15A!!!F3041!B!!!!
S!PVCCIO_CPU1!C3E1!1!@baseboard_fab2_lib.baseboard_fab2(sch_1):page214_i108@mstr_discrete.cap(chips)!CAP_0603-22.0UF,4V,20%,X6S,E15A!!!F2968!A!!!!
S!GND!C3E1!2!@baseboard_fab2_lib.baseboard_fab2(sch_1):page214_i108@mstr_discrete.cap(chips)!CAP_0603-22.0UF,4V,20%,X6S,E15A!!!F2968!B!!!!
S!PVCCIO_CPU0!C7C6!1!@baseboard_fab2_lib.baseboard_fab2(sch_1):page212_i23@mstr_discrete.cap(chips)!CAP_0603-22.0UF,4V,20%,X6S,E15A!!!F2800!A!!!!
S!GND!C7C6!2!@baseboard_fab2_lib.baseboard_fab2(sch_1):page212_i23@mstr_discrete.cap(chips)!CAP_0603-22.0UF,4V,20%,X6S,E15A!!!F2800!B!!!!
S!PVCCIO_CPU1!C7R1!1!@baseboard_fab2_lib.baseboard_fab2(sch_1):page214_i65@mstr_discrete.cap(chips)!CAP_0603-22.0UF,4V,20%,X6S,E15A!!!F2790!A!!!!
S!GND!C7R1!2!@baseboard_fab2_lib.baseboard_fab2(sch_1):page214_i65@mstr_discrete.cap(chips)!CAP_0603-22.0UF,4V,20%,X6S,E15A!!!F2790!B!!!!
S!PVCCIO_CPU0!C7C10!1!@baseboard_fab2_lib.baseboard_fab2(sch_1):page212_i77@mstr_discrete.cap(chips)!CAP_0603-22.0UF,4V,20%,X6S,E15A!!!F2798!A!!!!
S!GND!C7C10!2!@baseboard_fab2_lib.baseboard_fab2(sch_1):page212_i77@mstr_discrete.cap(chips)!CAP_0603-22.0UF,4V,20%,X6S,E15A!!!F2798!B!!!!
S!PVCCIN_CPU0!C4E11!1!@baseboard_fab2_lib.baseboard_fab2(sch_1):page202_i27@mstr_discrete.cap(chips)!CAP_0603-22.0UF,4V,20%,X6S,E15A!!!F2942!A!!!!
S!GND!C4E11!2!@baseboard_fab2_lib.baseboard_fab2(sch_1):page202_i27@mstr_discrete.cap(chips)!CAP_0603-22.0UF,4V,20%,X6S,E15A!!!F2942!B!!!!
S!PVCCIN_CPU0!C4D12!1!@baseboard_fab2_lib.baseboard_fab2(sch_1):page204_i9@mstr_discrete.cap(chips)!CAP_0603-22.0UF,4V,20%,X6S,E15A!!!F2945!A!!!!
S!GND!C4D12!2!@baseboard_fab2_lib.baseboard_fab2(sch_1):page204_i9@mstr_discrete.cap(chips)!CAP_0603-22.0UF,4V,20%,X6S,E15A!!!F2945!B!!!!
S!PVSA_CPU0!C6N7!1!@baseboard_fab2_lib.baseboard_fab2(sch_1):page205_i5@mstr_discrete.cap(chips)!CAP_0603-22.0UF,4V,20%,X6S,E15A!!!F2817!A!!!!
S!GND!C6N7!2!@baseboard_fab2_lib.baseboard_fab2(sch_1):page205_i5@mstr_discrete.cap(chips)!CAP_0603-22.0UF,4V,20%,X6S,E15A!!!F2817!B!!!!
S!PVCCIN_CPU0!C6R7!1!@baseboard_fab2_lib.baseboard_fab2(sch_1):page202_i9@mstr_discrete.cap(chips)!CAP_0603-22.0UF,4V,20%,X6S,E15A!!!F2812!A!!!!
S!GND!C6R7!2!@baseboard_fab2_lib.baseboard_fab2(sch_1):page202_i9@mstr_discrete.cap(chips)!CAP_0603-22.0UF,4V,20%,X6S,E15A!!!F2812!B!!!!
S!PVCCIN_CPU1!C9R8!1!@baseboard_fab2_lib.baseboard_fab2(sch_1):page207_i8@mstr_discrete.cap(chips)!CAP_0603-22.0UF,4V,20%,X6S,E15A!!!F2748!A!!!!
S!GND!C9R8!2!@baseboard_fab2_lib.baseboard_fab2(sch_1):page207_i8@mstr_discrete.cap(chips)!CAP_0603-22.0UF,4V,20%,X6S,E15A!!!F2748!B!!!!
S!PVCCIN_CPU1!C1E3!1!@baseboard_fab2_lib.baseboard_fab2(sch_1):page207_i18@mstr_discrete.cap(chips)!CAP_0603-22.0UF,4V,20%,X6S,E15A!!!F3062!A!!!!
S!GND!C1E3!2!@baseboard_fab2_lib.baseboard_fab2(sch_1):page207_i18@mstr_discrete.cap(chips)!CAP_0603-22.0UF,4V,20%,X6S,E15A!!!F3062!B!!!!
S!PVCCIN_CPU1!C1D14!1!@baseboard_fab2_lib.baseboard_fab2(sch_1):page208_i9@mstr_discrete.cap(chips)!CAP_0603-22.0UF,4V,20%,X6S,E15A!!!F3064!A!!!!
S!GND!C1D14!2!@baseboard_fab2_lib.baseboard_fab2(sch_1):page208_i9@mstr_discrete.cap(chips)!CAP_0603-22.0UF,4V,20%,X6S,E15A!!!F3064!B!!!!
S!PVCCIN_CPU1!C1D3!1!@baseboard_fab2_lib.baseboard_fab2(sch_1):page208_i22@mstr_discrete.cap(chips)!CAP_0603-22.0UF,4V,20%,X6S,E15A!!!F3065!A!!!!
S!GND!C1D3!2!@baseboard_fab2_lib.baseboard_fab2(sch_1):page208_i22@mstr_discrete.cap(chips)!CAP_0603-22.0UF,4V,20%,X6S,E15A!!!F3065!B!!!!
S!PVSA_CPU1!C1C19!1!@baseboard_fab2_lib.baseboard_fab2(sch_1):page210_i8@mstr_discrete.cap(chips)!CAP_0603-22.0UF,4V,20%,X6S,E15A!!!F3066!A!!!!
S!GND!C1C19!2!@baseboard_fab2_lib.baseboard_fab2(sch_1):page210_i8@mstr_discrete.cap(chips)!CAP_0603-22.0UF,4V,20%,X6S,E15A!!!F3066!B!!!!
S!PVCCIN_CPU0!C6P3!1!@baseboard_fab2_lib.baseboard_fab2(sch_1):page203_i25@mstr_discrete.cap(chips)!CAP_0603-22.0UF,4V,20%,X6S,E15A!!!F2816!A!!!!
S!GND!C6P3!2!@baseboard_fab2_lib.baseboard_fab2(sch_1):page203_i25@mstr_discrete.cap(chips)!CAP_0603-22.0UF,4V,20%,X6S,E15A!!!F2816!B!!!!
S!PVCCIN_CPU1!C1D24!1!@baseboard_fab2_lib.baseboard_fab2(sch_1):page209_i42@mstr_discrete.cap(chips)!CAP_0603-22.0UF,4V,20%,X6S,E15A!!!F3063!A!!!!
S!GND!C1D24!2!@baseboard_fab2_lib.baseboard_fab2(sch_1):page209_i42@mstr_discrete.cap(chips)!CAP_0603-22.0UF,4V,20%,X6S,E15A!!!F3063!B!!!!
S!PVCCIN_CPU0!C6P21!1!@baseboard_fab2_lib.baseboard_fab2(sch_1):page203_i66@mstr_discrete.cap(chips)!CAP_0603-22.0UF,4V,20%,X6S,E15A!!!F2814!A!!!!
S!GND!C6P21!2!@baseboard_fab2_lib.baseboard_fab2(sch_1):page203_i66@mstr_discrete.cap(chips)!CAP_0603-22.0UF,4V,20%,X6S,E15A!!!F2814!B!!!!
S!PVCCIN_CPU0!C6P16!1!@baseboard_fab2_lib.baseboard_fab2(sch_1):page202_i62@mstr_discrete.cap(chips)!CAP_0603-22.0UF,4V,20%,X6S,E15A!!!F2815!A!!!!
S!GND!C6P16!2!@baseboard_fab2_lib.baseboard_fab2(sch_1):page202_i62@mstr_discrete.cap(chips)!CAP_0603-22.0UF,4V,20%,X6S,E15A!!!F2815!B!!!!
S!PVCCIN_CPU0!C4E3!1!@baseboard_fab2_lib.baseboard_fab2(sch_1):page202_i61@mstr_discrete.cap(chips)!CAP_0603-22.0UF,4V,20%,X6S,E15A!!!F2943!A!!!!
S!GND!C4E3!2!@baseboard_fab2_lib.baseboard_fab2(sch_1):page202_i61@mstr_discrete.cap(chips)!CAP_0603-22.0UF,4V,20%,X6S,E15A!!!F2943!B!!!!
S!PVCCIN_CPU0!C4D34!1!@baseboard_fab2_lib.baseboard_fab2(sch_1):page203_i68@mstr_discrete.cap(chips)!CAP_0603-22.0UF,4V,20%,X6S,E15A!!!F2944!A!!!!
S!GND!C4D34!2!@baseboard_fab2_lib.baseboard_fab2(sch_1):page203_i68@mstr_discrete.cap(chips)!CAP_0603-22.0UF,4V,20%,X6S,E15A!!!F2944!B!!!!
S!PVCCIN_CPU0!C4D4!1!@baseboard_fab2_lib.baseboard_fab2(sch_1):page203_i69@mstr_discrete.cap(chips)!CAP_0603-22.0UF,4V,20%,X6S,E15A!!!F2946!A!!!!
S!GND!C4D4!2!@baseboard_fab2_lib.baseboard_fab2(sch_1):page203_i69@mstr_discrete.cap(chips)!CAP_0603-22.0UF,4V,20%,X6S,E15A!!!F2946!B!!!!
S!PVCCIN_CPU0!C6R2!1!@baseboard_fab2_lib.baseboard_fab2(sch_1):page204_i70@mstr_discrete.cap(chips)!CAP_0603-22.0UF,4V,20%,X6S,E15A!!!F2813!A!!!!
S!GND!C6R2!2!@baseboard_fab2_lib.baseboard_fab2(sch_1):page204_i70@mstr_discrete.cap(chips)!CAP_0603-22.0UF,4V,20%,X6S,E15A!!!F2813!B!!!!
S!PVSA_CPU0!C4C11!1!@baseboard_fab2_lib.baseboard_fab2(sch_1):page205_i43@mstr_discrete.cap(chips)!CAP_0603-22.0UF,4V,20%,X6S,E15A!!!F2947!A!!!!
S!GND!C4C11!2!@baseboard_fab2_lib.baseboard_fab2(sch_1):page205_i43@mstr_discrete.cap(chips)!CAP_0603-22.0UF,4V,20%,X6S,E15A!!!F2947!B!!!!
S!PVCCIN_CPU1!C9P3!1!@baseboard_fab2_lib.baseboard_fab2(sch_1):page207_i59@mstr_discrete.cap(chips)!CAP_0603-22.0UF,4V,20%,X6S,E15A!!!F2752!A!!!!
S!GND!C9P3!2!@baseboard_fab2_lib.baseboard_fab2(sch_1):page207_i59@mstr_discrete.cap(chips)!CAP_0603-22.0UF,4V,20%,X6S,E15A!!!F2752!B!!!!
S!PVCCIN_CPU1!C1E9!1!@baseboard_fab2_lib.baseboard_fab2(sch_1):page207_i58@mstr_discrete.cap(chips)!CAP_0603-22.0UF,4V,20%,X6S,E15A!!!F3061!A!!!!
S!GND!C1E9!2!@baseboard_fab2_lib.baseboard_fab2(sch_1):page207_i58@mstr_discrete.cap(chips)!CAP_0603-22.0UF,4V,20%,X6S,E15A!!!F3061!B!!!!
S!PVCCIN_CPU1!C9R2!1!@baseboard_fab2_lib.baseboard_fab2(sch_1):page208_i67@mstr_discrete.cap(chips)!CAP_0603-22.0UF,4V,20%,X6S,E15A!!!F2749!A!!!!
S!GND!C9R2!2!@baseboard_fab2_lib.baseboard_fab2(sch_1):page208_i67@mstr_discrete.cap(chips)!CAP_0603-22.0UF,4V,20%,X6S,E15A!!!F2749!B!!!!
S!PVCCIN_CPU1!C9P10!1!@baseboard_fab2_lib.baseboard_fab2(sch_1):page208_i66@mstr_discrete.cap(chips)!CAP_0603-22.0UF,4V,20%,X6S,E15A!!!F2751!A!!!!
S!GND!C9P10!2!@baseboard_fab2_lib.baseboard_fab2(sch_1):page208_i66@mstr_discrete.cap(chips)!CAP_0603-22.0UF,4V,20%,X6S,E15A!!!F2751!B!!!!
S!PVCCIN_CPU1!C9P20!1!@baseboard_fab2_lib.baseboard_fab2(sch_1):page209_i55@mstr_discrete.cap(chips)!CAP_0603-22.0UF,4V,20%,X6S,E15A!!!F2750!A!!!!
S!GND!C9P20!2!@baseboard_fab2_lib.baseboard_fab2(sch_1):page209_i55@mstr_discrete.cap(chips)!CAP_0603-22.0UF,4V,20%,X6S,E15A!!!F2750!B!!!!
S!PVSA_CPU1!C9N22!1!@baseboard_fab2_lib.baseboard_fab2(sch_1):page210_i44@mstr_discrete.cap(chips)!CAP_0603-22.0UF,4V,20%,X6S,E15A!!!F2753!A!!!!
S!GND!C9N22!2!@baseboard_fab2_lib.baseboard_fab2(sch_1):page210_i44@mstr_discrete.cap(chips)!CAP_0603-22.0UF,4V,20%,X6S,E15A!!!F2753!B!!!!
S!PVCCMCP_CPU1!C3D19!1!@baseboard_fab2_lib.baseboard_fab2(sch_1):page76_i208@mstr_discrete.cap(chips)!CAP_0603-22.0UF,4V,20%,X6S,E15A!!!F2974!A!!!!
S!GND!C3D19!2!@baseboard_fab2_lib.baseboard_fab2(sch_1):page76_i208@mstr_discrete.cap(chips)!CAP_0603-22.0UF,4V,20%,X6S,E15A!!!F2974!B!!!!
S!PVCCMCP_CPU0!C5D52!1!@baseboard_fab2_lib.baseboard_fab2(sch_1):page42_i180@mstr_discrete.cap(chips)!CAP_0603-22.0UF,4V,20%,X6S,E15A!!!F2878!A!!!!
S!GND!C5D52!2!@baseboard_fab2_lib.baseboard_fab2(sch_1):page42_i180@mstr_discrete.cap(chips)!CAP_0603-22.0UF,4V,20%,X6S,E15A!!!F2878!B!!!!
S!PVCCMCP_CPU0!C5D33!1!@baseboard_fab2_lib.baseboard_fab2(sch_1):page42_i174@mstr_discrete.cap(chips)!CAP_0603-22.0UF,4V,20%,X6S,E15A!!!F2897!A!!!!
S!GND!C5D33!2!@baseboard_fab2_lib.baseboard_fab2(sch_1):page42_i174@mstr_discrete.cap(chips)!CAP_0603-22.0UF,4V,20%,X6S,E15A!!!F2897!B!!!!
S!PVCCMCP_CPU0!C5D34!1!@baseboard_fab2_lib.baseboard_fab2(sch_1):page42_i175@mstr_discrete.cap(chips)!CAP_0603-22.0UF,4V,20%,X6S,E15A!!!F2896!A!!!!
S!GND!C5D34!2!@baseboard_fab2_lib.baseboard_fab2(sch_1):page42_i175@mstr_discrete.cap(chips)!CAP_0603-22.0UF,4V,20%,X6S,E15A!!!F2896!B!!!!
S!PVCCMCP_CPU0!C5D53!1!@baseboard_fab2_lib.baseboard_fab2(sch_1):page42_i179@mstr_discrete.cap(chips)!CAP_0603-22.0UF,4V,20%,X6S,E15A!!!F2877!A!!!!
S!GND!C5D53!2!@baseboard_fab2_lib.baseboard_fab2(sch_1):page42_i179@mstr_discrete.cap(chips)!CAP_0603-22.0UF,4V,20%,X6S,E15A!!!F2877!B!!!!
S!PVCCIN_CPU1!C2D3!1!@baseboard_fab2_lib.baseboard_fab2(sch_1):page76_i202@mstr_discrete.cap(chips)!CAP_0603-22.0UF,4V,20%,X6S,E15A!!!F3045!A!!!!
S!GND!C2D3!2!@baseboard_fab2_lib.baseboard_fab2(sch_1):page76_i202@mstr_discrete.cap(chips)!CAP_0603-22.0UF,4V,20%,X6S,E15A!!!F3045!B!!!!
S!PVCCIN_CPU1!C2D2!1!@baseboard_fab2_lib.baseboard_fab2(sch_1):page76_i201@mstr_discrete.cap(chips)!CAP_0603-22.0UF,4V,20%,X6S,E15A!!!F3046!A!!!!
S!GND!C2D2!2!@baseboard_fab2_lib.baseboard_fab2(sch_1):page76_i201@mstr_discrete.cap(chips)!CAP_0603-22.0UF,4V,20%,X6S,E15A!!!F3046!B!!!!
S!PVCCMCP_CPU1!C3D20!1!@baseboard_fab2_lib.baseboard_fab2(sch_1):page76_i207@mstr_discrete.cap(chips)!CAP_0603-22.0UF,4V,20%,X6S,E15A!!!F2973!A!!!!
S!GND!C3D20!2!@baseboard_fab2_lib.baseboard_fab2(sch_1):page76_i207@mstr_discrete.cap(chips)!CAP_0603-22.0UF,4V,20%,X6S,E15A!!!F2973!B!!!!
S!PVCCMCP_CPU0!C5D20!1!@baseboard_fab2_lib.baseboard_fab2(sch_1):page42_i173@mstr_discrete.cap(chips)!CAP_0603-22.0UF,4V,20%,X6S,E15A!!!F2910!A!!!!
S!GND!C5D20!2!@baseboard_fab2_lib.baseboard_fab2(sch_1):page42_i173@mstr_discrete.cap(chips)!CAP_0603-22.0UF,4V,20%,X6S,E15A!!!F2910!B!!!!
S!PVCCIN_CPU0!C5D28!1!@baseboard_fab2_lib.baseboard_fab2(sch_1):page42_i100@mstr_discrete.cap(chips)!CAP_0603-22.0UF,4V,20%,X6S,E15A!!!F2902!A!!!!
S!GND!C5D28!2!@baseboard_fab2_lib.baseboard_fab2(sch_1):page42_i100@mstr_discrete.cap(chips)!CAP_0603-22.0UF,4V,20%,X6S,E15A!!!F2902!B!!!!
S!PVCCIN_CPU0!C5D27!1!@baseboard_fab2_lib.baseboard_fab2(sch_1):page42_i109@mstr_discrete.cap(chips)!CAP_0603-22.0UF,4V,20%,X6S,E15A!!!F2903!A!!!!
S!GND!C5D27!2!@baseboard_fab2_lib.baseboard_fab2(sch_1):page42_i109@mstr_discrete.cap(chips)!CAP_0603-22.0UF,4V,20%,X6S,E15A!!!F2903!B!!!!
S!PVCCMCP_CPU0!C5D35!1!@baseboard_fab2_lib.baseboard_fab2(sch_1):page42_i176@mstr_discrete.cap(chips)!CAP_0603-22.0UF,4V,20%,X6S,E15A!!!F2895!A!!!!
S!GND!C5D35!2!@baseboard_fab2_lib.baseboard_fab2(sch_1):page42_i176@mstr_discrete.cap(chips)!CAP_0603-22.0UF,4V,20%,X6S,E15A!!!F2895!B!!!!
S!PVCCIN_CPU0!C5D25!1!@baseboard_fab2_lib.baseboard_fab2(sch_1):page42_i155@mstr_discrete.cap(chips)!CAP_0603-22.0UF,4V,20%,X6S,E15A!!!F2905!A!!!!
S!GND!C5D25!2!@baseboard_fab2_lib.baseboard_fab2(sch_1):page42_i155@mstr_discrete.cap(chips)!CAP_0603-22.0UF,4V,20%,X6S,E15A!!!F2905!B!!!!
S!PVCCIN_CPU0!C5D45!1!@baseboard_fab2_lib.baseboard_fab2(sch_1):page42_i156@mstr_discrete.cap(chips)!CAP_0603-22.0UF,4V,20%,X6S,E15A!!!F2885!A!!!!
S!GND!C5D45!2!@baseboard_fab2_lib.baseboard_fab2(sch_1):page42_i156@mstr_discrete.cap(chips)!CAP_0603-22.0UF,4V,20%,X6S,E15A!!!F2885!B!!!!
S!PVCCIN_CPU1!C2D46!1!@baseboard_fab2_lib.baseboard_fab2(sch_1):page76_i204@mstr_discrete.cap(chips)!CAP_0603-22.0UF,4V,20%,X6S,E15A!!!F3014!A!!!!
S!GND!C2D46!2!@baseboard_fab2_lib.baseboard_fab2(sch_1):page76_i204@mstr_discrete.cap(chips)!CAP_0603-22.0UF,4V,20%,X6S,E15A!!!F3014!B!!!!
S!PVCCIN_CPU1!C2D13!1!@baseboard_fab2_lib.baseboard_fab2(sch_1):page76_i73@mstr_discrete.cap(chips)!CAP_0603-22.0UF,4V,20%,X6S,E15A!!!F3043!A!!!!
S!GND!C2D13!2!@baseboard_fab2_lib.baseboard_fab2(sch_1):page76_i73@mstr_discrete.cap(chips)!CAP_0603-22.0UF,4V,20%,X6S,E15A!!!F3043!B!!!!
S!PVCCIN_CPU1!C2D14!1!@baseboard_fab2_lib.baseboard_fab2(sch_1):page76_i76@mstr_discrete.cap(chips)!CAP_0603-22.0UF,4V,20%,X6S,E15A!!!F3042!A!!!!
S!GND!C2D14!2!@baseboard_fab2_lib.baseboard_fab2(sch_1):page76_i76@mstr_discrete.cap(chips)!CAP_0603-22.0UF,4V,20%,X6S,E15A!!!F3042!B!!!!
S!PVCCIN_CPU1!C2D47!1!@baseboard_fab2_lib.baseboard_fab2(sch_1):page76_i203@mstr_discrete.cap(chips)!CAP_0603-22.0UF,4V,20%,X6S,E15A!!!F3013!A!!!!
S!GND!C2D47!2!@baseboard_fab2_lib.baseboard_fab2(sch_1):page76_i203@mstr_discrete.cap(chips)!CAP_0603-22.0UF,4V,20%,X6S,E15A!!!F3013!B!!!!
S!PVCCIN_CPU1!C2D38!1!@baseboard_fab2_lib.baseboard_fab2(sch_1):page76_i160@mstr_discrete.cap(chips)!CAP_0603-22.0UF,4V,20%,X6S,E15A!!!F3018!A!!!!
S!GND!C2D38!2!@baseboard_fab2_lib.baseboard_fab2(sch_1):page76_i160@mstr_discrete.cap(chips)!CAP_0603-22.0UF,4V,20%,X6S,E15A!!!F3018!B!!!!
S!PVCCIN_CPU1!C3D25!1!@baseboard_fab2_lib.baseboard_fab2(sch_1):page76_i205@mstr_discrete.cap(chips)!CAP_0603-22.0UF,4V,20%,X6S,E15A!!!F2969!A!!!!
S!GND!C3D25!2!@baseboard_fab2_lib.baseboard_fab2(sch_1):page76_i205@mstr_discrete.cap(chips)!CAP_0603-22.0UF,4V,20%,X6S,E15A!!!F2969!B!!!!
S!PVCCIN_CPU1!C2D35!1!@baseboard_fab2_lib.baseboard_fab2(sch_1):page76_i161@mstr_discrete.cap(chips)!CAP_0603-22.0UF,4V,20%,X6S,E15A!!!F3021!A!!!!
S!GND!C2D35!2!@baseboard_fab2_lib.baseboard_fab2(sch_1):page76_i161@mstr_discrete.cap(chips)!CAP_0603-22.0UF,4V,20%,X6S,E15A!!!F3021!B!!!!
S!PVCCIO_CPU1!C7P12!1!@baseboard_fab2_lib.baseboard_fab2(sch_1):page76_i179@mstr_discrete.cap(chips)!CAP_0603-22.0UF,4V,20%,X6S,E15A!!!F2792!A!!!!
S!GND!C7P12!2!@baseboard_fab2_lib.baseboard_fab2(sch_1):page76_i179@mstr_discrete.cap(chips)!CAP_0603-22.0UF,4V,20%,X6S,E15A!!!F2792!B!!!!
S!PVCCMCP_CPU0!C5D48!1!@baseboard_fab2_lib.baseboard_fab2(sch_1):page42_i90@mstr_discrete.cap(chips)!CAP_0603-22.0UF,4V,20%,X6S,E15A!!!F2882!A!!!!
S!GND!C5D48!2!@baseboard_fab2_lib.baseboard_fab2(sch_1):page42_i90@mstr_discrete.cap(chips)!CAP_0603-22.0UF,4V,20%,X6S,E15A!!!F2882!B!!!!
S!PVCCMCP_CPU0!C6D8!1!@baseboard_fab2_lib.baseboard_fab2(sch_1):page42_i68@mstr_discrete.cap(chips)!CAP_0603-22.0UF,4V,20%,X6S,E15A!!!F2820!A!!!!
S!GND!C6D8!2!@baseboard_fab2_lib.baseboard_fab2(sch_1):page42_i68@mstr_discrete.cap(chips)!CAP_0603-22.0UF,4V,20%,X6S,E15A!!!F2820!B!!!!
S!PVCCMCP_CPU0!C5D50!1!@baseboard_fab2_lib.baseboard_fab2(sch_1):page42_i89@mstr_discrete.cap(chips)!CAP_0603-22.0UF,4V,20%,X6S,E15A!!!F2880!A!!!!
S!GND!C5D50!2!@baseboard_fab2_lib.baseboard_fab2(sch_1):page42_i89@mstr_discrete.cap(chips)!CAP_0603-22.0UF,4V,20%,X6S,E15A!!!F2880!B!!!!
S!PVCCMCP_CPU0!C5D36!1!@baseboard_fab2_lib.baseboard_fab2(sch_1):page42_i151@mstr_discrete.cap(chips)!CAP_0603-22.0UF,4V,20%,X6S,E15A!!!F2894!A!!!!
S!GND!C5D36!2!@baseboard_fab2_lib.baseboard_fab2(sch_1):page42_i151@mstr_discrete.cap(chips)!CAP_0603-22.0UF,4V,20%,X6S,E15A!!!F2894!B!!!!
S!PVCCMCP_CPU0!C5D21!1!@baseboard_fab2_lib.baseboard_fab2(sch_1):page42_i88@mstr_discrete.cap(chips)!CAP_0603-22.0UF,4V,20%,X6S,E15A!!!F2909!A!!!!
S!GND!C5D21!2!@baseboard_fab2_lib.baseboard_fab2(sch_1):page42_i88@mstr_discrete.cap(chips)!CAP_0603-22.0UF,4V,20%,X6S,E15A!!!F2909!B!!!!
S!PVCCMCP_CPU0!C5D49!1!@baseboard_fab2_lib.baseboard_fab2(sch_1):page42_i152@mstr_discrete.cap(chips)!CAP_0603-22.0UF,4V,20%,X6S,E15A!!!F2881!A!!!!
S!GND!C5D49!2!@baseboard_fab2_lib.baseboard_fab2(sch_1):page42_i152@mstr_discrete.cap(chips)!CAP_0603-22.0UF,4V,20%,X6S,E15A!!!F2881!B!!!!
S!PVCCMCP_CPU0!C5D51!1!@baseboard_fab2_lib.baseboard_fab2(sch_1):page42_i83@mstr_discrete.cap(chips)!CAP_0603-22.0UF,4V,20%,X6S,E15A!!!F2879!A!!!!
S!GND!C5D51!2!@baseboard_fab2_lib.baseboard_fab2(sch_1):page42_i83@mstr_discrete.cap(chips)!CAP_0603-22.0UF,4V,20%,X6S,E15A!!!F2879!B!!!!
S!PVCCMCP_CPU0!C6D2!1!@baseboard_fab2_lib.baseboard_fab2(sch_1):page42_i77@mstr_discrete.cap(chips)!CAP_0603-22.0UF,4V,20%,X6S,E15A!!!F2826!A!!!!
S!GND!C6D2!2!@baseboard_fab2_lib.baseboard_fab2(sch_1):page42_i77@mstr_discrete.cap(chips)!CAP_0603-22.0UF,4V,20%,X6S,E15A!!!F2826!B!!!!
S!PVCCMCP_CPU0!C6D5!1!@baseboard_fab2_lib.baseboard_fab2(sch_1):page42_i75@mstr_discrete.cap(chips)!CAP_0603-22.0UF,4V,20%,X6S,E15A!!!F2823!A!!!!
S!GND!C6D5!2!@baseboard_fab2_lib.baseboard_fab2(sch_1):page42_i75@mstr_discrete.cap(chips)!CAP_0603-22.0UF,4V,20%,X6S,E15A!!!F2823!B!!!!
S!PVCCMCP_CPU0!C5D37!1!@baseboard_fab2_lib.baseboard_fab2(sch_1):page42_i70@mstr_discrete.cap(chips)!CAP_0603-22.0UF,4V,20%,X6S,E15A!!!F2893!A!!!!
S!GND!C5D37!2!@baseboard_fab2_lib.baseboard_fab2(sch_1):page42_i70@mstr_discrete.cap(chips)!CAP_0603-22.0UF,4V,20%,X6S,E15A!!!F2893!B!!!!
S!PVCCMCP_CPU0!C5D38!1!@baseboard_fab2_lib.baseboard_fab2(sch_1):page42_i69@mstr_discrete.cap(chips)!CAP_0603-22.0UF,4V,20%,X6S,E15A!!!F2892!A!!!!
S!GND!C5D38!2!@baseboard_fab2_lib.baseboard_fab2(sch_1):page42_i69@mstr_discrete.cap(chips)!CAP_0603-22.0UF,4V,20%,X6S,E15A!!!F2892!B!!!!
S!PVCCMCP_CPU1!C2D39!1!@baseboard_fab2_lib.baseboard_fab2(sch_1):page76_i165@mstr_discrete.cap(chips)!CAP_0603-22.0UF,4V,20%,X6S,E15A!!!F3017!A!!!!
S!GND!C2D39!2!@baseboard_fab2_lib.baseboard_fab2(sch_1):page76_i165@mstr_discrete.cap(chips)!CAP_0603-22.0UF,4V,20%,X6S,E15A!!!F3017!B!!!!
S!PVCCMCP_CPU1!C3D17!1!@baseboard_fab2_lib.baseboard_fab2(sch_1):page76_i166@mstr_discrete.cap(chips)!CAP_0603-22.0UF,4V,20%,X6S,E15A!!!F2976!A!!!!
S!GND!C3D17!2!@baseboard_fab2_lib.baseboard_fab2(sch_1):page76_i166@mstr_discrete.cap(chips)!CAP_0603-22.0UF,4V,20%,X6S,E15A!!!F2976!B!!!!
S!PVCCMCP_CPU1!C3D18!1!@baseboard_fab2_lib.baseboard_fab2(sch_1):page76_i169@mstr_discrete.cap(chips)!CAP_0603-22.0UF,4V,20%,X6S,E15A!!!F2975!A!!!!
S!GND!C3D18!2!@baseboard_fab2_lib.baseboard_fab2(sch_1):page76_i169@mstr_discrete.cap(chips)!CAP_0603-22.0UF,4V,20%,X6S,E15A!!!F2975!B!!!!
S!PVCCMCP_CPU1!C2D40!1!@baseboard_fab2_lib.baseboard_fab2(sch_1):page76_i10@mstr_discrete.cap(chips)!CAP_0603-22.0UF,4V,20%,X6S,E15A!!!F3016!A!!!!
S!GND!C2D40!2!@baseboard_fab2_lib.baseboard_fab2(sch_1):page76_i10@mstr_discrete.cap(chips)!CAP_0603-22.0UF,4V,20%,X6S,E15A!!!F3016!B!!!!
S!PVCCMCP_CPU1!C3D14!1!@baseboard_fab2_lib.baseboard_fab2(sch_1):page76_i171@mstr_discrete.cap(chips)!CAP_0603-22.0UF,4V,20%,X6S,E15A!!!F2979!A!!!!
S!GND!C3D14!2!@baseboard_fab2_lib.baseboard_fab2(sch_1):page76_i171@mstr_discrete.cap(chips)!CAP_0603-22.0UF,4V,20%,X6S,E15A!!!F2979!B!!!!
S!PVCCMCP_CPU1!C3D13!1!@baseboard_fab2_lib.baseboard_fab2(sch_1):page76_i8@mstr_discrete.cap(chips)!CAP_0603-22.0UF,4V,20%,X6S,E15A!!!F2980!A!!!!
S!GND!C3D13!2!@baseboard_fab2_lib.baseboard_fab2(sch_1):page76_i8@mstr_discrete.cap(chips)!CAP_0603-22.0UF,4V,20%,X6S,E15A!!!F2980!B!!!!
S!PVCCMCP_CPU1!C3D6!1!@baseboard_fab2_lib.baseboard_fab2(sch_1):page76_i170@mstr_discrete.cap(chips)!CAP_0603-22.0UF,4V,20%,X6S,E15A!!!F2987!A!!!!
S!GND!C3D6!2!@baseboard_fab2_lib.baseboard_fab2(sch_1):page76_i170@mstr_discrete.cap(chips)!CAP_0603-22.0UF,4V,20%,X6S,E15A!!!F2987!B!!!!
S!PVCCMCP_CPU1!C3D11!1!@baseboard_fab2_lib.baseboard_fab2(sch_1):page76_i7@mstr_discrete.cap(chips)!CAP_0603-22.0UF,4V,20%,X6S,E15A!!!F2982!A!!!!
S!GND!C3D11!2!@baseboard_fab2_lib.baseboard_fab2(sch_1):page76_i7@mstr_discrete.cap(chips)!CAP_0603-22.0UF,4V,20%,X6S,E15A!!!F2982!B!!!!
S!PVCCMCP_CPU1!C3D4!1!@baseboard_fab2_lib.baseboard_fab2(sch_1):page76_i5@mstr_discrete.cap(chips)!CAP_0603-22.0UF,4V,20%,X6S,E15A!!!F2989!A!!!!
S!GND!C3D4!2!@baseboard_fab2_lib.baseboard_fab2(sch_1):page76_i5@mstr_discrete.cap(chips)!CAP_0603-22.0UF,4V,20%,X6S,E15A!!!F2989!B!!!!
S!PVCCIO_CPU1!C3D16!1!@baseboard_fab2_lib.baseboard_fab2(sch_1):page76_i176@mstr_discrete.cap(chips)!CAP_0603-22.0UF,4V,20%,X6S,E15A!!!F2977!A!!!!
S!GND!C3D16!2!@baseboard_fab2_lib.baseboard_fab2(sch_1):page76_i176@mstr_discrete.cap(chips)!CAP_0603-22.0UF,4V,20%,X6S,E15A!!!F2977!B!!!!
S!PVCCMCP_CPU1!C3D12!1!@baseboard_fab2_lib.baseboard_fab2(sch_1):page76_i4@mstr_discrete.cap(chips)!CAP_0603-22.0UF,4V,20%,X6S,E15A!!!F2981!A!!!!
S!GND!C3D12!2!@baseboard_fab2_lib.baseboard_fab2(sch_1):page76_i4@mstr_discrete.cap(chips)!CAP_0603-22.0UF,4V,20%,X6S,E15A!!!F2981!B!!!!
S!PVCCIO_CPU1!C3D8!1!@baseboard_fab2_lib.baseboard_fab2(sch_1):page76_i18@mstr_discrete.cap(chips)!CAP_0603-22.0UF,4V,20%,X6S,E15A!!!F2985!A!!!!
S!GND!C3D8!2!@baseboard_fab2_lib.baseboard_fab2(sch_1):page76_i18@mstr_discrete.cap(chips)!CAP_0603-22.0UF,4V,20%,X6S,E15A!!!F2985!B!!!!
S!PVCCMCP_CPU1!C3D5!1!@baseboard_fab2_lib.baseboard_fab2(sch_1):page76_i3@mstr_discrete.cap(chips)!CAP_0603-22.0UF,4V,20%,X6S,E15A!!!F2988!A!!!!
S!GND!C3D5!2!@baseboard_fab2_lib.baseboard_fab2(sch_1):page76_i3@mstr_discrete.cap(chips)!CAP_0603-22.0UF,4V,20%,X6S,E15A!!!F2988!B!!!!
S!PVCCIO_CPU1!C3D9!1!@baseboard_fab2_lib.baseboard_fab2(sch_1):page76_i15@mstr_discrete.cap(chips)!CAP_0603-22.0UF,4V,20%,X6S,E15A!!!F2984!A!!!!
S!GND!C3D9!2!@baseboard_fab2_lib.baseboard_fab2(sch_1):page76_i15@mstr_discrete.cap(chips)!CAP_0603-22.0UF,4V,20%,X6S,E15A!!!F2984!B!!!!
S!PVCCMCP_CPU1!C3D21!1!@baseboard_fab2_lib.baseboard_fab2(sch_1):page76_i1@mstr_discrete.cap(chips)!CAP_0603-22.0UF,4V,20%,X6S,E15A!!!F2972!A!!!!
S!GND!C3D21!2!@baseboard_fab2_lib.baseboard_fab2(sch_1):page76_i1@mstr_discrete.cap(chips)!CAP_0603-22.0UF,4V,20%,X6S,E15A!!!F2972!B!!!!
S!PVCCMCP_CPU0!C5D22!1!@baseboard_fab2_lib.baseboard_fab2(sch_1):page42_i153@mstr_discrete.cap(chips)!CAP_0603-22.0UF,4V,20%,X6S,E15A!!!F2908!A!!!!
S!GND!C5D22!2!@baseboard_fab2_lib.baseboard_fab2(sch_1):page42_i153@mstr_discrete.cap(chips)!CAP_0603-22.0UF,4V,20%,X6S,E15A!!!F2908!B!!!!
S!PVCCIO_CPU1!C3D23!1!@baseboard_fab2_lib.baseboard_fab2(sch_1):page76_i172@mstr_discrete.cap(chips)!CAP_0603-22.0UF,4V,20%,X6S,E15A!!!F2971!A!!!!
S!GND!C3D23!2!@baseboard_fab2_lib.baseboard_fab2(sch_1):page76_i172@mstr_discrete.cap(chips)!CAP_0603-22.0UF,4V,20%,X6S,E15A!!!F2971!B!!!!
S!PVCCIO_CPU1!C7P16!1!@baseboard_fab2_lib.baseboard_fab2(sch_1):page76_i206@mstr_discrete.cap(chips)!CAP_0603-22.0UF,4V,20%,X6S,E15A!!!F2791!A!!!!
S!GND!C7P16!2!@baseboard_fab2_lib.baseboard_fab2(sch_1):page76_i206@mstr_discrete.cap(chips)!CAP_0603-22.0UF,4V,20%,X6S,E15A!!!F2791!B!!!!
S!PVCCIO_CPU1!C3D15!1!@baseboard_fab2_lib.baseboard_fab2(sch_1):page76_i174@mstr_discrete.cap(chips)!CAP_0603-22.0UF,4V,20%,X6S,E15A!!!F2978!A!!!!
S!GND!C3D15!2!@baseboard_fab2_lib.baseboard_fab2(sch_1):page76_i174@mstr_discrete.cap(chips)!CAP_0603-22.0UF,4V,20%,X6S,E15A!!!F2978!B!!!!
S!PVCCIO_CPU0!C4P8!1!@baseboard_fab2_lib.baseboard_fab2(sch_1):page42_i178@mstr_discrete.cap(chips)!CAP_0603-22.0UF,4V,20%,X6S,E15A!!!F2939!A!!!!
S!GND!C4P8!2!@baseboard_fab2_lib.baseboard_fab2(sch_1):page42_i178@mstr_discrete.cap(chips)!CAP_0603-22.0UF,4V,20%,X6S,E15A!!!F2939!B!!!!
S!PVCCIO_CPU0!C6D10!1!@baseboard_fab2_lib.baseboard_fab2(sch_1):page42_i147@mstr_discrete.cap(chips)!CAP_0603-22.0UF,4V,20%,X6S,E15A!!!F2818!A!!!!
S!GND!C6D10!2!@baseboard_fab2_lib.baseboard_fab2(sch_1):page42_i147@mstr_discrete.cap(chips)!CAP_0603-22.0UF,4V,20%,X6S,E15A!!!F2818!B!!!!
S!PVCCIO_CPU0!C6D9!1!@baseboard_fab2_lib.baseboard_fab2(sch_1):page42_i145@mstr_discrete.cap(chips)!CAP_0603-22.0UF,4V,20%,X6S,E15A!!!F2819!A!!!!
S!GND!C6D9!2!@baseboard_fab2_lib.baseboard_fab2(sch_1):page42_i145@mstr_discrete.cap(chips)!CAP_0603-22.0UF,4V,20%,X6S,E15A!!!F2819!B!!!!
S!PVCCIO_CPU0!C4P6!1!@baseboard_fab2_lib.baseboard_fab2(sch_1):page42_i164@mstr_discrete.cap(chips)!CAP_0603-22.0UF,4V,20%,X6S,E15A!!!F2940!A!!!!
S!GND!C4P6!2!@baseboard_fab2_lib.baseboard_fab2(sch_1):page42_i164@mstr_discrete.cap(chips)!CAP_0603-22.0UF,4V,20%,X6S,E15A!!!F2940!B!!!!
S!PVCCMCP_CPU1!C3D7!1!@baseboard_fab2_lib.baseboard_fab2(sch_1):page76_i164@mstr_discrete.cap(chips)!CAP_0603-22.0UF,4V,20%,X6S,E15A!!!F2986!A!!!!
S!GND!C3D7!2!@baseboard_fab2_lib.baseboard_fab2(sch_1):page76_i164@mstr_discrete.cap(chips)!CAP_0603-22.0UF,4V,20%,X6S,E15A!!!F2986!B!!!!
S!PVCCMCP_CPU0!C5D23!1!@baseboard_fab2_lib.baseboard_fab2(sch_1):page42_i98@mstr_discrete.cap(chips)!CAP_0603-22.0UF,4V,20%,X6S,E15A!!!F2907!A!!!!
S!GND!C5D23!2!@baseboard_fab2_lib.baseboard_fab2(sch_1):page42_i98@mstr_discrete.cap(chips)!CAP_0603-22.0UF,4V,20%,X6S,E15A!!!F2907!B!!!!
S!PVCCIO_CPU0!C6D7!1!@baseboard_fab2_lib.baseboard_fab2(sch_1):page42_i72@mstr_discrete.cap(chips)!CAP_0603-22.0UF,4V,20%,X6S,E15A!!!F2821!A!!!!
S!GND!C6D7!2!@baseboard_fab2_lib.baseboard_fab2(sch_1):page42_i72@mstr_discrete.cap(chips)!CAP_0603-22.0UF,4V,20%,X6S,E15A!!!F2821!B!!!!
S!PVCCIO_CPU0!C6D6!1!@baseboard_fab2_lib.baseboard_fab2(sch_1):page42_i81@mstr_discrete.cap(chips)!CAP_0603-22.0UF,4V,20%,X6S,E15A!!!F2822!A!!!!
S!GND!C6D6!2!@baseboard_fab2_lib.baseboard_fab2(sch_1):page42_i81@mstr_discrete.cap(chips)!CAP_0603-22.0UF,4V,20%,X6S,E15A!!!F2822!B!!!!
S!PVCCIO_CPU0!C6D3!1!@baseboard_fab2_lib.baseboard_fab2(sch_1):page42_i80@mstr_discrete.cap(chips)!CAP_0603-22.0UF,4V,20%,X6S,E15A!!!F2825!A!!!!
S!GND!C6D3!2!@baseboard_fab2_lib.baseboard_fab2(sch_1):page42_i80@mstr_discrete.cap(chips)!CAP_0603-22.0UF,4V,20%,X6S,E15A!!!F2825!B!!!!
S!PVCCIO_CPU0!C6D4!1!@baseboard_fab2_lib.baseboard_fab2(sch_1):page42_i74@mstr_discrete.cap(chips)!CAP_0603-22.0UF,4V,20%,X6S,E15A!!!F2824!A!!!!
S!GND!C6D4!2!@baseboard_fab2_lib.baseboard_fab2(sch_1):page42_i74@mstr_discrete.cap(chips)!CAP_0603-22.0UF,4V,20%,X6S,E15A!!!F2824!B!!!!
S!PVCCIO_CPU1!C3D24!1!@baseboard_fab2_lib.baseboard_fab2(sch_1):page76_i175@mstr_discrete.cap(chips)!CAP_0603-22.0UF,4V,20%,X6S,E15A!!!F2970!A!!!!
S!GND!C3D24!2!@baseboard_fab2_lib.baseboard_fab2(sch_1):page76_i175@mstr_discrete.cap(chips)!CAP_0603-22.0UF,4V,20%,X6S,E15A!!!F2970!B!!!!
S!PVNN_PCH_STBY!C3L24!1!@baseboard_fab2_lib.baseboard_fab2(sch_1):page132_i56@mstr_discrete.cap(chips)!CAP_0603-22.0UF,4V,20%,X6S,E15A!!!F2961!A!!!!
S!GND!C3L24!2!@baseboard_fab2_lib.baseboard_fab2(sch_1):page132_i56@mstr_discrete.cap(chips)!CAP_0603-22.0UF,4V,20%,X6S,E15A!!!F2961!B!!!!
S!PVNN_PCH_STBY!C3L22!1!@baseboard_fab2_lib.baseboard_fab2(sch_1):page132_i54@mstr_discrete.cap(chips)!CAP_0603-22.0UF,4V,20%,X6S,E15A!!!F2963!A!!!!
S!GND!C3L22!2!@baseboard_fab2_lib.baseboard_fab2(sch_1):page132_i54@mstr_discrete.cap(chips)!CAP_0603-22.0UF,4V,20%,X6S,E15A!!!F2963!B!!!!
S!PVNN_PCH_STBY!C3L23!1!@baseboard_fab2_lib.baseboard_fab2(sch_1):page132_i52@mstr_discrete.cap(chips)!CAP_0603-22.0UF,4V,20%,X6S,E15A!!!F2962!A!!!!
S!GND!C3L23!2!@baseboard_fab2_lib.baseboard_fab2(sch_1):page132_i52@mstr_discrete.cap(chips)!CAP_0603-22.0UF,4V,20%,X6S,E15A!!!F2962!B!!!!
S!PVNN_PCH_STBY!C3M6!1!@baseboard_fab2_lib.baseboard_fab2(sch_1):page132_i6@mstr_discrete.cap(chips)!CAP_0603-22.0UF,4V,20%,X6S,E15A!!!F2957!A!!!!
S!GND!C3M6!2!@baseboard_fab2_lib.baseboard_fab2(sch_1):page132_i6@mstr_discrete.cap(chips)!CAP_0603-22.0UF,4V,20%,X6S,E15A!!!F2957!B!!!!
S!PVNN_PCH_STBY!C3N11!1!@baseboard_fab2_lib.baseboard_fab2(sch_1):page132_i19@mstr_discrete.cap(chips)!CAP_0603-22.0UF,4V,20%,X6S,E15A!!!F2954!A!!!!
S!GND!C3N11!2!@baseboard_fab2_lib.baseboard_fab2(sch_1):page132_i19@mstr_discrete.cap(chips)!CAP_0603-22.0UF,4V,20%,X6S,E15A!!!F2954!B!!!!
S!PVNN_PCH_STBY!C3N31!1!@baseboard_fab2_lib.baseboard_fab2(sch_1):page132_i20@mstr_discrete.cap(chips)!CAP_0603-22.0UF,4V,20%,X6S,E15A!!!F2948!A!!!!
S!GND!C3N31!2!@baseboard_fab2_lib.baseboard_fab2(sch_1):page132_i20@mstr_discrete.cap(chips)!CAP_0603-22.0UF,4V,20%,X6S,E15A!!!F2948!B!!!!
S!PVNN_PCH_STBY!C3L27!1!@baseboard_fab2_lib.baseboard_fab2(sch_1):page132_i4@mstr_discrete.cap(chips)!CAP_0603-22.0UF,4V,20%,X6S,E15A!!!F2958!A!!!!
S!GND!C3L27!2!@baseboard_fab2_lib.baseboard_fab2(sch_1):page132_i4@mstr_discrete.cap(chips)!CAP_0603-22.0UF,4V,20%,X6S,E15A!!!F2958!B!!!!
S!PVNN_PCH_STBY!C3N10!1!@baseboard_fab2_lib.baseboard_fab2(sch_1):page132_i13@mstr_discrete.cap(chips)!CAP_0603-22.0UF,4V,20%,X6S,E15A!!!F2955!A!!!!
S!GND!C3N10!2!@baseboard_fab2_lib.baseboard_fab2(sch_1):page132_i13@mstr_discrete.cap(chips)!CAP_0603-22.0UF,4V,20%,X6S,E15A!!!F2955!B!!!!
S!PVNN_PCH_STBY!C3N28!1!@baseboard_fab2_lib.baseboard_fab2(sch_1):page132_i17@mstr_discrete.cap(chips)!CAP_0603-22.0UF,4V,20%,X6S,E15A!!!F2950!A!!!!
S!GND!C3N28!2!@baseboard_fab2_lib.baseboard_fab2(sch_1):page132_i17@mstr_discrete.cap(chips)!CAP_0603-22.0UF,4V,20%,X6S,E15A!!!F2950!B!!!!
S!PVNN_PCH_STBY!C3L26!1!@baseboard_fab2_lib.baseboard_fab2(sch_1):page132_i3@mstr_discrete.cap(chips)!CAP_0603-22.0UF,4V,20%,X6S,E15A!!!F2959!A!!!!
S!GND!C3L26!2!@baseboard_fab2_lib.baseboard_fab2(sch_1):page132_i3@mstr_discrete.cap(chips)!CAP_0603-22.0UF,4V,20%,X6S,E15A!!!F2959!B!!!!
S!PVNN_PCH_STBY!C3N12!1!@baseboard_fab2_lib.baseboard_fab2(sch_1):page132_i12@mstr_discrete.cap(chips)!CAP_0603-22.0UF,4V,20%,X6S,E15A!!!F2953!A!!!!
S!GND!C3N12!2!@baseboard_fab2_lib.baseboard_fab2(sch_1):page132_i12@mstr_discrete.cap(chips)!CAP_0603-22.0UF,4V,20%,X6S,E15A!!!F2953!B!!!!
S!PVNN_PCH_STBY!C3N24!1!@baseboard_fab2_lib.baseboard_fab2(sch_1):page132_i16@mstr_discrete.cap(chips)!CAP_0603-22.0UF,4V,20%,X6S,E15A!!!F2952!A!!!!
S!GND!C3N24!2!@baseboard_fab2_lib.baseboard_fab2(sch_1):page132_i16@mstr_discrete.cap(chips)!CAP_0603-22.0UF,4V,20%,X6S,E15A!!!F2952!B!!!!
S!PVNN_PCH_STBY!C3M7!1!@baseboard_fab2_lib.baseboard_fab2(sch_1):page132_i2@mstr_discrete.cap(chips)!CAP_0603-22.0UF,4V,20%,X6S,E15A!!!F2956!A!!!!
S!GND!C3M7!2!@baseboard_fab2_lib.baseboard_fab2(sch_1):page132_i2@mstr_discrete.cap(chips)!CAP_0603-22.0UF,4V,20%,X6S,E15A!!!F2956!B!!!!
S!PVNN_PCH_STBY!C7A36!1!@baseboard_fab2_lib.baseboard_fab2(sch_1):page132_i11@mstr_discrete.cap(chips)!CAP_0603-22.0UF,4V,20%,X6S,E15A!!!F2811!A!!!!
S!GND!C7A36!2!@baseboard_fab2_lib.baseboard_fab2(sch_1):page132_i11@mstr_discrete.cap(chips)!CAP_0603-22.0UF,4V,20%,X6S,E15A!!!F2811!B!!!!
S!PVNN_PCH_STBY!C3N30!1!@baseboard_fab2_lib.baseboard_fab2(sch_1):page132_i9@mstr_discrete.cap(chips)!CAP_0603-22.0UF,4V,20%,X6S,E15A!!!F2949!A!!!!
S!GND!C3N30!2!@baseboard_fab2_lib.baseboard_fab2(sch_1):page132_i9@mstr_discrete.cap(chips)!CAP_0603-22.0UF,4V,20%,X6S,E15A!!!F2949!B!!!!
S!PVNN_PCH_STBY!C7C9!1!@baseboard_fab2_lib.baseboard_fab2(sch_1):page132_i7@mstr_discrete.cap(chips)!CAP_0603-22.0UF,4V,20%,X6S,E15A!!!F2799!A!!!!
S!GND!C7C9!2!@baseboard_fab2_lib.baseboard_fab2(sch_1):page132_i7@mstr_discrete.cap(chips)!CAP_0603-22.0UF,4V,20%,X6S,E15A!!!F2799!B!!!!
S!PVNN_PCH_STBY!C3L25!1!@baseboard_fab2_lib.baseboard_fab2(sch_1):page132_i1@mstr_discrete.cap(chips)!CAP_0603-22.0UF,4V,20%,X6S,E15A!!!F2960!A!!!!
S!GND!C3L25!2!@baseboard_fab2_lib.baseboard_fab2(sch_1):page132_i1@mstr_discrete.cap(chips)!CAP_0603-22.0UF,4V,20%,X6S,E15A!!!F2960!B!!!!
S!PVNN_PCH_STBY!C3N27!1!@baseboard_fab2_lib.baseboard_fab2(sch_1):page132_i8@mstr_discrete.cap(chips)!CAP_0603-22.0UF,4V,20%,X6S,E15A!!!F2951!A!!!!
S!GND!C3N27!2!@baseboard_fab2_lib.baseboard_fab2(sch_1):page132_i8@mstr_discrete.cap(chips)!CAP_0603-22.0UF,4V,20%,X6S,E15A!!!F2951!B!!!!
S!P1V8_PCH_STBY!C2M2!1!@baseboard_fab2_lib.baseboard_fab2(sch_1):page130_i45@mstr_discrete.cap(chips)!CAP_0603-22.0UF,4V,20%,X6S,E15A!!!F2999!A!!!!
S!GND!C2M2!2!@baseboard_fab2_lib.baseboard_fab2(sch_1):page130_i45@mstr_discrete.cap(chips)!CAP_0603-22.0UF,4V,20%,X6S,E15A!!!F2999!B!!!!
S!P1V8_PCH_STBY!C8B4!1!@baseboard_fab2_lib.baseboard_fab2(sch_1):page130_i39@mstr_discrete.cap(chips)!CAP_0603-22.0UF,4V,20%,X6S,E15A!!!F2782!A!!!!
S!GND!C8B4!2!@baseboard_fab2_lib.baseboard_fab2(sch_1):page130_i39@mstr_discrete.cap(chips)!CAP_0603-22.0UF,4V,20%,X6S,E15A!!!F2782!B!!!!
S!P1V8_PCH_STBY!C7D3!1!@baseboard_fab2_lib.baseboard_fab2(sch_1):page130_i38@mstr_discrete.cap(chips)!CAP_0603-22.0UF,4V,20%,X6S,E15A!!!F2797!A!!!!
S!GND!C7D3!2!@baseboard_fab2_lib.baseboard_fab2(sch_1):page130_i38@mstr_discrete.cap(chips)!CAP_0603-22.0UF,4V,20%,X6S,E15A!!!F2797!B!!!!
S!P1V8_PCH_STBY!C2M1!1!@baseboard_fab2_lib.baseboard_fab2(sch_1):page130_i43@mstr_discrete.cap(chips)!CAP_0603-22.0UF,4V,20%,X6S,E15A!!!F3000!A!!!!
S!GND!C2M1!2!@baseboard_fab2_lib.baseboard_fab2(sch_1):page130_i43@mstr_discrete.cap(chips)!CAP_0603-22.0UF,4V,20%,X6S,E15A!!!F3000!B!!!!
S!P1V8_PCH_STBY!C8B2!1!@baseboard_fab2_lib.baseboard_fab2(sch_1):page130_i30@mstr_discrete.cap(chips)!CAP_0603-22.0UF,4V,20%,X6S,E15A!!!F2784!A!!!!
S!GND!C8B2!2!@baseboard_fab2_lib.baseboard_fab2(sch_1):page130_i30@mstr_discrete.cap(chips)!CAP_0603-22.0UF,4V,20%,X6S,E15A!!!F2784!B!!!!
S!P1V8_PCH_STBY!C8B1!1!@baseboard_fab2_lib.baseboard_fab2(sch_1):page130_i41@mstr_discrete.cap(chips)!CAP_0603-22.0UF,4V,20%,X6S,E15A!!!F2785!A!!!!
S!GND!C8B1!2!@baseboard_fab2_lib.baseboard_fab2(sch_1):page130_i41@mstr_discrete.cap(chips)!CAP_0603-22.0UF,4V,20%,X6S,E15A!!!F2785!B!!!!
S!P1V05_PCH_STBY!C7B17!1!@baseboard_fab2_lib.baseboard_fab2(sch_1):page131_i18@mstr_discrete.cap(chips)!CAP_0603-22.0UF,4V,20%,X6S,E15A!!!F2808!A!!!!
S!GND!C7B17!2!@baseboard_fab2_lib.baseboard_fab2(sch_1):page131_i18@mstr_discrete.cap(chips)!CAP_0603-22.0UF,4V,20%,X6S,E15A!!!F2808!B!!!!
S!P1V05_PCH_STBY!C7B20!1!@baseboard_fab2_lib.baseboard_fab2(sch_1):page131_i6@mstr_discrete.cap(chips)!CAP_0603-22.0UF,4V,20%,X6S,E15A!!!F2805!A!!!!
S!GND!C7B20!2!@baseboard_fab2_lib.baseboard_fab2(sch_1):page131_i6@mstr_discrete.cap(chips)!CAP_0603-22.0UF,4V,20%,X6S,E15A!!!F2805!B!!!!
S!P1V05_PCH_STBY!C7B18!1!@baseboard_fab2_lib.baseboard_fab2(sch_1):page131_i12@mstr_discrete.cap(chips)!CAP_0603-22.0UF,4V,20%,X6S,E15A!!!F2807!A!!!!
S!GND!C7B18!2!@baseboard_fab2_lib.baseboard_fab2(sch_1):page131_i12@mstr_discrete.cap(chips)!CAP_0603-22.0UF,4V,20%,X6S,E15A!!!F2807!B!!!!
S!P1V05_PCH_STBY!C7B21!1!@baseboard_fab2_lib.baseboard_fab2(sch_1):page131_i4@mstr_discrete.cap(chips)!CAP_0603-22.0UF,4V,20%,X6S,E15A!!!F2804!A!!!!
S!GND!C7B21!2!@baseboard_fab2_lib.baseboard_fab2(sch_1):page131_i4@mstr_discrete.cap(chips)!CAP_0603-22.0UF,4V,20%,X6S,E15A!!!F2804!B!!!!
S!P1V05_PCH_STBY!C7B24!1!@baseboard_fab2_lib.baseboard_fab2(sch_1):page131_i11@mstr_discrete.cap(chips)!CAP_0603-22.0UF,4V,20%,X6S,E15A!!!F2801!A!!!!
S!GND!C7B24!2!@baseboard_fab2_lib.baseboard_fab2(sch_1):page131_i11@mstr_discrete.cap(chips)!CAP_0603-22.0UF,4V,20%,X6S,E15A!!!F2801!B!!!!
S!P1V05_PCH_STBY!C7B16!1!@baseboard_fab2_lib.baseboard_fab2(sch_1):page131_i3@mstr_discrete.cap(chips)!CAP_0603-22.0UF,4V,20%,X6S,E15A!!!F2809!A!!!!
S!GND!C7B16!2!@baseboard_fab2_lib.baseboard_fab2(sch_1):page131_i3@mstr_discrete.cap(chips)!CAP_0603-22.0UF,4V,20%,X6S,E15A!!!F2809!B!!!!
S!P1V05_PCH_STBY!C7B22!1!@baseboard_fab2_lib.baseboard_fab2(sch_1):page131_i10@mstr_discrete.cap(chips)!CAP_0603-22.0UF,4V,20%,X6S,E15A!!!F2803!A!!!!
S!GND!C7B22!2!@baseboard_fab2_lib.baseboard_fab2(sch_1):page131_i10@mstr_discrete.cap(chips)!CAP_0603-22.0UF,4V,20%,X6S,E15A!!!F2803!B!!!!
S!P1V05_PCH_STBY!C7B19!1!@baseboard_fab2_lib.baseboard_fab2(sch_1):page131_i2@mstr_discrete.cap(chips)!CAP_0603-22.0UF,4V,20%,X6S,E15A!!!F2806!A!!!!
S!GND!C7B19!2!@baseboard_fab2_lib.baseboard_fab2(sch_1):page131_i2@mstr_discrete.cap(chips)!CAP_0603-22.0UF,4V,20%,X6S,E15A!!!F2806!B!!!!
S!P1V05_PCH_STBY!C7B23!1!@baseboard_fab2_lib.baseboard_fab2(sch_1):page131_i7@mstr_discrete.cap(chips)!CAP_0603-22.0UF,4V,20%,X6S,E15A!!!F2802!A!!!!
S!GND!C7B23!2!@baseboard_fab2_lib.baseboard_fab2(sch_1):page131_i7@mstr_discrete.cap(chips)!CAP_0603-22.0UF,4V,20%,X6S,E15A!!!F2802!B!!!!
S!P1V05_PCH_STBY!C7B15!1!@baseboard_fab2_lib.baseboard_fab2(sch_1):page131_i1@mstr_discrete.cap(chips)!CAP_0603-22.0UF,4V,20%,X6S,E15A!!!F2810!A!!!!
S!GND!C7B15!2!@baseboard_fab2_lib.baseboard_fab2(sch_1):page131_i1@mstr_discrete.cap(chips)!CAP_0603-22.0UF,4V,20%,X6S,E15A!!!F2810!B!!!!
S!P1V05_PCH_STBY!C8B13!1!@baseboard_fab2_lib.baseboard_fab2(sch_1):page131_i20@mstr_discrete.cap(chips)!CAP_0603-22.0UF,4V,20%,X6S,E15A!!!F2778!A!!!!
S!GND!C8B13!2!@baseboard_fab2_lib.baseboard_fab2(sch_1):page131_i20@mstr_discrete.cap(chips)!CAP_0603-22.0UF,4V,20%,X6S,E15A!!!F2778!B!!!!
S!P1V05_PCH_STBY!C8B14!1!@baseboard_fab2_lib.baseboard_fab2(sch_1):page131_i16@mstr_discrete.cap(chips)!CAP_0603-22.0UF,4V,20%,X6S,E15A!!!F2777!A!!!!
S!GND!C8B14!2!@baseboard_fab2_lib.baseboard_fab2(sch_1):page131_i16@mstr_discrete.cap(chips)!CAP_0603-22.0UF,4V,20%,X6S,E15A!!!F2777!B!!!!
S!P1V05_PCH_STBY!C8B11!1!@baseboard_fab2_lib.baseboard_fab2(sch_1):page131_i15@mstr_discrete.cap(chips)!CAP_0603-22.0UF,4V,20%,X6S,E15A!!!F2779!A!!!!
S!GND!C8B11!2!@baseboard_fab2_lib.baseboard_fab2(sch_1):page131_i15@mstr_discrete.cap(chips)!CAP_0603-22.0UF,4V,20%,X6S,E15A!!!F2779!B!!!!
S!P1V05_PCH_STBY!C8B9!1!@baseboard_fab2_lib.baseboard_fab2(sch_1):page131_i14@mstr_discrete.cap(chips)!CAP_0603-22.0UF,4V,20%,X6S,E15A!!!F2781!A!!!!
S!GND!C8B9!2!@baseboard_fab2_lib.baseboard_fab2(sch_1):page131_i14@mstr_discrete.cap(chips)!CAP_0603-22.0UF,4V,20%,X6S,E15A!!!F2781!B!!!!
S!P1V05_PCH_STBY!C8B10!1!@baseboard_fab2_lib.baseboard_fab2(sch_1):page131_i8@mstr_discrete.cap(chips)!CAP_0603-22.0UF,4V,20%,X6S,E15A!!!F2780!A!!!!
S!GND!C8B10!2!@baseboard_fab2_lib.baseboard_fab2(sch_1):page131_i8@mstr_discrete.cap(chips)!CAP_0603-22.0UF,4V,20%,X6S,E15A!!!F2780!B!!!!
S!P1V8_PCH_STBY!C8B3!1!@baseboard_fab2_lib.baseboard_fab2(sch_1):page130_i32@mstr_discrete.cap(chips)!CAP_0603-22.0UF,4V,20%,X6S,E15A!!!F2783!A!!!!
S!GND!C8B3!2!@baseboard_fab2_lib.baseboard_fab2(sch_1):page130_i32@mstr_discrete.cap(chips)!CAP_0603-22.0UF,4V,20%,X6S,E15A!!!F2783!B!!!!
S!P1V05_PCH_STBY!C2M12!1!@baseboard_fab2_lib.baseboard_fab2(sch_1):page131_i52@mstr_discrete.cap(chips)!CAP_0603-22.0UF,4V,20%,X6S,E15A!!!F2998!A!!!!
S!GND!C2M12!2!@baseboard_fab2_lib.baseboard_fab2(sch_1):page131_i52@mstr_discrete.cap(chips)!CAP_0603-22.0UF,4V,20%,X6S,E15A!!!F2998!B!!!!
S!P1V05_PCH_STBY!C2N10!1!@baseboard_fab2_lib.baseboard_fab2(sch_1):page131_i50@mstr_discrete.cap(chips)!CAP_0603-22.0UF,4V,20%,X6S,E15A!!!F2996!A!!!!
S!GND!C2N10!2!@baseboard_fab2_lib.baseboard_fab2(sch_1):page131_i50@mstr_discrete.cap(chips)!CAP_0603-22.0UF,4V,20%,X6S,E15A!!!F2996!B!!!!
S!P1V05_PCH_STBY!C2M13!1!@baseboard_fab2_lib.baseboard_fab2(sch_1):page131_i48@mstr_discrete.cap(chips)!CAP_0603-22.0UF,4V,20%,X6S,E15A!!!F2997!A!!!!
S!GND!C2M13!2!@baseboard_fab2_lib.baseboard_fab2(sch_1):page131_i48@mstr_discrete.cap(chips)!CAP_0603-22.0UF,4V,20%,X6S,E15A!!!F2997!B!!!!
S!A_CPU1_GHJ_RCOMP1!R7P17!1!@baseboard_fab2_lib.baseboard_fab2(sch_1):page55_i140@mstr_discrete.res(chips)!RES_0402-90.9,1%,1/16W,CHIP,G2A!!!F284!A!!!!
S!GND!R7P17!2!@baseboard_fab2_lib.baseboard_fab2(sch_1):page55_i140@mstr_discrete.res(chips)!RES_0402-90.9,1%,1/16W,CHIP,G2A!!!F284!B!!!!
S!A_CPU0_ABC_RCOMP1!R4P10!1!@baseboard_fab2_lib.baseboard_fab2(sch_1):page21_i181@mstr_discrete.res(chips)!RES_0402-90.9,1%,1/16W,CHIP,G2A!!!F288!A!!!!
S!GND!R4P10!2!@baseboard_fab2_lib.baseboard_fab2(sch_1):page21_i181@mstr_discrete.res(chips)!RES_0402-90.9,1%,1/16W,CHIP,G2A!!!F288!B!!!!
S!A_CPU0_ABC_RCOMP0!R4P8!1!@baseboard_fab2_lib.baseboard_fab2(sch_1):page21_i180@mstr_discrete.res(chips)!RES_0402-90.9,1%,1/16W,CHIP,G2A!!!F289!A!!!!
S!GND!R4P8!2!@baseboard_fab2_lib.baseboard_fab2(sch_1):page21_i180@mstr_discrete.res(chips)!RES_0402-90.9,1%,1/16W,CHIP,G2A!!!F289!B!!!!
S!A_CPU0_DEF_RCOMP1!R5D2!1!@baseboard_fab2_lib.baseboard_fab2(sch_1):page21_i178@mstr_discrete.res(chips)!RES_0402-90.9,1%,1/16W,CHIP,G2A!!!F286!A!!!!
S!GND!R5D2!2!@baseboard_fab2_lib.baseboard_fab2(sch_1):page21_i178@mstr_discrete.res(chips)!RES_0402-90.9,1%,1/16W,CHIP,G2A!!!F286!B!!!!
S!A_CPU0_DEF_RCOMP0!R5D1!1!@baseboard_fab2_lib.baseboard_fab2(sch_1):page21_i177@mstr_discrete.res(chips)!RES_0402-90.9,1%,1/16W,CHIP,G2A!!!F287!A!!!!
S!GND!R5D1!2!@baseboard_fab2_lib.baseboard_fab2(sch_1):page21_i177@mstr_discrete.res(chips)!RES_0402-90.9,1%,1/16W,CHIP,G2A!!!F287!B!!!!
S!A_CPU1_GHJ_RCOMP0!R7P16!1!@baseboard_fab2_lib.baseboard_fab2(sch_1):page55_i119@mstr_discrete.res(chips)!RES_0402-90.9,1%,1/16W,CHIP,G2A!!!F285!A!!!!
S!GND!R7P16!2!@baseboard_fab2_lib.baseboard_fab2(sch_1):page55_i119@mstr_discrete.res(chips)!RES_0402-90.9,1%,1/16W,CHIP,G2A!!!F285!B!!!!
S!A_CPU1_KLM_RCOMP1!R3D2!1!@baseboard_fab2_lib.baseboard_fab2(sch_1):page55_i117@mstr_discrete.res(chips)!RES_0402-90.9,1%,1/16W,CHIP,G2A!!!F290!A!!!!
S!GND!R3D2!2!@baseboard_fab2_lib.baseboard_fab2(sch_1):page55_i117@mstr_discrete.res(chips)!RES_0402-90.9,1%,1/16W,CHIP,G2A!!!F290!B!!!!
S!A_CPU1_KLM_RCOMP0!R3D1!1!@baseboard_fab2_lib.baseboard_fab2(sch_1):page55_i116@mstr_discrete.res(chips)!RES_0402-90.9,1%,1/16W,CHIP,G2A!!!F291!A!!!!
S!GND!R3D1!2!@baseboard_fab2_lib.baseboard_fab2(sch_1):page55_i116@mstr_discrete.res(chips)!RES_0402-90.9,1%,1/16W,CHIP,G2A!!!F291!B!!!!
S!A_P3V_BAT_R!R1U50!1!@baseboard_fab2_lib.baseboard_fab2(sch_1):page169_i126@mstr_discrete.res(chips)!RES_0402-200.0K,1%,1/16W,CHIP,A!!!F889!A!!!!
S!P3V_BAT_SOURCE_R!R1U50!2!@baseboard_fab2_lib.baseboard_fab2(sch_1):page169_i126@mstr_discrete.res(chips)!RES_0402-200.0K,1%,1/16W,CHIP,A!!!F889!B!!!!
S!P3V3_STBY_BMC_ADCVREFP!C9G8!1!@baseboard_fab2_lib.baseboard_fab2(sch_1):page147_i75@mstr_discrete.cap(chips)!CAP_0402-0.1UF,16V,10%,EMPTY,AA!!!F4085!A!!!!
S!P3V3_STBY_BMC_ADCVREFN!C9G8!2!@baseboard_fab2_lib.baseboard_fab2(sch_1):page147_i75@mstr_discrete.cap(chips)!CAP_0402-0.1UF,16V,10%,EMPTY,AA!!!F4085!B!!!!
S!GND!C9G10!1!@baseboard_fab2_lib.baseboard_fab2(sch_1):page147_i79@mstr_discrete.cap(chips)!CAP_0402-0.1UF,16V,10%,EMPTY,AA!!!F4084!A!!!!
S!P3V3_STBY_BMC_ADCVREFN!C9G10!2!@baseboard_fab2_lib.baseboard_fab2(sch_1):page147_i79@mstr_discrete.cap(chips)!CAP_0402-0.1UF,16V,10%,EMPTY,AA!!!F4084!B!!!!
S!P3V3_STBY_BMC_ADCAV33!C9G11!1!@baseboard_fab2_lib.baseboard_fab2(sch_1):page147_i76@mstr_discrete.cap(chips)!CAP_0402-0.1UF,16V,10%,EMPTY,AA!!!F4083!A!!!!
S!P3V3_STBY_BMC_ADCVREFP!C9G11!2!@baseboard_fab2_lib.baseboard_fab2(sch_1):page147_i76@mstr_discrete.cap(chips)!CAP_0402-0.1UF,16V,10%,EMPTY,AA!!!F4083!B!!!!
S!FM_PWRBRK_N!Q7E8!3!@baseboard_fab2_lib.baseboard_fab2(sch_1):page95_i119@mstr_discrete.fet_n(chips)!FET_N_SOT23-2N7002,FET,C79254-A!!!F2142!DRN!!!!
S!FM_SYS_THROTTLE_LVC3!Q7E8!1!@baseboard_fab2_lib.baseboard_fab2(sch_1):page95_i119@mstr_discrete.fet_n(chips)!FET_N_SOT23-2N7002,FET,C79254-A!!!F2142!GATE!!!!
S!GND!Q7E8!2!@baseboard_fab2_lib.baseboard_fab2(sch_1):page95_i119@mstr_discrete.fet_n(chips)!FET_N_SOT23-2N7002,FET,C79254-A!!!F2142!SRC!!!!
S!PWRGD_P5V_R!Q2P2!3!@baseboard_fab2_lib.baseboard_fab2(sch_1):page196_i124@mstr_discrete.fet_n(chips)!FET_N_SOT23-2N7002,FET,C79254-A!!!F2143!DRN!!!!
S!PWRGD_P5V_N!Q2P2!1!@baseboard_fab2_lib.baseboard_fab2(sch_1):page196_i124@mstr_discrete.fet_n(chips)!FET_N_SOT23-2N7002,FET,C79254-A!!!F2143!GATE!!!!
S!GND!Q2P2!2!@baseboard_fab2_lib.baseboard_fab2(sch_1):page196_i124@mstr_discrete.fet_n(chips)!FET_N_SOT23-2N7002,FET,C79254-A!!!F2143!SRC!!!!
S!FM_PCH_BMC_THERMTRIP_N!Q8D2!3!@baseboard_fab2_lib.baseboard_fab2(sch_1):page135_i100@mstr_discrete.fet_n(chips)!FET_N_SOT23-2N7002,FET,C79254-A!!!F2144!DRN!!!!
S!RST_PLTRST_BUF_N!Q8D2!1!@baseboard_fab2_lib.baseboard_fab2(sch_1):page135_i100@mstr_discrete.fet_n(chips)!FET_N_SOT23-2N7002,FET,C79254-A!!!F2144!GATE!!!!
S!FM_PCH_BMC_THERMTRIP_EXI_STRAP_!Q8D2!2!@baseboard_fab2_lib.baseboard_fab2(sch_1):page135_i100@mstr_discrete.fet_n(chips)!FET_N_SOT23-2N7002,FET,C79254-A!!!F2144!SRC!!!!
S!FM_SYS_THROTTLE_LVC3!Q7E4!3!@baseboard_fab2_lib.baseboard_fab2(sch_1):page95_i104@mstr_discrete.fet_n(chips)!FET_N_SOT23-2N7002,FET,C79254-A!!!F2139!DRN!!!!
S!FM_THROTTLE_R_N!Q7E4!1!@baseboard_fab2_lib.baseboard_fab2(sch_1):page95_i104@mstr_discrete.fet_n(chips)!FET_N_SOT23-2N7002,FET,C79254-A!!!F2139!GATE!!!!
S!GND!Q7E4!2!@baseboard_fab2_lib.baseboard_fab2(sch_1):page95_i104@mstr_discrete.fet_n(chips)!FET_N_SOT23-2N7002,FET,C79254-A!!!F2139!SRC!!!!
S!IRQ_DIMM_SAVE_N!Q6F1!3!@baseboard_fab2_lib.baseboard_fab2(sch_1):page89_i18@mstr_discrete.fet_n(chips)!FET_N_SOT23-2N7002,FET,C79254-A!!!F2141!DRN!!!!
S!FM_ADR_COMPLETE_R!Q6F1!1!@baseboard_fab2_lib.baseboard_fab2(sch_1):page89_i18@mstr_discrete.fet_n(chips)!FET_N_SOT23-2N7002,FET,C79254-A!!!F2141!GATE!!!!
S!GND!Q6F1!2!@baseboard_fab2_lib.baseboard_fab2(sch_1):page89_i18@mstr_discrete.fet_n(chips)!FET_N_SOT23-2N7002,FET,C79254-A!!!F2141!SRC!!!!
S!FM_THERMTRIP_DLY_R!Q7D1!1!@baseboard_fab2_lib.baseboard_fab2(sch_1):page135_i76@mstr_discrete.fet_n(chips)!FET_N_SOT23-2N7002,FET,C79254-A!!!F2140!GATE!!!!
S!FM_PCH_LVC1_THERMTRIP_N!Q7D1!3!@baseboard_fab2_lib.baseboard_fab2(sch_1):page135_i76@mstr_discrete.fet_n(chips)!FET_N_SOT23-2N7002,FET,C79254-A!!!F2140!DRN!!!!
S!GND!Q7D1!2!@baseboard_fab2_lib.baseboard_fab2(sch_1):page135_i76@mstr_discrete.fet_n(chips)!FET_N_SOT23-2N7002,FET,C79254-A!!!F2140!SRC!!!!
S!GND!U8D4!4!!AT24C64_SOICLF-IC,C47049-001-GA!!!!!!!!
S!P3V3_STBY!U8D4!8!!AT24C64_SOICLF-IC,C47049-001-GA!!!!!!!!
S!GND!U8D4!1!@baseboard_fab2_lib.baseboard_fab2(sch_1):page167_i49@mstr_memory.at24c64(chips)!AT24C64_SOICLF-IC,C47049-001-GA!!!F4186!A0!!!!
S!GND!U8D4!2!@baseboard_fab2_lib.baseboard_fab2(sch_1):page167_i49@mstr_memory.at24c64(chips)!AT24C64_SOICLF-IC,C47049-001-GA!!!F4186!A1!!!!
S!PU_AT24C64_A2!U8D4!3!@baseboard_fab2_lib.baseboard_fab2(sch_1):page167_i49@mstr_memory.at24c64(chips)!AT24C64_SOICLF-IC,C47049-001-GA!!!F4186!A2!!!!
S!SMB_SENSOR_STBY_LVC3_SCL_R2!U8D4!6!@baseboard_fab2_lib.baseboard_fab2(sch_1):page167_i49@mstr_memory.at24c64(chips)!AT24C64_SOICLF-IC,C47049-001-GA!!!F4186!SCL!!!!
S!SMB_SENSOR_STBY_LVC3_SDA_R2!U8D4!5!@baseboard_fab2_lib.baseboard_fab2(sch_1):page167_i49@mstr_memory.at24c64(chips)!AT24C64_SOICLF-IC,C47049-001-GA!!!F4186!SDA!!!!
S!PD_FRU_WP!U8D4!7!@baseboard_fab2_lib.baseboard_fab2(sch_1):page167_i49@mstr_memory.at24c64(chips)!AT24C64_SOICLF-IC,C47049-001-GA!!!F4186!WP!!!!
S!ISENSE_TMP421_1_DXP!C1M4!1!@baseboard_fab2_lib.baseboard_fab2(sch_1):page167_i7@mstr_discrete.cap(chips)!CAP_0402LF-47.0PF,50V,5%,EMPTYA!!!F3104!A!!!!
S!ISENSE_TMP421_1_DXN!C1M4!2!@baseboard_fab2_lib.baseboard_fab2(sch_1):page167_i7@mstr_discrete.cap(chips)!CAP_0402LF-47.0PF,50V,5%,EMPTYA!!!F3104!B!!!!
S!ISENSE_TMP421_2_DXP!C1E19!1!@baseboard_fab2_lib.baseboard_fab2(sch_1):page167_i24@mstr_discrete.cap(chips)!CAP_0402LF-47.0PF,50V,5%,EMPTYA!!!F3105!A!!!!
S!ISENSE_TMP421_2_DXN!C1E19!2!@baseboard_fab2_lib.baseboard_fab2(sch_1):page167_i24@mstr_discrete.cap(chips)!CAP_0402LF-47.0PF,50V,5%,EMPTYA!!!F3105!B!!!!
S!P1V05_PCH_STBY!L2M1!1!@baseboard_fab2_lib.baseboard_fab2(sch_1):page127_i71@mstr_discrete.inductor(chips)!INDUCTOR_SMT-0.022UH,IND,72189A!!!F2081!INA!!!!
S!P1V05_PCH_STBY_KR_PLL!L2M1!2!@baseboard_fab2_lib.baseboard_fab2(sch_1):page127_i71@mstr_discrete.inductor(chips)!INDUCTOR_SMT-0.022UH,IND,72189A!!!F2081!INB!!!!
S!ISENSE_TMP421_1_BC!Q9B1!1!@baseboard_fab2_lib.baseboard_fab2(sch_1):page167_i3@mstr_discrete.pnp(chips)!PNP_TO92-MPS2907,IC,G73554-001!!!F1977!B!!!!
S!ISENSE_TMP421_1_BC!Q9B1!3!@baseboard_fab2_lib.baseboard_fab2(sch_1):page167_i3@mstr_discrete.pnp(chips)!PNP_TO92-MPS2907,IC,G73554-001!!!F1977!C!!!!
S!ISENSE_TMP421_1_E!Q9B1!2!@baseboard_fab2_lib.baseboard_fab2(sch_1):page167_i3@mstr_discrete.pnp(chips)!PNP_TO92-MPS2907,IC,G73554-001!!!F1977!E!!!!
S!ISENSE_TMP421_2_BC!Q1E1!1!@baseboard_fab2_lib.baseboard_fab2(sch_1):page167_i27@mstr_discrete.pnp(chips)!PNP_TO92-MPS2907,IC,G73554-001!!!F1978!B!!!!
S!ISENSE_TMP421_2_BC!Q1E1!3!@baseboard_fab2_lib.baseboard_fab2(sch_1):page167_i27@mstr_discrete.pnp(chips)!PNP_TO92-MPS2907,IC,G73554-001!!!F1978!C!!!!
S!ISENSE_TMP421_2_E!Q1E1!2!@baseboard_fab2_lib.baseboard_fab2(sch_1):page167_i27@mstr_discrete.pnp(chips)!PNP_TO92-MPS2907,IC,G73554-001!!!F1978!E!!!!
S!PD_TMP421_1_A0!U9B4!4!@baseboard_fab2_lib.baseboard_fab2(sch_1):page167_i1@mstr_analog.tmp421(chips)!TMP421_TSSOP-IC,G62962-001!!!F61!A(0)!!!!
S!PU_TMP421_1_A1!U9B4!3!@baseboard_fab2_lib.baseboard_fab2(sch_1):page167_i1@mstr_analog.tmp421(chips)!TMP421_TSSOP-IC,G62962-001!!!F61!A(1)!!!!
S!ISENSE_TMP421_1_DXN!U9B4!2!@baseboard_fab2_lib.baseboard_fab2(sch_1):page167_i1@mstr_analog.tmp421(chips)!TMP421_TSSOP-IC,G62962-001!!!F61!DXN!!!!
S!ISENSE_TMP421_1_DXP!U9B4!1!@baseboard_fab2_lib.baseboard_fab2(sch_1):page167_i1@mstr_analog.tmp421(chips)!TMP421_TSSOP-IC,G62962-001!!!F61!DXP!!!!
S!GND!U9B4!5!@baseboard_fab2_lib.baseboard_fab2(sch_1):page167_i1@mstr_analog.tmp421(chips)!TMP421_TSSOP-IC,G62962-001!!!F61!GND!!!!
S!SMB_SENSOR_TMP421_1_SCL!U9B4!7!@baseboard_fab2_lib.baseboard_fab2(sch_1):page167_i1@mstr_analog.tmp421(chips)!TMP421_TSSOP-IC,G62962-001!!!F61!SCL!!!!
S!SMB_SENSOR_TMP421_1_SDA!U9B4!6!@baseboard_fab2_lib.baseboard_fab2(sch_1):page167_i1@mstr_analog.tmp421(chips)!TMP421_TSSOP-IC,G62962-001!!!F61!SDA!!!!
S!P3V3_STBY!U9B4!8!@baseboard_fab2_lib.baseboard_fab2(sch_1):page167_i1@mstr_analog.tmp421(chips)!TMP421_TSSOP-IC,G62962-001!!!F61!VP!!!!
S!PU_TMP421_2_A0!U1E1!4!@baseboard_fab2_lib.baseboard_fab2(sch_1):page167_i30@mstr_analog.tmp421(chips)!TMP421_TSSOP-IC,G62962-001!!!F62!A(0)!!!!
S!PD_TMP421_2_A1!U1E1!3!@baseboard_fab2_lib.baseboard_fab2(sch_1):page167_i30@mstr_analog.tmp421(chips)!TMP421_TSSOP-IC,G62962-001!!!F62!A(1)!!!!
S!ISENSE_TMP421_2_DXN!U1E1!2!@baseboard_fab2_lib.baseboard_fab2(sch_1):page167_i30@mstr_analog.tmp421(chips)!TMP421_TSSOP-IC,G62962-001!!!F62!DXN!!!!
S!ISENSE_TMP421_2_DXP!U1E1!1!@baseboard_fab2_lib.baseboard_fab2(sch_1):page167_i30@mstr_analog.tmp421(chips)!TMP421_TSSOP-IC,G62962-001!!!F62!DXP!!!!
S!GND!U1E1!5!@baseboard_fab2_lib.baseboard_fab2(sch_1):page167_i30@mstr_analog.tmp421(chips)!TMP421_TSSOP-IC,G62962-001!!!F62!GND!!!!
S!SMB_SENSOR_TMP421_2_SCL!U1E1!7!@baseboard_fab2_lib.baseboard_fab2(sch_1):page167_i30@mstr_analog.tmp421(chips)!TMP421_TSSOP-IC,G62962-001!!!F62!SCL!!!!
S!SMB_SENSOR_TMP421_2_SDA!U1E1!6!@baseboard_fab2_lib.baseboard_fab2(sch_1):page167_i30@mstr_analog.tmp421(chips)!TMP421_TSSOP-IC,G62962-001!!!F62!SDA!!!!
S!P3V3_STBY!U1E1!8!@baseboard_fab2_lib.baseboard_fab2(sch_1):page167_i30@mstr_analog.tmp421(chips)!TMP421_TSSOP-IC,G62962-001!!!F62!VP!!!!
S!P3V3_STBY!C9E11!1!@baseboard_fab2_lib.baseboard_fab2(sch_1):page238_i39@mstr_discrete.cap(chips)!CAP_0402-1.0UF,16V,10%,X6S,D97A!!!F3759!A!!!!
S!GND!C9E11!2!@baseboard_fab2_lib.baseboard_fab2(sch_1):page238_i39@mstr_discrete.cap(chips)!CAP_0402-1.0UF,16V,10%,X6S,D97A!!!F3759!B!!!!
S!A_HSC_VCAP!C1D19!1!@baseboard_fab2_lib.baseboard_fab2(sch_1):page199_i119@mstr_discrete.cap(chips)!CAP_0402-1.0UF,16V,10%,X6S,D97A!!!F3817!A!!!!
S!AGND_HSC!C1D19!2!@baseboard_fab2_lib.baseboard_fab2(sch_1):page199_i119@mstr_discrete.cap(chips)!CAP_0402-1.0UF,16V,10%,X6S,D97A!!!F3817!B!!!!
S!VR_PVCCIN_CPU0_PH1_VCIN!C4E10!1!@baseboard_fab2_lib.baseboard_fab2(sch_1):page202_i34@mstr_discrete.cap(chips)!CAP_0402-1.0UF,16V,10%,X6S,D97A!!!F3786!A!!!!
S!GND!C4E10!2!@baseboard_fab2_lib.baseboard_fab2(sch_1):page202_i34@mstr_discrete.cap(chips)!CAP_0402-1.0UF,16V,10%,X6S,D97A!!!F3786!B!!!!
S!VR_FET_SW_P12V_STBY_PVCCIO_CPU0!C7C12!1!@baseboard_fab2_lib.baseboard_fab2(sch_1):page212_i39@mstr_discrete.cap(chips)!CAP_0402-1.0UF,16V,10%,X6S,D97A!!!F3768!A!!!!
S!GND!C7C12!2!@baseboard_fab2_lib.baseboard_fab2(sch_1):page212_i39@mstr_discrete.cap(chips)!CAP_0402-1.0UF,16V,10%,X6S,D97A!!!F3768!B!!!!
S!VR_PVCCIO_CPU0_PH1_VCIN!C7C17!1!@baseboard_fab2_lib.baseboard_fab2(sch_1):page212_i36@mstr_discrete.cap(chips)!CAP_0402-1.0UF,16V,10%,X6S,D97A!!!F3767!A!!!!
S!GND!C7C17!2!@baseboard_fab2_lib.baseboard_fab2(sch_1):page212_i36@mstr_discrete.cap(chips)!CAP_0402-1.0UF,16V,10%,X6S,D97A!!!F3767!B!!!!
S!VR_FET_SW_P12V_STBY_PVPP_ABC!C3T10!1!@baseboard_fab2_lib.baseboard_fab2(sch_1):page231_i161@mstr_discrete.cap(chips)!CAP_0402-1.0UF,16V,10%,X6S,D97A!!!F3801!A!!!!
S!GND!C3T10!2!@baseboard_fab2_lib.baseboard_fab2(sch_1):page231_i161@mstr_discrete.cap(chips)!CAP_0402-1.0UF,16V,10%,X6S,D97A!!!F3801!B!!!!
S!VR_FET_SW_P12V_STBY_P3V3_STBY!C8E14!1!@baseboard_fab2_lib.baseboard_fab2(sch_1):page240_i139@mstr_discrete.cap(chips)!CAP_0402-1.0UF,16V,10%,X6S,D97A!!!F3760!A!!!!
S!GND!C8E14!2!@baseboard_fab2_lib.baseboard_fab2(sch_1):page240_i139@mstr_discrete.cap(chips)!CAP_0402-1.0UF,16V,10%,X6S,D97A!!!F3760!B!!!!
S!VR_FET_SW_P12V_STBY_PVPP_DEF!C3M9!1!@baseboard_fab2_lib.baseboard_fab2(sch_1):page232_i207@mstr_discrete.cap(chips)!CAP_0402-1.0UF,16V,10%,X6S,D97A!!!F3803!A!!!!
S!GND!C3M9!2!@baseboard_fab2_lib.baseboard_fab2(sch_1):page232_i207@mstr_discrete.cap(chips)!CAP_0402-1.0UF,16V,10%,X6S,D97A!!!F3803!B!!!!
S!VR_FET_SW_P12V_STBY_PVPP_GHJ!C4G4!1!@baseboard_fab2_lib.baseboard_fab2(sch_1):page233_i196@mstr_discrete.cap(chips)!CAP_0402-1.0UF,16V,10%,X6S,D97A!!!F3782!A!!!!
S!GND!C4G4!2!@baseboard_fab2_lib.baseboard_fab2(sch_1):page233_i196@mstr_discrete.cap(chips)!CAP_0402-1.0UF,16V,10%,X6S,D97A!!!F3782!B!!!!
S!VR_FET_SW_P12V_STBY_PVPP_KLM!C6L11!1!@baseboard_fab2_lib.baseboard_fab2(sch_1):page234_i152@mstr_discrete.cap(chips)!CAP_0402-1.0UF,16V,10%,X6S,D97A!!!F3777!A!!!!
S!GND!C6L11!2!@baseboard_fab2_lib.baseboard_fab2(sch_1):page234_i152@mstr_discrete.cap(chips)!CAP_0402-1.0UF,16V,10%,X6S,D97A!!!F3777!B!!!!
S!VR_PVSA_CPU0_VCIN!C4C6!1!@baseboard_fab2_lib.baseboard_fab2(sch_1):page205_i20@mstr_discrete.cap(chips)!CAP_0402-1.0UF,16V,10%,X6S,D97A!!!F3796!A!!!!
S!GND!C4C6!2!@baseboard_fab2_lib.baseboard_fab2(sch_1):page205_i20@mstr_discrete.cap(chips)!CAP_0402-1.0UF,16V,10%,X6S,D97A!!!F3796!B!!!!
S!VR_FET_SW_P12V_STBY_PVCCIN_CPU0!C4D48!1!@baseboard_fab2_lib.baseboard_fab2(sch_1):page202_i47@mstr_discrete.cap(chips)!CAP_0402-1.0UF,16V,10%,X6S,D97A!!!F3787!A!!!!
S!GND!C4D48!2!@baseboard_fab2_lib.baseboard_fab2(sch_1):page202_i47@mstr_discrete.cap(chips)!CAP_0402-1.0UF,16V,10%,X6S,D97A!!!F3787!B!!!!
S!VR_FET_SW_P12V_STBY_PVCCIN_CPU0!C4E19!1!@baseboard_fab2_lib.baseboard_fab2(sch_1):page202_i36@mstr_discrete.cap(chips)!CAP_0402-1.0UF,16V,10%,X6S,D97A!!!F3784!A!!!!
S!GND!C4E19!2!@baseboard_fab2_lib.baseboard_fab2(sch_1):page202_i36@mstr_discrete.cap(chips)!CAP_0402-1.0UF,16V,10%,X6S,D97A!!!F3784!B!!!!
S!VR_PVCCIN_CPU0_PH2_VCIN!C4E26!1!@baseboard_fab2_lib.baseboard_fab2(sch_1):page202_i45@mstr_discrete.cap(chips)!CAP_0402-1.0UF,16V,10%,X6S,D97A!!!F3788!A!!!!
S!GND!C4E26!2!@baseboard_fab2_lib.baseboard_fab2(sch_1):page202_i45@mstr_discrete.cap(chips)!CAP_0402-1.0UF,16V,10%,X6S,D97A!!!F3788!B!!!!
S!VR_FET_SW_P12V_STBY_PVCCIN_CPU0!C4D30!1!@baseboard_fab2_lib.baseboard_fab2(sch_1):page203_i47@mstr_discrete.cap(chips)!CAP_0402-1.0UF,16V,10%,X6S,D97A!!!F3789!A!!!!
S!GND!C4D30!2!@baseboard_fab2_lib.baseboard_fab2(sch_1):page203_i47@mstr_discrete.cap(chips)!CAP_0402-1.0UF,16V,10%,X6S,D97A!!!F3789!B!!!!
S!VR_FET_SW_P12V_STBY_PVCCIN_CPU0!C4D10!1!@baseboard_fab2_lib.baseboard_fab2(sch_1):page203_i53@mstr_discrete.cap(chips)!CAP_0402-1.0UF,16V,10%,X6S,D97A!!!F3791!A!!!!
S!GND!C4D10!2!@baseboard_fab2_lib.baseboard_fab2(sch_1):page203_i53@mstr_discrete.cap(chips)!CAP_0402-1.0UF,16V,10%,X6S,D97A!!!F3791!B!!!!
S!VR_PVCCIN_CPU0_PH3_VCIN!C4D16!1!@baseboard_fab2_lib.baseboard_fab2(sch_1):page203_i45@mstr_discrete.cap(chips)!CAP_0402-1.0UF,16V,10%,X6S,D97A!!!F3790!A!!!!
S!GND!C4D16!2!@baseboard_fab2_lib.baseboard_fab2(sch_1):page203_i45@mstr_discrete.cap(chips)!CAP_0402-1.0UF,16V,10%,X6S,D97A!!!F3790!B!!!!
S!VR_PVCCIN_CPU0_PH4_VCIN!C4D7!1!@baseboard_fab2_lib.baseboard_fab2(sch_1):page203_i51@mstr_discrete.cap(chips)!CAP_0402-1.0UF,16V,10%,X6S,D97A!!!F3792!A!!!!
S!GND!C4D7!2!@baseboard_fab2_lib.baseboard_fab2(sch_1):page203_i51@mstr_discrete.cap(chips)!CAP_0402-1.0UF,16V,10%,X6S,D97A!!!F3792!B!!!!
S!VR_PVCCIN_CPU0_PH5_VCIN!C4D46!1!@baseboard_fab2_lib.baseboard_fab2(sch_1):page204_i34@mstr_discrete.cap(chips)!CAP_0402-1.0UF,16V,10%,X6S,D97A!!!F3794!A!!!!
S!GND!C4D46!2!@baseboard_fab2_lib.baseboard_fab2(sch_1):page204_i34@mstr_discrete.cap(chips)!CAP_0402-1.0UF,16V,10%,X6S,D97A!!!F3794!B!!!!
S!VR_FET_SW_P12V_STBY_PVDDQ_ABC!C7G37!1!@baseboard_fab2_lib.baseboard_fab2(sch_1):page216_i48@mstr_discrete.cap(chips)!CAP_0402-1.0UF,16V,10%,X6S,D97A!!!F3762!A!!!!
S!GND!C7G37!2!@baseboard_fab2_lib.baseboard_fab2(sch_1):page216_i48@mstr_discrete.cap(chips)!CAP_0402-1.0UF,16V,10%,X6S,D97A!!!F3762!B!!!!
S!VR_FET_SW_P12V_STBY_PVDDQ_ABC!C7G30!1!@baseboard_fab2_lib.baseboard_fab2(sch_1):page216_i79@mstr_discrete.cap(chips)!CAP_0402-1.0UF,16V,10%,X6S,D97A!!!F3764!A!!!!
S!GND!C7G30!2!@baseboard_fab2_lib.baseboard_fab2(sch_1):page216_i79@mstr_discrete.cap(chips)!CAP_0402-1.0UF,16V,10%,X6S,D97A!!!F3764!B!!!!
S!VR_PVDDQ_ABC_PH1_VCIN!C7G33!1!@baseboard_fab2_lib.baseboard_fab2(sch_1):page216_i50@mstr_discrete.cap(chips)!CAP_0402-1.0UF,16V,10%,X6S,D97A!!!F3763!A!!!!
S!GND!C7G33!2!@baseboard_fab2_lib.baseboard_fab2(sch_1):page216_i50@mstr_discrete.cap(chips)!CAP_0402-1.0UF,16V,10%,X6S,D97A!!!F3763!B!!!!
S!VR_FET_SW_P12V_STBY_PVCCIN_CPU0!C4C9!1!@baseboard_fab2_lib.baseboard_fab2(sch_1):page205_i32@mstr_discrete.cap(chips)!CAP_0402-1.0UF,16V,10%,X6S,D97A!!!F3795!A!!!!
S!GND!C4C9!2!@baseboard_fab2_lib.baseboard_fab2(sch_1):page205_i32@mstr_discrete.cap(chips)!CAP_0402-1.0UF,16V,10%,X6S,D97A!!!F3795!B!!!!
S!VR_PVDDQ_ABC_PH2_VCIN!C7G40!1!@baseboard_fab2_lib.baseboard_fab2(sch_1):page216_i77@mstr_discrete.cap(chips)!CAP_0402-1.0UF,16V,10%,X6S,D97A!!!F3761!A!!!!
S!GND!C7G40!2!@baseboard_fab2_lib.baseboard_fab2(sch_1):page216_i77@mstr_discrete.cap(chips)!CAP_0402-1.0UF,16V,10%,X6S,D97A!!!F3761!B!!!!
S!VR_FET_SW_P12V_STBY_PVDDQ_DEF!C7A21!1!@baseboard_fab2_lib.baseboard_fab2(sch_1):page219_i79@mstr_discrete.cap(chips)!CAP_0402-1.0UF,16V,10%,X6S,D97A!!!F3770!A!!!!
S!GND!C7A21!2!@baseboard_fab2_lib.baseboard_fab2(sch_1):page219_i79@mstr_discrete.cap(chips)!CAP_0402-1.0UF,16V,10%,X6S,D97A!!!F3770!B!!!!
S!VR_PVDDQ_DEF_PH1_VCIN!C7A16!1!@baseboard_fab2_lib.baseboard_fab2(sch_1):page219_i50@mstr_discrete.cap(chips)!CAP_0402-1.0UF,16V,10%,X6S,D97A!!!F3771!A!!!!
S!GND!C7A16!2!@baseboard_fab2_lib.baseboard_fab2(sch_1):page219_i50@mstr_discrete.cap(chips)!CAP_0402-1.0UF,16V,10%,X6S,D97A!!!F3771!B!!!!
S!VR_PVDDQ_DEF_PH2_VCIN!C7A24!1!@baseboard_fab2_lib.baseboard_fab2(sch_1):page219_i77@mstr_discrete.cap(chips)!CAP_0402-1.0UF,16V,10%,X6S,D97A!!!F3769!A!!!!
S!GND!C7A24!2!@baseboard_fab2_lib.baseboard_fab2(sch_1):page219_i77@mstr_discrete.cap(chips)!CAP_0402-1.0UF,16V,10%,X6S,D97A!!!F3769!B!!!!
S!VR_FET_SW_P12V_STBY_PVDDQ_KLM!C1A19!1!@baseboard_fab2_lib.baseboard_fab2(sch_1):page227_i48@mstr_discrete.cap(chips)!CAP_0402-1.0UF,16V,10%,X6S,D97A!!!F3825!A!!!!
S!GND!C1A19!2!@baseboard_fab2_lib.baseboard_fab2(sch_1):page227_i48@mstr_discrete.cap(chips)!CAP_0402-1.0UF,16V,10%,X6S,D97A!!!F3825!B!!!!
S!VR_FET_SW_P12V_STBY_PVDDQ_KLM!C1A9!1!@baseboard_fab2_lib.baseboard_fab2(sch_1):page227_i79@mstr_discrete.cap(chips)!CAP_0402-1.0UF,16V,10%,X6S,D97A!!!F3827!A!!!!
S!GND!C1A9!2!@baseboard_fab2_lib.baseboard_fab2(sch_1):page227_i79@mstr_discrete.cap(chips)!CAP_0402-1.0UF,16V,10%,X6S,D97A!!!F3827!B!!!!
S!VR_PVDDQ_KLM_PH1_VCIN!C1B20!1!@baseboard_fab2_lib.baseboard_fab2(sch_1):page227_i50@mstr_discrete.cap(chips)!CAP_0402-1.0UF,16V,10%,X6S,D97A!!!F3826!A!!!!
S!GND!C1B20!2!@baseboard_fab2_lib.baseboard_fab2(sch_1):page227_i50@mstr_discrete.cap(chips)!CAP_0402-1.0UF,16V,10%,X6S,D97A!!!F3826!B!!!!
S!VR_FET_SW_P12V_STBY_PVDDQ_GHJ!C1F27!1!@baseboard_fab2_lib.baseboard_fab2(sch_1):page224_i48@mstr_discrete.cap(chips)!CAP_0402-1.0UF,16V,10%,X6S,D97A!!!F3809!A!!!!
S!GND!C1F27!2!@baseboard_fab2_lib.baseboard_fab2(sch_1):page224_i48@mstr_discrete.cap(chips)!CAP_0402-1.0UF,16V,10%,X6S,D97A!!!F3809!B!!!!
S!VR_FET_SW_P12V_STBY_PVDDQ_GHJ!C1G13!1!@baseboard_fab2_lib.baseboard_fab2(sch_1):page224_i79@mstr_discrete.cap(chips)!CAP_0402-1.0UF,16V,10%,X6S,D97A!!!F3807!A!!!!
S!GND!C1G13!2!@baseboard_fab2_lib.baseboard_fab2(sch_1):page224_i79@mstr_discrete.cap(chips)!CAP_0402-1.0UF,16V,10%,X6S,D97A!!!F3807!B!!!!
S!VR_PVDDQ_GHJ_PH1_VCIN!C1G6!1!@baseboard_fab2_lib.baseboard_fab2(sch_1):page224_i50@mstr_discrete.cap(chips)!CAP_0402-1.0UF,16V,10%,X6S,D97A!!!F3808!A!!!!
S!GND!C1G6!2!@baseboard_fab2_lib.baseboard_fab2(sch_1):page224_i50@mstr_discrete.cap(chips)!CAP_0402-1.0UF,16V,10%,X6S,D97A!!!F3808!B!!!!
S!VR_PVDDQ_GHJ_PH2_VCIN!C1G28!1!@baseboard_fab2_lib.baseboard_fab2(sch_1):page224_i77@mstr_discrete.cap(chips)!CAP_0402-1.0UF,16V,10%,X6S,D97A!!!F3810!A!!!!
S!GND!C1G28!2!@baseboard_fab2_lib.baseboard_fab2(sch_1):page224_i77@mstr_discrete.cap(chips)!CAP_0402-1.0UF,16V,10%,X6S,D97A!!!F3810!B!!!!
S!VR_PVCCIN_CPU1_PH1_VCIN!C1E8!1!@baseboard_fab2_lib.baseboard_fab2(sch_1):page207_i32@mstr_discrete.cap(chips)!CAP_0402-1.0UF,16V,10%,X6S,D97A!!!F3812!A!!!!
S!GND!C1E8!2!@baseboard_fab2_lib.baseboard_fab2(sch_1):page207_i32@mstr_discrete.cap(chips)!CAP_0402-1.0UF,16V,10%,X6S,D97A!!!F3812!B!!!!
S!VR_PVCCIN_CPU1_PH2_VCIN!C1E24!1!@baseboard_fab2_lib.baseboard_fab2(sch_1):page207_i40@mstr_discrete.cap(chips)!CAP_0402-1.0UF,16V,10%,X6S,D97A!!!F3814!A!!!!
S!GND!C1E24!2!@baseboard_fab2_lib.baseboard_fab2(sch_1):page207_i40@mstr_discrete.cap(chips)!CAP_0402-1.0UF,16V,10%,X6S,D97A!!!F3814!B!!!!
S!VR_FET_SW_P12V_STBY_PVCCIN_CPU1!C1D35!1!@baseboard_fab2_lib.baseboard_fab2(sch_1):page207_i42@mstr_discrete.cap(chips)!CAP_0402-1.0UF,16V,10%,X6S,D97A!!!F3813!A!!!!
S!GND!C1D35!2!@baseboard_fab2_lib.baseboard_fab2(sch_1):page207_i42@mstr_discrete.cap(chips)!CAP_0402-1.0UF,16V,10%,X6S,D97A!!!F3813!B!!!!
S!VR_FET_SW_P12V_STBY_PVCCIN_CPU1!C1E13!1!@baseboard_fab2_lib.baseboard_fab2(sch_1):page207_i34@mstr_discrete.cap(chips)!CAP_0402-1.0UF,16V,10%,X6S,D97A!!!F3811!A!!!!
S!GND!C1E13!2!@baseboard_fab2_lib.baseboard_fab2(sch_1):page207_i34@mstr_discrete.cap(chips)!CAP_0402-1.0UF,16V,10%,X6S,D97A!!!F3811!B!!!!
S!VR_FET_SW_P12V_STBY_PVCCIN_CPU1!C1D23!1!@baseboard_fab2_lib.baseboard_fab2(sch_1):page208_i45@mstr_discrete.cap(chips)!CAP_0402-1.0UF,16V,10%,X6S,D97A!!!F3816!A!!!!
S!GND!C1D23!2!@baseboard_fab2_lib.baseboard_fab2(sch_1):page208_i45@mstr_discrete.cap(chips)!CAP_0402-1.0UF,16V,10%,X6S,D97A!!!F3816!B!!!!
S!VR_FET_SW_P12V_STBY_PVCCIN_CPU1!C1D12!1!@baseboard_fab2_lib.baseboard_fab2(sch_1):page208_i52@mstr_discrete.cap(chips)!CAP_0402-1.0UF,16V,10%,X6S,D97A!!!F3819!A!!!!
S!GND!C1D12!2!@baseboard_fab2_lib.baseboard_fab2(sch_1):page208_i52@mstr_discrete.cap(chips)!CAP_0402-1.0UF,16V,10%,X6S,D97A!!!F3819!B!!!!
S!VR_PVCCIN_CPU1_PH3_VCIN!C1D17!1!@baseboard_fab2_lib.baseboard_fab2(sch_1):page208_i43@mstr_discrete.cap(chips)!CAP_0402-1.0UF,16V,10%,X6S,D97A!!!F3818!A!!!!
S!GND!C1D17!2!@baseboard_fab2_lib.baseboard_fab2(sch_1):page208_i43@mstr_discrete.cap(chips)!CAP_0402-1.0UF,16V,10%,X6S,D97A!!!F3818!B!!!!
S!VR_PVCCIN_CPU1_PH4_VCIN!C1D7!1!@baseboard_fab2_lib.baseboard_fab2(sch_1):page208_i50@mstr_discrete.cap(chips)!CAP_0402-1.0UF,16V,10%,X6S,D97A!!!F3820!A!!!!
S!GND!C1D7!2!@baseboard_fab2_lib.baseboard_fab2(sch_1):page208_i50@mstr_discrete.cap(chips)!CAP_0402-1.0UF,16V,10%,X6S,D97A!!!F3820!B!!!!
S!VR_FET_SW_P12V_STBY_PVCCIN_CPU1!C1C15!1!@baseboard_fab2_lib.baseboard_fab2(sch_1):page210_i28@mstr_discrete.cap(chips)!CAP_0402-1.0UF,16V,10%,X6S,D97A!!!F3823!A!!!!
S!GND!C1C15!2!@baseboard_fab2_lib.baseboard_fab2(sch_1):page210_i28@mstr_discrete.cap(chips)!CAP_0402-1.0UF,16V,10%,X6S,D97A!!!F3823!B!!!!
S!VR_PVSA_CPU1_VCIN!C1C5!1!@baseboard_fab2_lib.baseboard_fab2(sch_1):page210_i26@mstr_discrete.cap(chips)!CAP_0402-1.0UF,16V,10%,X6S,D97A!!!F3824!A!!!!
S!GND!C1C5!2!@baseboard_fab2_lib.baseboard_fab2(sch_1):page210_i26@mstr_discrete.cap(chips)!CAP_0402-1.0UF,16V,10%,X6S,D97A!!!F3824!B!!!!
S!VR_FET_SW_P12V_STBY_PVCCIN_CPU0!C4C18!1!@baseboard_fab2_lib.baseboard_fab2(sch_1):page204_i36@mstr_discrete.cap(chips)!CAP_0402-1.0UF,16V,10%,X6S,D97A!!!F3793!A!!!!
S!GND!C4C18!2!@baseboard_fab2_lib.baseboard_fab2(sch_1):page204_i36@mstr_discrete.cap(chips)!CAP_0402-1.0UF,16V,10%,X6S,D97A!!!F3793!B!!!!
S!VR_P5V_STBY_VIN!C7E14!1!@baseboard_fab2_lib.baseboard_fab2(sch_1):page241_i30@mstr_discrete.cap(chips)!CAP_0402-1.0UF,16V,10%,X6S,D97A!!!F3765!A!!!!
S!GND!C7E14!2!@baseboard_fab2_lib.baseboard_fab2(sch_1):page241_i30@mstr_discrete.cap(chips)!CAP_0402-1.0UF,16V,10%,X6S,D97A!!!F3765!B!!!!
S!VR_PVDDQ_KLM_PH2_VCIN!C1A6!1!@baseboard_fab2_lib.baseboard_fab2(sch_1):page227_i77@mstr_discrete.cap(chips)!CAP_0402-1.0UF,16V,10%,X6S,D97A!!!F3828!A!!!!
S!GND!C1A6!2!@baseboard_fab2_lib.baseboard_fab2(sch_1):page227_i77@mstr_discrete.cap(chips)!CAP_0402-1.0UF,16V,10%,X6S,D97A!!!F3828!B!!!!
S!VR_FET_SW_P12V_STBY_PVCCIN_CPU1!C1C26!1!@baseboard_fab2_lib.baseboard_fab2(sch_1):page209_i16@mstr_discrete.cap(chips)!CAP_0402-1.0UF,16V,10%,X6S,D97A!!!F3821!A!!!!
S!GND!C1C26!2!@baseboard_fab2_lib.baseboard_fab2(sch_1):page209_i16@mstr_discrete.cap(chips)!CAP_0402-1.0UF,16V,10%,X6S,D97A!!!F3821!B!!!!
S!VR_PVCCIN_CPU1_PH5_VCIN!C1D32!1!@baseboard_fab2_lib.baseboard_fab2(sch_1):page209_i18@mstr_discrete.cap(chips)!CAP_0402-1.0UF,16V,10%,X6S,D97A!!!F3822!A!!!!
S!GND!C1D32!2!@baseboard_fab2_lib.baseboard_fab2(sch_1):page209_i18@mstr_discrete.cap(chips)!CAP_0402-1.0UF,16V,10%,X6S,D97A!!!F3822!B!!!!
S!VR_FET_SW_P12V_STBY_PVDDQ_DEF!C7A11!1!@baseboard_fab2_lib.baseboard_fab2(sch_1):page219_i48@mstr_discrete.cap(chips)!CAP_0402-1.0UF,16V,10%,X6S,D97A!!!F3772!A!!!!
S!GND!C7A11!2!@baseboard_fab2_lib.baseboard_fab2(sch_1):page219_i48@mstr_discrete.cap(chips)!CAP_0402-1.0UF,16V,10%,X6S,D97A!!!F3772!B!!!!
S!VR_FET_SW_P12V_STBY_PVCCIN_CPU0!C4E15!1!@baseboard_fab2_lib.baseboard_fab2(sch_1):page214_i79@mstr_discrete.cap(chips)!CAP_0402-1.0UF,16V,10%,X6S,D97A!!!F3785!A!!!!
S!GND!C4E15!2!@baseboard_fab2_lib.baseboard_fab2(sch_1):page214_i79@mstr_discrete.cap(chips)!CAP_0402-1.0UF,16V,10%,X6S,D97A!!!F3785!B!!!!
S!VR_PVCCIO_CPU1_PH1_VCIN!C4E22!1!@baseboard_fab2_lib.baseboard_fab2(sch_1):page214_i76@mstr_discrete.cap(chips)!CAP_0402-1.0UF,16V,10%,X6S,D97A!!!F3783!A!!!!
S!GND!C4E22!2!@baseboard_fab2_lib.baseboard_fab2(sch_1):page214_i76@mstr_discrete.cap(chips)!CAP_0402-1.0UF,16V,10%,X6S,D97A!!!F3783!B!!!!
S!VR_FET_SW_P12V_STBY_PVDDQ_DEF!C7A9!1!@baseboard_fab2_lib.baseboard_fab2(sch_1):page236_i33@mstr_discrete.cap(chips)!CAP_0402-1.0UF,16V,10%,X6S,D97A!!!F3774!A!!!!
S!GND!C7A9!2!@baseboard_fab2_lib.baseboard_fab2(sch_1):page236_i33@mstr_discrete.cap(chips)!CAP_0402-1.0UF,16V,10%,X6S,D97A!!!F3774!B!!!!
S!VR_FET_SW_P12V_STBY_PVDDQ_DEF!C7A7!1!@baseboard_fab2_lib.baseboard_fab2(sch_1):page236_i22@mstr_discrete.cap(chips)!CAP_0402-1.0UF,16V,10%,X6S,D97A!!!F3775!A!!!!
S!GND!C7A7!2!@baseboard_fab2_lib.baseboard_fab2(sch_1):page236_i22@mstr_discrete.cap(chips)!CAP_0402-1.0UF,16V,10%,X6S,D97A!!!F3775!B!!!!
S!VR_PVNN_PCH_PH1_VCIN!C7A6!1!@baseboard_fab2_lib.baseboard_fab2(sch_1):page236_i19@mstr_discrete.cap(chips)!CAP_0402-1.0UF,16V,10%,X6S,D97A!!!F3776!A!!!!
S!GND!C7A6!2!@baseboard_fab2_lib.baseboard_fab2(sch_1):page236_i19@mstr_discrete.cap(chips)!CAP_0402-1.0UF,16V,10%,X6S,D97A!!!F3776!B!!!!
S!VR_P1V05_PCH_STBY_PH1_VCIN!C7A10!1!@baseboard_fab2_lib.baseboard_fab2(sch_1):page236_i36@mstr_discrete.cap(chips)!CAP_0402-1.0UF,16V,10%,X6S,D97A!!!F3773!A!!!!
S!GND!C7A10!2!@baseboard_fab2_lib.baseboard_fab2(sch_1):page236_i36@mstr_discrete.cap(chips)!CAP_0402-1.0UF,16V,10%,X6S,D97A!!!F3773!B!!!!
S!P12V_HSC_VCC!C1D25!1!@baseboard_fab2_lib.baseboard_fab2(sch_1):page199_i3@mstr_discrete.cap(chips)!CAP_0402-1.0UF,16V,10%,X6S,D97A!!!F3815!A!!!!
S!AGND_HSC!C1D25!2!@baseboard_fab2_lib.baseboard_fab2(sch_1):page199_i3@mstr_discrete.cap(chips)!CAP_0402-1.0UF,16V,10%,X6S,D97A!!!F3815!B!!!!
S!P3V3_STBY!C1L19!1!@baseboard_fab2_lib.baseboard_fab2(sch_1):page112_i140@mstr_discrete.cap(chips)!CAP_0402-1.0UF,16V,10%,X6S,D97A!!!F3805!A!!!!
S!GND!C1L19!2!@baseboard_fab2_lib.baseboard_fab2(sch_1):page112_i140@mstr_discrete.cap(chips)!CAP_0402-1.0UF,16V,10%,X6S,D97A!!!F3805!B!!!!
S!P3V3_STBY!C1L1!1!@baseboard_fab2_lib.baseboard_fab2(sch_1):page112_i136@mstr_discrete.cap(chips)!CAP_0402-1.0UF,16V,10%,X6S,D97A!!!F3806!A!!!!
S!GND!C1L1!2!@baseboard_fab2_lib.baseboard_fab2(sch_1):page112_i136@mstr_discrete.cap(chips)!CAP_0402-1.0UF,16V,10%,X6S,D97A!!!F3806!B!!!!
S!P3V3!C7D4!1!@baseboard_fab2_lib.baseboard_fab2(sch_1):page92_i79@mstr_discrete.cap(chips)!CAP_0402-1.0UF,16V,10%,X6S,D97A!!!F3766!A!!!!
S!GND!C7D4!2!@baseboard_fab2_lib.baseboard_fab2(sch_1):page92_i79@mstr_discrete.cap(chips)!CAP_0402-1.0UF,16V,10%,X6S,D97A!!!F3766!B!!!!
S!P3V3!C3P50!1!@baseboard_fab2_lib.baseboard_fab2(sch_1):page92_i84@mstr_discrete.cap(chips)!CAP_0402-1.0UF,16V,10%,X6S,D97A!!!F3802!A!!!!
S!GND!C3P50!2!@baseboard_fab2_lib.baseboard_fab2(sch_1):page92_i84@mstr_discrete.cap(chips)!CAP_0402-1.0UF,16V,10%,X6S,D97A!!!F3802!B!!!!
S!P3V3!C1U19!1!@baseboard_fab2_lib.baseboard_fab2(sch_1):page152_i18@mstr_discrete.cap(chips)!CAP_0402-1.0UF,16V,10%,X6S,D97A!!!F3804!A!!!!
S!GND!C1U19!2!@baseboard_fab2_lib.baseboard_fab2(sch_1):page152_i18@mstr_discrete.cap(chips)!CAP_0402-1.0UF,16V,10%,X6S,D97A!!!F3804!B!!!!
S!VR_PVTT_ABC_BIAS!C4G15!1!@baseboard_fab2_lib.baseboard_fab2(sch_1):page221_i24@mstr_discrete.cap(chips)!CAP_0402-1.0UF,16V,10%,X6S,D97A!!!F3781!A!!!!
S!GND!C4G15!2!@baseboard_fab2_lib.baseboard_fab2(sch_1):page221_i24@mstr_discrete.cap(chips)!CAP_0402-1.0UF,16V,10%,X6S,D97A!!!F3781!B!!!!
S!VR_PVTT_ABC_VREF!C4G16!1!@baseboard_fab2_lib.baseboard_fab2(sch_1):page221_i34@mstr_discrete.cap(chips)!CAP_0402-1.0UF,16V,10%,X6S,D97A!!!F3780!A!!!!
S!GND!C4G16!2!@baseboard_fab2_lib.baseboard_fab2(sch_1):page221_i34@mstr_discrete.cap(chips)!CAP_0402-1.0UF,16V,10%,X6S,D97A!!!F3780!B!!!!
S!VR_PVTT_DEF_VREF!C4A9!1!@baseboard_fab2_lib.baseboard_fab2(sch_1):page222_i21@mstr_discrete.cap(chips)!CAP_0402-1.0UF,16V,10%,X6S,D97A!!!F3799!A!!!!
S!GND!C4A9!2!@baseboard_fab2_lib.baseboard_fab2(sch_1):page222_i21@mstr_discrete.cap(chips)!CAP_0402-1.0UF,16V,10%,X6S,D97A!!!F3799!B!!!!
S!VR_PVTT_GHJ_VREF!C4G21!1!@baseboard_fab2_lib.baseboard_fab2(sch_1):page229_i21@mstr_discrete.cap(chips)!CAP_0402-1.0UF,16V,10%,X6S,D97A!!!F3778!A!!!!
S!GND!C4G21!2!@baseboard_fab2_lib.baseboard_fab2(sch_1):page229_i21@mstr_discrete.cap(chips)!CAP_0402-1.0UF,16V,10%,X6S,D97A!!!F3778!B!!!!
S!VR_PVTT_KLM_VREF!C4A14!1!@baseboard_fab2_lib.baseboard_fab2(sch_1):page230_i21@mstr_discrete.cap(chips)!CAP_0402-1.0UF,16V,10%,X6S,D97A!!!F3797!A!!!!
S!GND!C4A14!2!@baseboard_fab2_lib.baseboard_fab2(sch_1):page230_i21@mstr_discrete.cap(chips)!CAP_0402-1.0UF,16V,10%,X6S,D97A!!!F3797!B!!!!
S!VR_PVTT_DEF_BIAS!C4A10!1!@baseboard_fab2_lib.baseboard_fab2(sch_1):page222_i28@mstr_discrete.cap(chips)!CAP_0402-1.0UF,16V,10%,X6S,D97A!!!F3798!A!!!!
S!GND!C4A10!2!@baseboard_fab2_lib.baseboard_fab2(sch_1):page222_i28@mstr_discrete.cap(chips)!CAP_0402-1.0UF,16V,10%,X6S,D97A!!!F3798!B!!!!
S!VR_PVTT_GHJ_BIAS!C4G18!1!@baseboard_fab2_lib.baseboard_fab2(sch_1):page229_i27@mstr_discrete.cap(chips)!CAP_0402-1.0UF,16V,10%,X6S,D97A!!!F3779!A!!!!
S!GND!C4G18!2!@baseboard_fab2_lib.baseboard_fab2(sch_1):page229_i27@mstr_discrete.cap(chips)!CAP_0402-1.0UF,16V,10%,X6S,D97A!!!F3779!B!!!!
S!VR_PVTT_KLM_BIAS!C4A8!1!@baseboard_fab2_lib.baseboard_fab2(sch_1):page230_i28@mstr_discrete.cap(chips)!CAP_0402-1.0UF,16V,10%,X6S,D97A!!!F3800!A!!!!
S!GND!C4A8!2!@baseboard_fab2_lib.baseboard_fab2(sch_1):page230_i28@mstr_discrete.cap(chips)!CAP_0402-1.0UF,16V,10%,X6S,D97A!!!F3800!B!!!!
S!GND!EU4G3!3!@baseboard_fab2_lib.baseboard_fab2(sch_1):page221_i1@mstr_vreg.mic5166(chips)!MIC5166_DFN-IC,H55101-001!!!F2021!AGND!!!!
S!VR_PVTT_ABC_BIAS!EU4G3!2!@baseboard_fab2_lib.baseboard_fab2(sch_1):page221_i1@mstr_vreg.mic5166(chips)!MIC5166_DFN-IC,H55101-001!!!F2021!BIAS!!!!
S!FM_PVTT_ABC_EN_R!EU4G3!7!@baseboard_fab2_lib.baseboard_fab2(sch_1):page221_i1@mstr_vreg.mic5166(chips)!MIC5166_DFN-IC,H55101-001!!!F2021!EN!!!!
S!PWRGD_PVTT_ABC_CPU0_R!EU4G3!5!@baseboard_fab2_lib.baseboard_fab2(sch_1):page221_i1@mstr_vreg.mic5166(chips)!MIC5166_DFN-IC,H55101-001!!!F2021!PG!!!!
S!GND!EU4G3!8!@baseboard_fab2_lib.baseboard_fab2(sch_1):page221_i1@mstr_vreg.mic5166(chips)!MIC5166_DFN-IC,H55101-001!!!F2021!PGND!!!!
S!VR_PVTT_ABC_SNS!EU4G3!6!@baseboard_fab2_lib.baseboard_fab2(sch_1):page221_i1@mstr_vreg.mic5166(chips)!MIC5166_DFN-IC,H55101-001!!!F2021!SNS!!!!
S!GND!EU4G3!11!@baseboard_fab2_lib.baseboard_fab2(sch_1):page221_i1@mstr_vreg.mic5166(chips)!MIC5166_DFN-IC,H55101-001!!!F2021!THPAD!!!!
S!VSENSE_PVDDQ_ABC_VTT!EU4G3!4!@baseboard_fab2_lib.baseboard_fab2(sch_1):page221_i1@mstr_vreg.mic5166(chips)!MIC5166_DFN-IC,H55101-001!!!F2021!VDDQ!!!!
S!PVDDQ_ABC!EU4G3!10!@baseboard_fab2_lib.baseboard_fab2(sch_1):page221_i1@mstr_vreg.mic5166(chips)!MIC5166_DFN-IC,H55101-001!!!F2021!VIN!!!!
S!VR_PVTT_ABC_VREF!EU4G3!1!@baseboard_fab2_lib.baseboard_fab2(sch_1):page221_i1@mstr_vreg.mic5166(chips)!MIC5166_DFN-IC,H55101-001!!!F2021!VREF!!!!
S!PVTT_ABC!EU4G3!9!@baseboard_fab2_lib.baseboard_fab2(sch_1):page221_i1@mstr_vreg.mic5166(chips)!MIC5166_DFN-IC,H55101-001!!!F2021!VTT!!!!
S!GND!EU4A1!3!@baseboard_fab2_lib.baseboard_fab2(sch_1):page222_i31@mstr_vreg.mic5166(chips)!MIC5166_DFN-IC,H55101-001!!!F2024!AGND!!!!
S!VR_PVTT_DEF_BIAS!EU4A1!2!@baseboard_fab2_lib.baseboard_fab2(sch_1):page222_i31@mstr_vreg.mic5166(chips)!MIC5166_DFN-IC,H55101-001!!!F2024!BIAS!!!!
S!FM_PVTT_DEF_EN_R!EU4A1!7!@baseboard_fab2_lib.baseboard_fab2(sch_1):page222_i31@mstr_vreg.mic5166(chips)!MIC5166_DFN-IC,H55101-001!!!F2024!EN!!!!
S!PWRGD_PVTT_DEF_CPU0_R!EU4A1!5!@baseboard_fab2_lib.baseboard_fab2(sch_1):page222_i31@mstr_vreg.mic5166(chips)!MIC5166_DFN-IC,H55101-001!!!F2024!PG!!!!
S!GND!EU4A1!8!@baseboard_fab2_lib.baseboard_fab2(sch_1):page222_i31@mstr_vreg.mic5166(chips)!MIC5166_DFN-IC,H55101-001!!!F2024!PGND!!!!
S!VR_PVTT_DEF_SNS!EU4A1!6!@baseboard_fab2_lib.baseboard_fab2(sch_1):page222_i31@mstr_vreg.mic5166(chips)!MIC5166_DFN-IC,H55101-001!!!F2024!SNS!!!!
S!GND!EU4A1!11!@baseboard_fab2_lib.baseboard_fab2(sch_1):page222_i31@mstr_vreg.mic5166(chips)!MIC5166_DFN-IC,H55101-001!!!F2024!THPAD!!!!
S!VSENSE_PVDDQ_DEF_VTT!EU4A1!4!@baseboard_fab2_lib.baseboard_fab2(sch_1):page222_i31@mstr_vreg.mic5166(chips)!MIC5166_DFN-IC,H55101-001!!!F2024!VDDQ!!!!
S!PVDDQ_DEF!EU4A1!10!@baseboard_fab2_lib.baseboard_fab2(sch_1):page222_i31@mstr_vreg.mic5166(chips)!MIC5166_DFN-IC,H55101-001!!!F2024!VIN!!!!
S!VR_PVTT_DEF_VREF!EU4A1!1!@baseboard_fab2_lib.baseboard_fab2(sch_1):page222_i31@mstr_vreg.mic5166(chips)!MIC5166_DFN-IC,H55101-001!!!F2024!VREF!!!!
S!PVTT_DEF!EU4A1!9!@baseboard_fab2_lib.baseboard_fab2(sch_1):page222_i31@mstr_vreg.mic5166(chips)!MIC5166_DFN-IC,H55101-001!!!F2024!VTT!!!!
S!GND!EU4G2!3!@baseboard_fab2_lib.baseboard_fab2(sch_1):page229_i24@mstr_vreg.mic5166(chips)!MIC5166_DFN-IC,H55101-001!!!F2022!AGND!!!!
S!VR_PVTT_GHJ_BIAS!EU4G2!2!@baseboard_fab2_lib.baseboard_fab2(sch_1):page229_i24@mstr_vreg.mic5166(chips)!MIC5166_DFN-IC,H55101-001!!!F2022!BIAS!!!!
S!FM_PVTT_GHJ_EN_R!EU4G2!7!@baseboard_fab2_lib.baseboard_fab2(sch_1):page229_i24@mstr_vreg.mic5166(chips)!MIC5166_DFN-IC,H55101-001!!!F2022!EN!!!!
S!PWRGD_PVTT_GHJ_CPU1_R!EU4G2!5!@baseboard_fab2_lib.baseboard_fab2(sch_1):page229_i24@mstr_vreg.mic5166(chips)!MIC5166_DFN-IC,H55101-001!!!F2022!PG!!!!
S!GND!EU4G2!8!@baseboard_fab2_lib.baseboard_fab2(sch_1):page229_i24@mstr_vreg.mic5166(chips)!MIC5166_DFN-IC,H55101-001!!!F2022!PGND!!!!
S!VR_PVTT_GHJ_SNS!EU4G2!6!@baseboard_fab2_lib.baseboard_fab2(sch_1):page229_i24@mstr_vreg.mic5166(chips)!MIC5166_DFN-IC,H55101-001!!!F2022!SNS!!!!
S!GND!EU4G2!11!@baseboard_fab2_lib.baseboard_fab2(sch_1):page229_i24@mstr_vreg.mic5166(chips)!MIC5166_DFN-IC,H55101-001!!!F2022!THPAD!!!!
S!VSENSE_PVDDQ_GHJ_VTT!EU4G2!4!@baseboard_fab2_lib.baseboard_fab2(sch_1):page229_i24@mstr_vreg.mic5166(chips)!MIC5166_DFN-IC,H55101-001!!!F2022!VDDQ!!!!
S!PVDDQ_GHJ!EU4G2!10!@baseboard_fab2_lib.baseboard_fab2(sch_1):page229_i24@mstr_vreg.mic5166(chips)!MIC5166_DFN-IC,H55101-001!!!F2022!VIN!!!!
S!VR_PVTT_GHJ_VREF!EU4G2!1!@baseboard_fab2_lib.baseboard_fab2(sch_1):page229_i24@mstr_vreg.mic5166(chips)!MIC5166_DFN-IC,H55101-001!!!F2022!VREF!!!!
S!PVTT_GHJ!EU4G2!9!@baseboard_fab2_lib.baseboard_fab2(sch_1):page229_i24@mstr_vreg.mic5166(chips)!MIC5166_DFN-IC,H55101-001!!!F2022!VTT!!!!
S!GND!EU4A2!3!@baseboard_fab2_lib.baseboard_fab2(sch_1):page230_i31@mstr_vreg.mic5166(chips)!MIC5166_DFN-IC,H55101-001!!!F2023!AGND!!!!
S!VR_PVTT_KLM_BIAS!EU4A2!2!@baseboard_fab2_lib.baseboard_fab2(sch_1):page230_i31@mstr_vreg.mic5166(chips)!MIC5166_DFN-IC,H55101-001!!!F2023!BIAS!!!!
S!FM_PVTT_KLM_EN_R!EU4A2!7!@baseboard_fab2_lib.baseboard_fab2(sch_1):page230_i31@mstr_vreg.mic5166(chips)!MIC5166_DFN-IC,H55101-001!!!F2023!EN!!!!
S!PWRGD_PVTT_KLM_CPU1_R!EU4A2!5!@baseboard_fab2_lib.baseboard_fab2(sch_1):page230_i31@mstr_vreg.mic5166(chips)!MIC5166_DFN-IC,H55101-001!!!F2023!PG!!!!
S!GND!EU4A2!8!@baseboard_fab2_lib.baseboard_fab2(sch_1):page230_i31@mstr_vreg.mic5166(chips)!MIC5166_DFN-IC,H55101-001!!!F2023!PGND!!!!
S!VR_PVTT_KLM_SNS!EU4A2!6!@baseboard_fab2_lib.baseboard_fab2(sch_1):page230_i31@mstr_vreg.mic5166(chips)!MIC5166_DFN-IC,H55101-001!!!F2023!SNS!!!!
S!GND!EU4A2!11!@baseboard_fab2_lib.baseboard_fab2(sch_1):page230_i31@mstr_vreg.mic5166(chips)!MIC5166_DFN-IC,H55101-001!!!F2023!THPAD!!!!
S!VSENSE_PVDDQ_KLM_VTT!EU4A2!4!@baseboard_fab2_lib.baseboard_fab2(sch_1):page230_i31@mstr_vreg.mic5166(chips)!MIC5166_DFN-IC,H55101-001!!!F2023!VDDQ!!!!
S!PVDDQ_KLM!EU4A2!10!@baseboard_fab2_lib.baseboard_fab2(sch_1):page230_i31@mstr_vreg.mic5166(chips)!MIC5166_DFN-IC,H55101-001!!!F2023!VIN!!!!
S!VR_PVTT_KLM_VREF!EU4A2!1!@baseboard_fab2_lib.baseboard_fab2(sch_1):page230_i31@mstr_vreg.mic5166(chips)!MIC5166_DFN-IC,H55101-001!!!F2023!VREF!!!!
S!PVTT_KLM!EU4A2!9!@baseboard_fab2_lib.baseboard_fab2(sch_1):page230_i31@mstr_vreg.mic5166(chips)!MIC5166_DFN-IC,H55101-001!!!F2023!VTT!!!!
S!GND!U4F1!2!@baseboard_fab2_lib.baseboard_fab2(sch_1):page197_i97@mstr_vreg.max9634(chips)!MAX9634_SOT-IC,H35789-001!!!F2025!GND(0)!!!!
S!GND!U4F1!1!@baseboard_fab2_lib.baseboard_fab2(sch_1):page197_i97@mstr_vreg.max9634(chips)!MAX9634_SOT-IC,H35789-001!!!F2025!GND(1)!!!!
S!VR_PVDDQ_ABC_AIINSEN_R!U4F1!3!@baseboard_fab2_lib.baseboard_fab2(sch_1):page197_i97@mstr_vreg.max9634(chips)!MAX9634_SOT-IC,H35789-001!!!F2025!\out\!!!!
S!P12V_NVDIMM_ABC!U4F1!4!@baseboard_fab2_lib.baseboard_fab2(sch_1):page197_i97@mstr_vreg.max9634(chips)!MAX9634_SOT-IC,H35789-001!!!F2025!RSN!!!!
S!P12V_STBY!U4F1!5!@baseboard_fab2_lib.baseboard_fab2(sch_1):page197_i97@mstr_vreg.max9634(chips)!MAX9634_SOT-IC,H35789-001!!!F2025!RSP!!!!
S!GND!U4B1!2!@baseboard_fab2_lib.baseboard_fab2(sch_1):page197_i120@mstr_vreg.max9634(chips)!MAX9634_SOT-IC,H35789-001!!!F2026!GND(0)!!!!
S!GND!U4B1!1!@baseboard_fab2_lib.baseboard_fab2(sch_1):page197_i120@mstr_vreg.max9634(chips)!MAX9634_SOT-IC,H35789-001!!!F2026!GND(1)!!!!
S!VR_PVDDQ_DEF_AIINSEN_R!U4B1!3!@baseboard_fab2_lib.baseboard_fab2(sch_1):page197_i120@mstr_vreg.max9634(chips)!MAX9634_SOT-IC,H35789-001!!!F2026!\out\!!!!
S!P12V_NVDIMM_DEF!U4B1!4!@baseboard_fab2_lib.baseboard_fab2(sch_1):page197_i120@mstr_vreg.max9634(chips)!MAX9634_SOT-IC,H35789-001!!!F2026!RSN!!!!
S!P12V_STBY!U4B1!5!@baseboard_fab2_lib.baseboard_fab2(sch_1):page197_i120@mstr_vreg.max9634(chips)!MAX9634_SOT-IC,H35789-001!!!F2026!RSP!!!!
S!GND!U1F1!2!@baseboard_fab2_lib.baseboard_fab2(sch_1):page197_i133@mstr_vreg.max9634(chips)!MAX9634_SOT-IC,H35789-001!!!F2027!GND(0)!!!!
S!GND!U1F1!1!@baseboard_fab2_lib.baseboard_fab2(sch_1):page197_i133@mstr_vreg.max9634(chips)!MAX9634_SOT-IC,H35789-001!!!F2027!GND(1)!!!!
S!VR_PVDDQ_GHJ_AIINSEN_R!U1F1!3!@baseboard_fab2_lib.baseboard_fab2(sch_1):page197_i133@mstr_vreg.max9634(chips)!MAX9634_SOT-IC,H35789-001!!!F2027!\out\!!!!
S!P12V_NVDIMM_GHJ!U1F1!4!@baseboard_fab2_lib.baseboard_fab2(sch_1):page197_i133@mstr_vreg.max9634(chips)!MAX9634_SOT-IC,H35789-001!!!F2027!RSN!!!!
S!P12V_STBY!U1F1!5!@baseboard_fab2_lib.baseboard_fab2(sch_1):page197_i133@mstr_vreg.max9634(chips)!MAX9634_SOT-IC,H35789-001!!!F2027!RSP!!!!
S!GND!U1B1!2!@baseboard_fab2_lib.baseboard_fab2(sch_1):page197_i144@mstr_vreg.max9634(chips)!MAX9634_SOT-IC,H35789-001!!!F2028!GND(0)!!!!
S!GND!U1B1!1!@baseboard_fab2_lib.baseboard_fab2(sch_1):page197_i144@mstr_vreg.max9634(chips)!MAX9634_SOT-IC,H35789-001!!!F2028!GND(1)!!!!
S!VR_PVDDQ_KLM_AIINSEN_R!U1B1!3!@baseboard_fab2_lib.baseboard_fab2(sch_1):page197_i144@mstr_vreg.max9634(chips)!MAX9634_SOT-IC,H35789-001!!!F2028!\out\!!!!
S!P12V_NVDIMM_KLM!U1B1!4!@baseboard_fab2_lib.baseboard_fab2(sch_1):page197_i144@mstr_vreg.max9634(chips)!MAX9634_SOT-IC,H35789-001!!!F2028!RSN!!!!
S!P12V_STBY!U1B1!5!@baseboard_fab2_lib.baseboard_fab2(sch_1):page197_i144@mstr_vreg.max9634(chips)!MAX9634_SOT-IC,H35789-001!!!F2028!RSP!!!!
S!P12V_NVDIMM_ABC!R4F2!1!@baseboard_fab2_lib.baseboard_fab2(sch_1):page197_i99@mstr_discrete.res(chips)!RES_1206-0.002,1%,1W,CHIP,G521A!!!F252!A!!!!
S!P12V_STBY!R4F2!2!@baseboard_fab2_lib.baseboard_fab2(sch_1):page197_i99@mstr_discrete.res(chips)!RES_1206-0.002,1%,1W,CHIP,G521A!!!F252!B!!!!
S!P12V_NVDIMM_DEF!R4B12!1!@baseboard_fab2_lib.baseboard_fab2(sch_1):page197_i121@mstr_discrete.res(chips)!RES_1206-0.002,1%,1W,CHIP,G521A!!!F253!A!!!!
S!P12V_STBY!R4B12!2!@baseboard_fab2_lib.baseboard_fab2(sch_1):page197_i121@mstr_discrete.res(chips)!RES_1206-0.002,1%,1W,CHIP,G521A!!!F253!B!!!!
S!P12V_NVDIMM_GHJ!R1F3!1!@baseboard_fab2_lib.baseboard_fab2(sch_1):page197_i131@mstr_discrete.res(chips)!RES_1206-0.002,1%,1W,CHIP,G521A!!!F254!A!!!!
S!P12V_STBY!R1F3!2!@baseboard_fab2_lib.baseboard_fab2(sch_1):page197_i131@mstr_discrete.res(chips)!RES_1206-0.002,1%,1W,CHIP,G521A!!!F254!B!!!!
S!P12V_NVDIMM_KLM!R9M4!1!@baseboard_fab2_lib.baseboard_fab2(sch_1):page197_i142@mstr_discrete.res(chips)!RES_1206-0.002,1%,1W,CHIP,G521A!!!F251!A!!!!
S!P12V_STBY!R9M4!2!@baseboard_fab2_lib.baseboard_fab2(sch_1):page197_i142@mstr_discrete.res(chips)!RES_1206-0.002,1%,1W,CHIP,G521A!!!F251!B!!!!
S!P3E_CPU0_PE1_PCH_RXP<0>!C2U3!1!@baseboard_fab2_lib.baseboard_fab2(sch_1):page107_i272@mstr_discrete.cap(chips)!CAP_0402-0.22UF,16V,10%,X7R,A3A!!!F3971!A!!!!
S!P3E_CPU0_PE1_SS_RXP<0>!C2U3!2!@baseboard_fab2_lib.baseboard_fab2(sch_1):page107_i272@mstr_discrete.cap(chips)!CAP_0402-0.22UF,16V,10%,X7R,A3A!!!F3971!B!!!!
S!P3E_CPU0_PE1_PCH_RXN<0>!C2U4!1!@baseboard_fab2_lib.baseboard_fab2(sch_1):page107_i257@mstr_discrete.cap(chips)!CAP_0402-0.22UF,16V,10%,X7R,A3A!!!F3970!A!!!!
S!P3E_CPU0_PE1_SS_RXN<0>!C2U4!2!@baseboard_fab2_lib.baseboard_fab2(sch_1):page107_i257@mstr_discrete.cap(chips)!CAP_0402-0.22UF,16V,10%,X7R,A3A!!!F3970!B!!!!
S!P3E_CPU0_PE1_PCH_RXP<1>!C2U5!1!@baseboard_fab2_lib.baseboard_fab2(sch_1):page107_i274@mstr_discrete.cap(chips)!CAP_0402-0.22UF,16V,10%,X7R,A3A!!!F3969!A!!!!
S!P3E_CPU0_PE1_SS_RXP<1>!C2U5!2!@baseboard_fab2_lib.baseboard_fab2(sch_1):page107_i274@mstr_discrete.cap(chips)!CAP_0402-0.22UF,16V,10%,X7R,A3A!!!F3969!B!!!!
S!P3E_CPU0_PE1_PCH_RXN<1>!C2U6!1!@baseboard_fab2_lib.baseboard_fab2(sch_1):page107_i260@mstr_discrete.cap(chips)!CAP_0402-0.22UF,16V,10%,X7R,A3A!!!F3968!A!!!!
S!P3E_CPU0_PE1_SS_RXN<1>!C2U6!2!@baseboard_fab2_lib.baseboard_fab2(sch_1):page107_i260@mstr_discrete.cap(chips)!CAP_0402-0.22UF,16V,10%,X7R,A3A!!!F3968!B!!!!
S!P3E_CPU0_PE1_PCH_RXP<2>!C2U7!1!@baseboard_fab2_lib.baseboard_fab2(sch_1):page107_i277@mstr_discrete.cap(chips)!CAP_0402-0.22UF,16V,10%,X7R,A3A!!!F3967!A!!!!
S!P3E_CPU0_PE1_SS_RXP<2>!C2U7!2!@baseboard_fab2_lib.baseboard_fab2(sch_1):page107_i277@mstr_discrete.cap(chips)!CAP_0402-0.22UF,16V,10%,X7R,A3A!!!F3967!B!!!!
S!P3E_CPU0_PE1_PCH_RXN<2>!C2U8!1!@baseboard_fab2_lib.baseboard_fab2(sch_1):page107_i264@mstr_discrete.cap(chips)!CAP_0402-0.22UF,16V,10%,X7R,A3A!!!F3966!A!!!!
S!P3E_CPU0_PE1_SS_RXN<2>!C2U8!2!@baseboard_fab2_lib.baseboard_fab2(sch_1):page107_i264@mstr_discrete.cap(chips)!CAP_0402-0.22UF,16V,10%,X7R,A3A!!!F3966!B!!!!
S!P3E_CPU0_PE1_PCH_RXP<3>!C2U9!1!@baseboard_fab2_lib.baseboard_fab2(sch_1):page107_i279@mstr_discrete.cap(chips)!CAP_0402-0.22UF,16V,10%,X7R,A3A!!!F3965!A!!!!
S!P3E_CPU0_PE1_SS_RXP<3>!C2U9!2!@baseboard_fab2_lib.baseboard_fab2(sch_1):page107_i279@mstr_discrete.cap(chips)!CAP_0402-0.22UF,16V,10%,X7R,A3A!!!F3965!B!!!!
S!P3E_CPU0_PE1_PCH_RXN<3>!C2U10!1!@baseboard_fab2_lib.baseboard_fab2(sch_1):page107_i267@mstr_discrete.cap(chips)!CAP_0402-0.22UF,16V,10%,X7R,A3A!!!F3964!A!!!!
S!P3E_CPU0_PE1_SS_RXN<3>!C2U10!2!@baseboard_fab2_lib.baseboard_fab2(sch_1):page107_i267@mstr_discrete.cap(chips)!CAP_0402-0.22UF,16V,10%,X7R,A3A!!!F3964!B!!!!
S!P3E_CPU0_PE1_PCH_RXP<4>!C2U11!1!@baseboard_fab2_lib.baseboard_fab2(sch_1):page107_i278@mstr_discrete.cap(chips)!CAP_0402-0.22UF,16V,10%,X7R,A3A!!!F3963!A!!!!
S!P3E_CPU0_PE1_SS_RXP<4>!C2U11!2!@baseboard_fab2_lib.baseboard_fab2(sch_1):page107_i278@mstr_discrete.cap(chips)!CAP_0402-0.22UF,16V,10%,X7R,A3A!!!F3963!B!!!!
S!P3E_CPU0_PE1_PCH_RXN<4>!C2U12!1!@baseboard_fab2_lib.baseboard_fab2(sch_1):page107_i265@mstr_discrete.cap(chips)!CAP_0402-0.22UF,16V,10%,X7R,A3A!!!F3962!A!!!!
S!P3E_CPU0_PE1_SS_RXN<4>!C2U12!2!@baseboard_fab2_lib.baseboard_fab2(sch_1):page107_i265@mstr_discrete.cap(chips)!CAP_0402-0.22UF,16V,10%,X7R,A3A!!!F3962!B!!!!
S!P3E_CPU0_PE1_PCH_RXP<5>!C2U13!1!@baseboard_fab2_lib.baseboard_fab2(sch_1):page107_i297@mstr_discrete.cap(chips)!CAP_0402-0.22UF,16V,10%,X7R,A3A!!!F3961!A!!!!
S!P3E_CPU0_PE1_SS_RXP<5>!C2U13!2!@baseboard_fab2_lib.baseboard_fab2(sch_1):page107_i297@mstr_discrete.cap(chips)!CAP_0402-0.22UF,16V,10%,X7R,A3A!!!F3961!B!!!!
S!P3E_CPU0_PE1_PCH_RXN<5>!C2U14!1!@baseboard_fab2_lib.baseboard_fab2(sch_1):page107_i287@mstr_discrete.cap(chips)!CAP_0402-0.22UF,16V,10%,X7R,A3A!!!F3960!A!!!!
S!P3E_CPU0_PE1_SS_RXN<5>!C2U14!2!@baseboard_fab2_lib.baseboard_fab2(sch_1):page107_i287@mstr_discrete.cap(chips)!CAP_0402-0.22UF,16V,10%,X7R,A3A!!!F3960!B!!!!
S!P3E_CPU0_PE1_PCH_RXP<6>!C2U15!1!@baseboard_fab2_lib.baseboard_fab2(sch_1):page107_i296@mstr_discrete.cap(chips)!CAP_0402-0.22UF,16V,10%,X7R,A3A!!!F3959!A!!!!
S!P3E_CPU0_PE1_SS_RXP<6>!C2U15!2!@baseboard_fab2_lib.baseboard_fab2(sch_1):page107_i296@mstr_discrete.cap(chips)!CAP_0402-0.22UF,16V,10%,X7R,A3A!!!F3959!B!!!!
S!P3E_CPU0_PE1_PCH_RXN<6>!C2U16!1!@baseboard_fab2_lib.baseboard_fab2(sch_1):page107_i286@mstr_discrete.cap(chips)!CAP_0402-0.22UF,16V,10%,X7R,A3A!!!F3958!A!!!!
S!P3E_CPU0_PE1_SS_RXN<6>!C2U16!2!@baseboard_fab2_lib.baseboard_fab2(sch_1):page107_i286@mstr_discrete.cap(chips)!CAP_0402-0.22UF,16V,10%,X7R,A3A!!!F3958!B!!!!
S!P3E_CPU0_PE1_PCH_RXP<7>!C2U17!1!@baseboard_fab2_lib.baseboard_fab2(sch_1):page107_i300@mstr_discrete.cap(chips)!CAP_0402-0.22UF,16V,10%,X7R,A3A!!!F3957!A!!!!
S!P3E_CPU0_PE1_SS_RXP<7>!C2U17!2!@baseboard_fab2_lib.baseboard_fab2(sch_1):page107_i300@mstr_discrete.cap(chips)!CAP_0402-0.22UF,16V,10%,X7R,A3A!!!F3957!B!!!!
S!P3E_CPU0_PE1_PCH_RXN<7>!C2U18!1!@baseboard_fab2_lib.baseboard_fab2(sch_1):page107_i294@mstr_discrete.cap(chips)!CAP_0402-0.22UF,16V,10%,X7R,A3A!!!F3956!A!!!!
S!P3E_CPU0_PE1_SS_RXN<7>!C2U18!2!@baseboard_fab2_lib.baseboard_fab2(sch_1):page107_i294@mstr_discrete.cap(chips)!CAP_0402-0.22UF,16V,10%,X7R,A3A!!!F3956!B!!!!
S!P3E_CPU0_PE1_SS_TXP<0>!C3P11!1!@baseboard_fab2_lib.baseboard_fab2(sch_1):page107_i212@mstr_discrete.cap(chips)!CAP_0402-0.22UF,16V,10%,X7R,A3A!!!F3931!A!!!!
S!P3E_CPU0_PE1_PCH_TXP<0>!C3P11!2!@baseboard_fab2_lib.baseboard_fab2(sch_1):page107_i212@mstr_discrete.cap(chips)!CAP_0402-0.22UF,16V,10%,X7R,A3A!!!F3931!B!!!!
S!P3E_CPU0_PE1_SS_TXN<0>!C3P13!1!@baseboard_fab2_lib.baseboard_fab2(sch_1):page107_i207@mstr_discrete.cap(chips)!CAP_0402-0.22UF,16V,10%,X7R,A3A!!!F3930!A!!!!
S!P3E_CPU0_PE1_PCH_TXN<0>!C3P13!2!@baseboard_fab2_lib.baseboard_fab2(sch_1):page107_i207@mstr_discrete.cap(chips)!CAP_0402-0.22UF,16V,10%,X7R,A3A!!!F3930!B!!!!
S!P3E_CPU0_PE1_SS_TXP<1>!C3P15!1!@baseboard_fab2_lib.baseboard_fab2(sch_1):page107_i226@mstr_discrete.cap(chips)!CAP_0402-0.22UF,16V,10%,X7R,A3A!!!F3929!A!!!!
S!P3E_CPU0_PE1_PCH_TXP<1>!C3P15!2!@baseboard_fab2_lib.baseboard_fab2(sch_1):page107_i226@mstr_discrete.cap(chips)!CAP_0402-0.22UF,16V,10%,X7R,A3A!!!F3929!B!!!!
S!P3E_CPU0_PE1_SS_TXN<1>!C3P17!1!@baseboard_fab2_lib.baseboard_fab2(sch_1):page107_i208@mstr_discrete.cap(chips)!CAP_0402-0.22UF,16V,10%,X7R,A3A!!!F3928!A!!!!
S!P3E_CPU0_PE1_PCH_TXN<1>!C3P17!2!@baseboard_fab2_lib.baseboard_fab2(sch_1):page107_i208@mstr_discrete.cap(chips)!CAP_0402-0.22UF,16V,10%,X7R,A3A!!!F3928!B!!!!
S!P3E_CPU0_PE1_SS_TXP<2>!C3P18!1!@baseboard_fab2_lib.baseboard_fab2(sch_1):page107_i219@mstr_discrete.cap(chips)!CAP_0402-0.22UF,16V,10%,X7R,A3A!!!F3927!A!!!!
S!P3E_CPU0_PE1_PCH_TXP<2>!C3P18!2!@baseboard_fab2_lib.baseboard_fab2(sch_1):page107_i219@mstr_discrete.cap(chips)!CAP_0402-0.22UF,16V,10%,X7R,A3A!!!F3927!B!!!!
S!P3E_CPU0_PE1_SS_TXN<2>!C3P20!1!@baseboard_fab2_lib.baseboard_fab2(sch_1):page107_i215@mstr_discrete.cap(chips)!CAP_0402-0.22UF,16V,10%,X7R,A3A!!!F3926!A!!!!
S!P3E_CPU0_PE1_PCH_TXN<2>!C3P20!2!@baseboard_fab2_lib.baseboard_fab2(sch_1):page107_i215@mstr_discrete.cap(chips)!CAP_0402-0.22UF,16V,10%,X7R,A3A!!!F3926!B!!!!
S!P3E_CPU0_PE1_SS_TXP<3>!C3P23!1!@baseboard_fab2_lib.baseboard_fab2(sch_1):page107_i229@mstr_discrete.cap(chips)!CAP_0402-0.22UF,16V,10%,X7R,A3A!!!F3925!A!!!!
S!P3E_CPU0_PE1_PCH_TXP<3>!C3P23!2!@baseboard_fab2_lib.baseboard_fab2(sch_1):page107_i229@mstr_discrete.cap(chips)!CAP_0402-0.22UF,16V,10%,X7R,A3A!!!F3925!B!!!!
S!P3E_CPU0_PE1_SS_TXN<3>!C3P25!1!@baseboard_fab2_lib.baseboard_fab2(sch_1):page107_i216@mstr_discrete.cap(chips)!CAP_0402-0.22UF,16V,10%,X7R,A3A!!!F3924!A!!!!
S!P3E_CPU0_PE1_PCH_TXN<3>!C3P25!2!@baseboard_fab2_lib.baseboard_fab2(sch_1):page107_i216@mstr_discrete.cap(chips)!CAP_0402-0.22UF,16V,10%,X7R,A3A!!!F3924!B!!!!
S!P3E_CPU0_PE1_SS_TXP<4>!C3P27!1!@baseboard_fab2_lib.baseboard_fab2(sch_1):page107_i223@mstr_discrete.cap(chips)!CAP_0402-0.22UF,16V,10%,X7R,A3A!!!F3923!A!!!!
S!P3E_CPU0_PE1_PCH_TXP<4>!C3P27!2!@baseboard_fab2_lib.baseboard_fab2(sch_1):page107_i223@mstr_discrete.cap(chips)!CAP_0402-0.22UF,16V,10%,X7R,A3A!!!F3923!B!!!!
S!P3E_CPU0_PE1_SS_TXN<4>!C3P28!1!@baseboard_fab2_lib.baseboard_fab2(sch_1):page107_i232@mstr_discrete.cap(chips)!CAP_0402-0.22UF,16V,10%,X7R,A3A!!!F3922!A!!!!
S!P3E_CPU0_PE1_PCH_TXN<4>!C3P28!2!@baseboard_fab2_lib.baseboard_fab2(sch_1):page107_i232@mstr_discrete.cap(chips)!CAP_0402-0.22UF,16V,10%,X7R,A3A!!!F3922!B!!!!
S!P3E_CPU0_PE1_SS_TXP<5>!C3P30!1!@baseboard_fab2_lib.baseboard_fab2(sch_1):page107_i245@mstr_discrete.cap(chips)!CAP_0402-0.22UF,16V,10%,X7R,A3A!!!F3921!A!!!!
S!P3E_CPU0_PE1_PCH_TXP<5>!C3P30!2!@baseboard_fab2_lib.baseboard_fab2(sch_1):page107_i245@mstr_discrete.cap(chips)!CAP_0402-0.22UF,16V,10%,X7R,A3A!!!F3921!B!!!!
S!P3E_CPU0_PE1_SS_TXN<5>!C3P32!1!@baseboard_fab2_lib.baseboard_fab2(sch_1):page107_i234@mstr_discrete.cap(chips)!CAP_0402-0.22UF,16V,10%,X7R,A3A!!!F3920!A!!!!
S!P3E_CPU0_PE1_PCH_TXN<5>!C3P32!2!@baseboard_fab2_lib.baseboard_fab2(sch_1):page107_i234@mstr_discrete.cap(chips)!CAP_0402-0.22UF,16V,10%,X7R,A3A!!!F3920!B!!!!
S!P3E_CPU0_PE1_SS_TXP<6>!C3P35!1!@baseboard_fab2_lib.baseboard_fab2(sch_1):page107_i240@mstr_discrete.cap(chips)!CAP_0402-0.22UF,16V,10%,X7R,A3A!!!F3919!A!!!!
S!P3E_CPU0_PE1_PCH_TXP<6>!C3P35!2!@baseboard_fab2_lib.baseboard_fab2(sch_1):page107_i240@mstr_discrete.cap(chips)!CAP_0402-0.22UF,16V,10%,X7R,A3A!!!F3919!B!!!!
S!P3E_CPU0_PE1_SS_TXN<6>!C3P37!1!@baseboard_fab2_lib.baseboard_fab2(sch_1):page107_i235@mstr_discrete.cap(chips)!CAP_0402-0.22UF,16V,10%,X7R,A3A!!!F3918!A!!!!
S!P3E_CPU0_PE1_PCH_TXN<6>!C3P37!2!@baseboard_fab2_lib.baseboard_fab2(sch_1):page107_i235@mstr_discrete.cap(chips)!CAP_0402-0.22UF,16V,10%,X7R,A3A!!!F3918!B!!!!
S!P3E_CPU0_PE1_SS_TXP<7>!C3P39!1!@baseboard_fab2_lib.baseboard_fab2(sch_1):page107_i248@mstr_discrete.cap(chips)!CAP_0402-0.22UF,16V,10%,X7R,A3A!!!F3917!A!!!!
S!P3E_CPU0_PE1_PCH_TXP<7>!C3P39!2!@baseboard_fab2_lib.baseboard_fab2(sch_1):page107_i248@mstr_discrete.cap(chips)!CAP_0402-0.22UF,16V,10%,X7R,A3A!!!F3917!B!!!!
S!P3E_CPU0_PE1_SS_TXN<7>!C3P40!1!@baseboard_fab2_lib.baseboard_fab2(sch_1):page107_i241@mstr_discrete.cap(chips)!CAP_0402-0.22UF,16V,10%,X7R,A3A!!!F3916!A!!!!
S!P3E_CPU0_PE1_PCH_TXN<7>!C3P40!2!@baseboard_fab2_lib.baseboard_fab2(sch_1):page107_i241@mstr_discrete.cap(chips)!CAP_0402-0.22UF,16V,10%,X7R,A3A!!!F3916!B!!!!
S!P3E_PCH_TX_0_DP!C8F7!1!@baseboard_fab2_lib.baseboard_fab2(sch_1):page185_i96@mstr_discrete.cap(chips)!CAP_0402-0.22UF,16V,10%,X7R,A3A!!!F3856!A!!!!
S!P3E_PCH_M2_SATA6G_TX_R_DP!C8F7!2!@baseboard_fab2_lib.baseboard_fab2(sch_1):page185_i96@mstr_discrete.cap(chips)!CAP_0402-0.22UF,16V,10%,X7R,A3A!!!F3856!B!!!!
S!P3E_PCH_TX_0_DN!C8F12!1!@baseboard_fab2_lib.baseboard_fab2(sch_1):page185_i98@mstr_discrete.cap(chips)!CAP_0402-0.22UF,16V,10%,X7R,A3A!!!F3855!A!!!!
S!P3E_PCH_M2_SATA6G_TX_R_DN!C8F12!2!@baseboard_fab2_lib.baseboard_fab2(sch_1):page185_i98@mstr_discrete.cap(chips)!CAP_0402-0.22UF,16V,10%,X7R,A3A!!!F3855!B!!!!
S!P3E_CPU0_PE1_PCH_R_RXP<15>!C3M2!1!@baseboard_fab2_lib.baseboard_fab2(sch_1):page105_i247@mstr_discrete.cap(chips)!CAP_0402-0.22UF,16V,10%,X7R,A3A!!!F3954!A!!!!
S!P3E_CPU0_PE1_PCH_RXP<15>!C3M2!2!@baseboard_fab2_lib.baseboard_fab2(sch_1):page105_i247@mstr_discrete.cap(chips)!CAP_0402-0.22UF,16V,10%,X7R,A3A!!!F3954!B!!!!
S!P3E_CPU0_PE1_PCH_R_RXN<15>!C3M1!1!@baseboard_fab2_lib.baseboard_fab2(sch_1):page105_i255@mstr_discrete.cap(chips)!CAP_0402-0.22UF,16V,10%,X7R,A3A!!!F3955!A!!!!
S!P3E_CPU0_PE1_PCH_RXN<15>!C3M1!2!@baseboard_fab2_lib.baseboard_fab2(sch_1):page105_i255@mstr_discrete.cap(chips)!CAP_0402-0.22UF,16V,10%,X7R,A3A!!!F3955!B!!!!
S!P3E_CPU0_PE1_PCH_R_RXP<14>!C3M11!1!@baseboard_fab2_lib.baseboard_fab2(sch_1):page105_i234@mstr_discrete.cap(chips)!CAP_0402-0.22UF,16V,10%,X7R,A3A!!!F3951!A!!!!
S!P3E_CPU0_PE1_PCH_RXP<14>!C3M11!2!@baseboard_fab2_lib.baseboard_fab2(sch_1):page105_i234@mstr_discrete.cap(chips)!CAP_0402-0.22UF,16V,10%,X7R,A3A!!!F3951!B!!!!
S!P3E_CPU0_PE1_PCH_R_RXN<14>!C3M12!1!@baseboard_fab2_lib.baseboard_fab2(sch_1):page105_i246@mstr_discrete.cap(chips)!CAP_0402-0.22UF,16V,10%,X7R,A3A!!!F3950!A!!!!
S!P3E_CPU0_PE1_PCH_RXN<14>!C3M12!2!@baseboard_fab2_lib.baseboard_fab2(sch_1):page105_i246@mstr_discrete.cap(chips)!CAP_0402-0.22UF,16V,10%,X7R,A3A!!!F3950!B!!!!
S!P3E_CPU0_PE1_PCH_R_RXP<13>!C3M13!1!@baseboard_fab2_lib.baseboard_fab2(sch_1):page105_i239@mstr_discrete.cap(chips)!CAP_0402-0.22UF,16V,10%,X7R,A3A!!!F3949!A!!!!
S!P3E_CPU0_PE1_PCH_RXP<13>!C3M13!2!@baseboard_fab2_lib.baseboard_fab2(sch_1):page105_i239@mstr_discrete.cap(chips)!CAP_0402-0.22UF,16V,10%,X7R,A3A!!!F3949!B!!!!
S!P3E_CPU0_PE1_PCH_R_RXN<13>!C3M14!1!@baseboard_fab2_lib.baseboard_fab2(sch_1):page105_i253@mstr_discrete.cap(chips)!CAP_0402-0.22UF,16V,10%,X7R,A3A!!!F3948!A!!!!
S!P3E_CPU0_PE1_PCH_RXN<13>!C3M14!2!@baseboard_fab2_lib.baseboard_fab2(sch_1):page105_i253@mstr_discrete.cap(chips)!CAP_0402-0.22UF,16V,10%,X7R,A3A!!!F3948!B!!!!
S!P3E_CPU0_PE1_PCH_R_RXP<12>!C3M3!1!@baseboard_fab2_lib.baseboard_fab2(sch_1):page105_i232@mstr_discrete.cap(chips)!CAP_0402-0.22UF,16V,10%,X7R,A3A!!!F3953!A!!!!
S!P3E_CPU0_PE1_PCH_RXP<12>!C3M3!2!@baseboard_fab2_lib.baseboard_fab2(sch_1):page105_i232@mstr_discrete.cap(chips)!CAP_0402-0.22UF,16V,10%,X7R,A3A!!!F3953!B!!!!
S!P3E_CPU0_PE1_PCH_R_RXN<12>!C3M4!1!@baseboard_fab2_lib.baseboard_fab2(sch_1):page105_i244@mstr_discrete.cap(chips)!CAP_0402-0.22UF,16V,10%,X7R,A3A!!!F3952!A!!!!
S!P3E_CPU0_PE1_PCH_RXN<12>!C3M4!2!@baseboard_fab2_lib.baseboard_fab2(sch_1):page105_i244@mstr_discrete.cap(chips)!CAP_0402-0.22UF,16V,10%,X7R,A3A!!!F3952!B!!!!
S!P3E_CPU0_PE1_PCH_R_RXP<11>!C3M25!1!@baseboard_fab2_lib.baseboard_fab2(sch_1):page105_i205@mstr_discrete.cap(chips)!CAP_0402-0.22UF,16V,10%,X7R,A3A!!!F3947!A!!!!
S!P3E_CPU0_PE1_PCH_RXP<11>!C3M25!2!@baseboard_fab2_lib.baseboard_fab2(sch_1):page105_i205@mstr_discrete.cap(chips)!CAP_0402-0.22UF,16V,10%,X7R,A3A!!!F3947!B!!!!
S!P3E_CPU0_PE1_PCH_R_RXN<11>!C3M26!1!@baseboard_fab2_lib.baseboard_fab2(sch_1):page105_i229@mstr_discrete.cap(chips)!CAP_0402-0.22UF,16V,10%,X7R,A3A!!!F3946!A!!!!
S!P3E_CPU0_PE1_PCH_RXN<11>!C3M26!2!@baseboard_fab2_lib.baseboard_fab2(sch_1):page105_i229@mstr_discrete.cap(chips)!CAP_0402-0.22UF,16V,10%,X7R,A3A!!!F3946!B!!!!
S!P3E_CPU0_PE1_PCH_R_RXP<10>!C3M28!1!@baseboard_fab2_lib.baseboard_fab2(sch_1):page105_i212@mstr_discrete.cap(chips)!CAP_0402-0.22UF,16V,10%,X7R,A3A!!!F3945!A!!!!
S!P3E_CPU0_PE1_PCH_RXP<10>!C3M28!2!@baseboard_fab2_lib.baseboard_fab2(sch_1):page105_i212@mstr_discrete.cap(chips)!CAP_0402-0.22UF,16V,10%,X7R,A3A!!!F3945!B!!!!
S!P3E_CPU0_PE1_PCH_R_RXN<10>!C3M32!1!@baseboard_fab2_lib.baseboard_fab2(sch_1):page105_i223@mstr_discrete.cap(chips)!CAP_0402-0.22UF,16V,10%,X7R,A3A!!!F3944!A!!!!
S!P3E_CPU0_PE1_PCH_RXN<10>!C3M32!2!@baseboard_fab2_lib.baseboard_fab2(sch_1):page105_i223@mstr_discrete.cap(chips)!CAP_0402-0.22UF,16V,10%,X7R,A3A!!!F3944!B!!!!
S!P3E_CPU0_PE1_PCH_R_RXP<9>!C3M36!1!@baseboard_fab2_lib.baseboard_fab2(sch_1):page105_i218@mstr_discrete.cap(chips)!CAP_0402-0.22UF,16V,10%,X7R,A3A!!!F3940!A!!!!
S!P3E_CPU0_PE1_PCH_RXP<9>!C3M36!2!@baseboard_fab2_lib.baseboard_fab2(sch_1):page105_i218@mstr_discrete.cap(chips)!CAP_0402-0.22UF,16V,10%,X7R,A3A!!!F3940!B!!!!
S!P3E_CPU0_PE1_PCH_R_RXN<9>!C3M35!1!@baseboard_fab2_lib.baseboard_fab2(sch_1):page105_i225@mstr_discrete.cap(chips)!CAP_0402-0.22UF,16V,10%,X7R,A3A!!!F3941!A!!!!
S!P3E_CPU0_PE1_PCH_RXN<9>!C3M35!2!@baseboard_fab2_lib.baseboard_fab2(sch_1):page105_i225@mstr_discrete.cap(chips)!CAP_0402-0.22UF,16V,10%,X7R,A3A!!!F3941!B!!!!
S!P3E_CPU0_PE1_PCH_R_RXP<8>!C3M34!1!@baseboard_fab2_lib.baseboard_fab2(sch_1):page105_i206@mstr_discrete.cap(chips)!CAP_0402-0.22UF,16V,10%,X7R,A3A!!!F3942!A!!!!
S!P3E_CPU0_PE1_PCH_RXP<8>!C3M34!2!@baseboard_fab2_lib.baseboard_fab2(sch_1):page105_i206@mstr_discrete.cap(chips)!CAP_0402-0.22UF,16V,10%,X7R,A3A!!!F3942!B!!!!
S!P3E_CPU0_PE1_PCH_R_RXN<8>!C3M33!1!@baseboard_fab2_lib.baseboard_fab2(sch_1):page105_i217@mstr_discrete.cap(chips)!CAP_0402-0.22UF,16V,10%,X7R,A3A!!!F3943!A!!!!
S!P3E_CPU0_PE1_PCH_RXN<8>!C3M33!2!@baseboard_fab2_lib.baseboard_fab2(sch_1):page105_i217@mstr_discrete.cap(chips)!CAP_0402-0.22UF,16V,10%,X7R,A3A!!!F3943!B!!!!
S!P3E_CPU0_PE1_PCH_TXN<15>!C6B4!1!@baseboard_fab2_lib.baseboard_fab2(sch_1):page105_i196@mstr_discrete.cap(chips)!CAP_0402-0.22UF,16V,10%,X7R,A3A!!!F3908!A!!!!
S!P3E_CPU0_PE1_PCH_C_TXN<15>!C6B4!2!@baseboard_fab2_lib.baseboard_fab2(sch_1):page105_i196@mstr_discrete.cap(chips)!CAP_0402-0.22UF,16V,10%,X7R,A3A!!!F3908!B!!!!
S!P3E_CPU0_PE1_PCH_TXP<15>!C6B5!1!@baseboard_fab2_lib.baseboard_fab2(sch_1):page105_i201@mstr_discrete.cap(chips)!CAP_0402-0.22UF,16V,10%,X7R,A3A!!!F3907!A!!!!
S!P3E_CPU0_PE1_PCH_C_TXP<15>!C6B5!2!@baseboard_fab2_lib.baseboard_fab2(sch_1):page105_i201@mstr_discrete.cap(chips)!CAP_0402-0.22UF,16V,10%,X7R,A3A!!!F3907!B!!!!
S!P3E_CPU0_PE1_PCH_TXN<14>!C6B6!1!@baseboard_fab2_lib.baseboard_fab2(sch_1):page105_i169@mstr_discrete.cap(chips)!CAP_0402-0.22UF,16V,10%,X7R,A3A!!!F3906!A!!!!
S!P3E_CPU0_PE1_PCH_C_TXN<14>!C6B6!2!@baseboard_fab2_lib.baseboard_fab2(sch_1):page105_i169@mstr_discrete.cap(chips)!CAP_0402-0.22UF,16V,10%,X7R,A3A!!!F3906!B!!!!
S!P3E_CPU0_PE1_PCH_TXP<14>!C6B8!1!@baseboard_fab2_lib.baseboard_fab2(sch_1):page105_i198@mstr_discrete.cap(chips)!CAP_0402-0.22UF,16V,10%,X7R,A3A!!!F3905!A!!!!
S!P3E_CPU0_PE1_PCH_C_TXP<14>!C6B8!2!@baseboard_fab2_lib.baseboard_fab2(sch_1):page105_i198@mstr_discrete.cap(chips)!CAP_0402-0.22UF,16V,10%,X7R,A3A!!!F3905!B!!!!
S!P3E_CPU0_PE1_PCH_TXN<13>!C6B9!1!@baseboard_fab2_lib.baseboard_fab2(sch_1):page105_i185@mstr_discrete.cap(chips)!CAP_0402-0.22UF,16V,10%,X7R,A3A!!!F3904!A!!!!
S!P3E_CPU0_PE1_PCH_C_TXN<13>!C6B9!2!@baseboard_fab2_lib.baseboard_fab2(sch_1):page105_i185@mstr_discrete.cap(chips)!CAP_0402-0.22UF,16V,10%,X7R,A3A!!!F3904!B!!!!
S!P3E_CPU0_PE1_PCH_TXP<13>!C6B10!1!@baseboard_fab2_lib.baseboard_fab2(sch_1):page105_i193@mstr_discrete.cap(chips)!CAP_0402-0.22UF,16V,10%,X7R,A3A!!!F3903!A!!!!
S!P3E_CPU0_PE1_PCH_C_TXP<13>!C6B10!2!@baseboard_fab2_lib.baseboard_fab2(sch_1):page105_i193@mstr_discrete.cap(chips)!CAP_0402-0.22UF,16V,10%,X7R,A3A!!!F3903!B!!!!
S!P3E_CPU0_PE1_PCH_TXN<12>!C6B11!1!@baseboard_fab2_lib.baseboard_fab2(sch_1):page105_i166@mstr_discrete.cap(chips)!CAP_0402-0.22UF,16V,10%,X7R,A3A!!!F3902!A!!!!
S!P3E_CPU0_PE1_PCH_C_TXN<12>!C6B11!2!@baseboard_fab2_lib.baseboard_fab2(sch_1):page105_i166@mstr_discrete.cap(chips)!CAP_0402-0.22UF,16V,10%,X7R,A3A!!!F3902!B!!!!
S!P3E_CPU0_PE1_PCH_TXP<12>!C6B12!1!@baseboard_fab2_lib.baseboard_fab2(sch_1):page105_i187@mstr_discrete.cap(chips)!CAP_0402-0.22UF,16V,10%,X7R,A3A!!!F3901!A!!!!
S!P3E_CPU0_PE1_PCH_C_TXP<12>!C6B12!2!@baseboard_fab2_lib.baseboard_fab2(sch_1):page105_i187@mstr_discrete.cap(chips)!CAP_0402-0.22UF,16V,10%,X7R,A3A!!!F3901!B!!!!
S!P3E_CPU0_PE1_PCH_TXN<11>!C6B14!1!@baseboard_fab2_lib.baseboard_fab2(sch_1):page105_i181@mstr_discrete.cap(chips)!CAP_0402-0.22UF,16V,10%,X7R,A3A!!!F3899!A!!!!
S!P3E_CPU0_PE1_PCH_C_TXN<11>!C6B14!2!@baseboard_fab2_lib.baseboard_fab2(sch_1):page105_i181@mstr_discrete.cap(chips)!CAP_0402-0.22UF,16V,10%,X7R,A3A!!!F3899!B!!!!
S!P3E_CPU0_PE1_PCH_TXP<11>!C6B13!1!@baseboard_fab2_lib.baseboard_fab2(sch_1):page105_i189@mstr_discrete.cap(chips)!CAP_0402-0.22UF,16V,10%,X7R,A3A!!!F3900!A!!!!
S!P3E_CPU0_PE1_PCH_C_TXP<11>!C6B13!2!@baseboard_fab2_lib.baseboard_fab2(sch_1):page105_i189@mstr_discrete.cap(chips)!CAP_0402-0.22UF,16V,10%,X7R,A3A!!!F3900!B!!!!
S!P3E_CPU0_PE1_PCH_TXN<10>!C6B15!1!@baseboard_fab2_lib.baseboard_fab2(sch_1):page105_i163@mstr_discrete.cap(chips)!CAP_0402-0.22UF,16V,10%,X7R,A3A!!!F3898!A!!!!
S!P3E_CPU0_PE1_PCH_C_TXN<10>!C6B15!2!@baseboard_fab2_lib.baseboard_fab2(sch_1):page105_i163@mstr_discrete.cap(chips)!CAP_0402-0.22UF,16V,10%,X7R,A3A!!!F3898!B!!!!
S!P3E_CPU0_PE1_PCH_TXP<10>!C6B16!1!@baseboard_fab2_lib.baseboard_fab2(sch_1):page105_i180@mstr_discrete.cap(chips)!CAP_0402-0.22UF,16V,10%,X7R,A3A!!!F3897!A!!!!
S!P3E_CPU0_PE1_PCH_C_TXP<10>!C6B16!2!@baseboard_fab2_lib.baseboard_fab2(sch_1):page105_i180@mstr_discrete.cap(chips)!CAP_0402-0.22UF,16V,10%,X7R,A3A!!!F3897!B!!!!
S!P3E_CPU0_PE1_PCH_TXN<9>!C6B17!1!@baseboard_fab2_lib.baseboard_fab2(sch_1):page105_i175@mstr_discrete.cap(chips)!CAP_0402-0.22UF,16V,10%,X7R,A3A!!!F3896!A!!!!
S!P3E_CPU0_PE1_PCH_C_TXN<9>!C6B17!2!@baseboard_fab2_lib.baseboard_fab2(sch_1):page105_i175@mstr_discrete.cap(chips)!CAP_0402-0.22UF,16V,10%,X7R,A3A!!!F3896!B!!!!
S!P3E_CPU0_PE1_PCH_TXP<9>!C6B18!1!@baseboard_fab2_lib.baseboard_fab2(sch_1):page105_i153@mstr_discrete.cap(chips)!CAP_0402-0.22UF,16V,10%,X7R,A3A!!!F3895!A!!!!
S!P3E_CPU0_PE1_PCH_C_TXP<9>!C6B18!2!@baseboard_fab2_lib.baseboard_fab2(sch_1):page105_i153@mstr_discrete.cap(chips)!CAP_0402-0.22UF,16V,10%,X7R,A3A!!!F3895!B!!!!
S!P3E_CPU0_PE1_PCH_TXN<8>!C6B19!1!@baseboard_fab2_lib.baseboard_fab2(sch_1):page105_i160@mstr_discrete.cap(chips)!CAP_0402-0.22UF,16V,10%,X7R,A3A!!!F3894!A!!!!
S!P3E_CPU0_PE1_PCH_C_TXN<8>!C6B19!2!@baseboard_fab2_lib.baseboard_fab2(sch_1):page105_i160@mstr_discrete.cap(chips)!CAP_0402-0.22UF,16V,10%,X7R,A3A!!!F3894!B!!!!
S!P3E_CPU0_PE1_PCH_TXP<8>!C6B20!1!@baseboard_fab2_lib.baseboard_fab2(sch_1):page105_i173@mstr_discrete.cap(chips)!CAP_0402-0.22UF,16V,10%,X7R,A3A!!!F3893!A!!!!
S!P3E_CPU0_PE1_PCH_C_TXP<8>!C6B20!2!@baseboard_fab2_lib.baseboard_fab2(sch_1):page105_i173@mstr_discrete.cap(chips)!CAP_0402-0.22UF,16V,10%,X7R,A3A!!!F3893!B!!!!
S!P3E_CPU0_PE3_OCP_TXP<3>!C1R8!1!@baseboard_fab2_lib.baseboard_fab2(sch_1):page106_i55@mstr_discrete.cap(chips)!CAP_0402-0.22UF,16V,10%,X7R,A3A!!!F3989!A!!!!
S!P3E_OCP_CPU0_PE3_C_TXP<3>!C1R8!2!@baseboard_fab2_lib.baseboard_fab2(sch_1):page106_i55@mstr_discrete.cap(chips)!CAP_0402-0.22UF,16V,10%,X7R,A3A!!!F3989!B!!!!
S!P3E_CPU0_PE3_OCP_TXN<3>!C1R7!1!@baseboard_fab2_lib.baseboard_fab2(sch_1):page106_i70@mstr_discrete.cap(chips)!CAP_0402-0.22UF,16V,10%,X7R,A3A!!!F3990!A!!!!
S!P3E_OCP_CPU0_PE3_C_TXN<3>!C1R7!2!@baseboard_fab2_lib.baseboard_fab2(sch_1):page106_i70@mstr_discrete.cap(chips)!CAP_0402-0.22UF,16V,10%,X7R,A3A!!!F3990!B!!!!
S!P3E_CPU0_PE3_OCP_TXP<2>!C1R6!1!@baseboard_fab2_lib.baseboard_fab2(sch_1):page106_i40@mstr_discrete.cap(chips)!CAP_0402-0.22UF,16V,10%,X7R,A3A!!!F3991!A!!!!
S!P3E_OCP_CPU0_PE3_C_TXP<2>!C1R6!2!@baseboard_fab2_lib.baseboard_fab2(sch_1):page106_i40@mstr_discrete.cap(chips)!CAP_0402-0.22UF,16V,10%,X7R,A3A!!!F3991!B!!!!
S!P3E_CPU0_PE3_OCP_TXN<2>!C1R5!1!@baseboard_fab2_lib.baseboard_fab2(sch_1):page106_i59@mstr_discrete.cap(chips)!CAP_0402-0.22UF,16V,10%,X7R,A3A!!!F3992!A!!!!
S!P3E_OCP_CPU0_PE3_C_TXN<2>!C1R5!2!@baseboard_fab2_lib.baseboard_fab2(sch_1):page106_i59@mstr_discrete.cap(chips)!CAP_0402-0.22UF,16V,10%,X7R,A3A!!!F3992!B!!!!
S!P3E_CPU0_PE3_OCP_TXP<1>!C1R4!1!@baseboard_fab2_lib.baseboard_fab2(sch_1):page106_i26@mstr_discrete.cap(chips)!CAP_0402-0.22UF,16V,10%,X7R,A3A!!!F3993!A!!!!
S!P3E_OCP_CPU0_PE3_C_TXP<1>!C1R4!2!@baseboard_fab2_lib.baseboard_fab2(sch_1):page106_i26@mstr_discrete.cap(chips)!CAP_0402-0.22UF,16V,10%,X7R,A3A!!!F3993!B!!!!
S!P3E_CPU0_PE3_OCP_TXN<1>!C1R3!1!@baseboard_fab2_lib.baseboard_fab2(sch_1):page106_i37@mstr_discrete.cap(chips)!CAP_0402-0.22UF,16V,10%,X7R,A3A!!!F3994!A!!!!
S!P3E_OCP_CPU0_PE3_C_TXN<1>!C1R3!2!@baseboard_fab2_lib.baseboard_fab2(sch_1):page106_i37@mstr_discrete.cap(chips)!CAP_0402-0.22UF,16V,10%,X7R,A3A!!!F3994!B!!!!
S!P3E_CPU0_PE3_OCP_TXP<7>!C2R10!1!@baseboard_fab2_lib.baseboard_fab2(sch_1):page106_i142@mstr_discrete.cap(chips)!CAP_0402-0.22UF,16V,10%,X7R,A3A!!!F3978!A!!!!
S!P3E_OCP_CPU0_PE3_C_TXP<7>!C2R10!2!@baseboard_fab2_lib.baseboard_fab2(sch_1):page106_i142@mstr_discrete.cap(chips)!CAP_0402-0.22UF,16V,10%,X7R,A3A!!!F3978!B!!!!
S!P3E_CPU0_PE3_OCP_TXN<7>!C2R9!1!@baseboard_fab2_lib.baseboard_fab2(sch_1):page106_i147@mstr_discrete.cap(chips)!CAP_0402-0.22UF,16V,10%,X7R,A3A!!!F3979!A!!!!
S!P3E_OCP_CPU0_PE3_C_TXN<7>!C2R9!2!@baseboard_fab2_lib.baseboard_fab2(sch_1):page106_i147@mstr_discrete.cap(chips)!CAP_0402-0.22UF,16V,10%,X7R,A3A!!!F3979!B!!!!
S!P3E_CPU0_PE3_OCP_TXP<6>!C2R8!1!@baseboard_fab2_lib.baseboard_fab2(sch_1):page106_i141@mstr_discrete.cap(chips)!CAP_0402-0.22UF,16V,10%,X7R,A3A!!!F3980!A!!!!
S!P3E_OCP_CPU0_PE3_C_TXP<6>!C2R8!2!@baseboard_fab2_lib.baseboard_fab2(sch_1):page106_i141@mstr_discrete.cap(chips)!CAP_0402-0.22UF,16V,10%,X7R,A3A!!!F3980!B!!!!
S!P3E_CPU0_PE3_OCP_TXN<6>!C2R7!1!@baseboard_fab2_lib.baseboard_fab2(sch_1):page106_i123@mstr_discrete.cap(chips)!CAP_0402-0.22UF,16V,10%,X7R,A3A!!!F3981!A!!!!
S!P3E_OCP_CPU0_PE3_C_TXN<6>!C2R7!2!@baseboard_fab2_lib.baseboard_fab2(sch_1):page106_i123@mstr_discrete.cap(chips)!CAP_0402-0.22UF,16V,10%,X7R,A3A!!!F3981!B!!!!
S!P3E_CPU0_PE3_OCP_TXP<5>!C2R14!1!@baseboard_fab2_lib.baseboard_fab2(sch_1):page106_i130@mstr_discrete.cap(chips)!CAP_0402-0.22UF,16V,10%,X7R,A3A!!!F3985!A!!!!
S!P3E_OCP_CPU0_PE3_C_TXP<5>!C2R14!2!@baseboard_fab2_lib.baseboard_fab2(sch_1):page106_i130@mstr_discrete.cap(chips)!CAP_0402-0.22UF,16V,10%,X7R,A3A!!!F3985!B!!!!
S!P3E_CPU0_PE3_OCP_TXP<0>!C1R2!1!@baseboard_fab2_lib.baseboard_fab2(sch_1):page106_i10@mstr_discrete.cap(chips)!CAP_0402-0.22UF,16V,10%,X7R,A3A!!!F3995!A!!!!
S!P3E_OCP_CPU0_PE3_C_TXP<0>!C1R2!2!@baseboard_fab2_lib.baseboard_fab2(sch_1):page106_i10@mstr_discrete.cap(chips)!CAP_0402-0.22UF,16V,10%,X7R,A3A!!!F3995!B!!!!
S!P3E_CPU0_PE3_OCP_TXN<0>!C1R1!1!@baseboard_fab2_lib.baseboard_fab2(sch_1):page106_i29@mstr_discrete.cap(chips)!CAP_0402-0.22UF,16V,10%,X7R,A3A!!!F3996!A!!!!
S!P3E_OCP_CPU0_PE3_C_TXN<0>!C1R1!2!@baseboard_fab2_lib.baseboard_fab2(sch_1):page106_i29@mstr_discrete.cap(chips)!CAP_0402-0.22UF,16V,10%,X7R,A3A!!!F3996!B!!!!
S!P3E_CPU0_PE3_OCP_TXN<5>!C2R13!1!@baseboard_fab2_lib.baseboard_fab2(sch_1):page106_i137@mstr_discrete.cap(chips)!CAP_0402-0.22UF,16V,10%,X7R,A3A!!!F3986!A!!!!
S!P3E_OCP_CPU0_PE3_C_TXN<5>!C2R13!2!@baseboard_fab2_lib.baseboard_fab2(sch_1):page106_i137@mstr_discrete.cap(chips)!CAP_0402-0.22UF,16V,10%,X7R,A3A!!!F3986!B!!!!
S!P3E_CPU0_PE3_OCP_TXP<4>!C1R10!1!@baseboard_fab2_lib.baseboard_fab2(sch_1):page106_i128@mstr_discrete.cap(chips)!CAP_0402-0.22UF,16V,10%,X7R,A3A!!!F3987!A!!!!
S!P3E_OCP_CPU0_PE3_C_TXP<4>!C1R10!2!@baseboard_fab2_lib.baseboard_fab2(sch_1):page106_i128@mstr_discrete.cap(chips)!CAP_0402-0.22UF,16V,10%,X7R,A3A!!!F3987!B!!!!
S!P3E_CPU0_PE3_OCP_TXN<4>!C1R9!1!@baseboard_fab2_lib.baseboard_fab2(sch_1):page106_i134@mstr_discrete.cap(chips)!CAP_0402-0.22UF,16V,10%,X7R,A3A!!!F3988!A!!!!
S!P3E_OCP_CPU0_PE3_C_TXN<4>!C1R9!2!@baseboard_fab2_lib.baseboard_fab2(sch_1):page106_i134@mstr_discrete.cap(chips)!CAP_0402-0.22UF,16V,10%,X7R,A3A!!!F3988!B!!!!
S!P3E_CPU0_PE3_OCP_TXP<15>!C1M6!1!@baseboard_fab2_lib.baseboard_fab2(sch_1):page106_i109@mstr_discrete.cap(chips)!CAP_0402-0.22UF,16V,10%,X7R,A3A!!!F4010!A!!!!
S!P3E_OCP_CPU0_PE3_C_TXP<15>!C1M6!2!@baseboard_fab2_lib.baseboard_fab2(sch_1):page106_i109@mstr_discrete.cap(chips)!CAP_0402-0.22UF,16V,10%,X7R,A3A!!!F4010!B!!!!
S!P3E_CPU0_PE3_OCP_TXN<15>!C1M7!1!@baseboard_fab2_lib.baseboard_fab2(sch_1):page106_i122@mstr_discrete.cap(chips)!CAP_0402-0.22UF,16V,10%,X7R,A3A!!!F4009!A!!!!
S!P3E_OCP_CPU0_PE3_C_TXN<15>!C1M7!2!@baseboard_fab2_lib.baseboard_fab2(sch_1):page106_i122@mstr_discrete.cap(chips)!CAP_0402-0.22UF,16V,10%,X7R,A3A!!!F4009!B!!!!
S!P3E_CPU0_PE3_OCP_TXP<14>!C1M8!1!@baseboard_fab2_lib.baseboard_fab2(sch_1):page106_i105@mstr_discrete.cap(chips)!CAP_0402-0.22UF,16V,10%,X7R,A3A!!!F4008!A!!!!
S!P3E_OCP_CPU0_PE3_C_TXP<14>!C1M8!2!@baseboard_fab2_lib.baseboard_fab2(sch_1):page106_i105@mstr_discrete.cap(chips)!CAP_0402-0.22UF,16V,10%,X7R,A3A!!!F4008!B!!!!
S!P3E_CPU0_PE3_OCP_TXN<14>!C1M9!1!@baseboard_fab2_lib.baseboard_fab2(sch_1):page106_i114@mstr_discrete.cap(chips)!CAP_0402-0.22UF,16V,10%,X7R,A3A!!!F4007!A!!!!
S!P3E_OCP_CPU0_PE3_C_TXN<14>!C1M9!2!@baseboard_fab2_lib.baseboard_fab2(sch_1):page106_i114@mstr_discrete.cap(chips)!CAP_0402-0.22UF,16V,10%,X7R,A3A!!!F4007!B!!!!
S!P3E_CPU0_PE3_OCP_TXP<13>!C1M10!1!@baseboard_fab2_lib.baseboard_fab2(sch_1):page106_i102@mstr_discrete.cap(chips)!CAP_0402-0.22UF,16V,10%,X7R,A3A!!!F4006!A!!!!
S!P3E_OCP_CPU0_PE3_C_TXP<13>!C1M10!2!@baseboard_fab2_lib.baseboard_fab2(sch_1):page106_i102@mstr_discrete.cap(chips)!CAP_0402-0.22UF,16V,10%,X7R,A3A!!!F4006!B!!!!
S!P3E_CPU0_PE3_OCP_TXN<13>!C1M11!1!@baseboard_fab2_lib.baseboard_fab2(sch_1):page106_i117@mstr_discrete.cap(chips)!CAP_0402-0.22UF,16V,10%,X7R,A3A!!!F4005!A!!!!
S!P3E_OCP_CPU0_PE3_C_TXN<13>!C1M11!2!@baseboard_fab2_lib.baseboard_fab2(sch_1):page106_i117@mstr_discrete.cap(chips)!CAP_0402-0.22UF,16V,10%,X7R,A3A!!!F4005!B!!!!
S!P3E_CPU0_PE3_OCP_TXP<12>!C1M12!1!@baseboard_fab2_lib.baseboard_fab2(sch_1):page106_i100@mstr_discrete.cap(chips)!CAP_0402-0.22UF,16V,10%,X7R,A3A!!!F4004!A!!!!
S!P3E_OCP_CPU0_PE3_C_TXP<12>!C1M12!2!@baseboard_fab2_lib.baseboard_fab2(sch_1):page106_i100@mstr_discrete.cap(chips)!CAP_0402-0.22UF,16V,10%,X7R,A3A!!!F4004!B!!!!
S!P3E_CPU0_PE3_OCP_TXN<12>!C1M13!1!@baseboard_fab2_lib.baseboard_fab2(sch_1):page106_i111@mstr_discrete.cap(chips)!CAP_0402-0.22UF,16V,10%,X7R,A3A!!!F4003!A!!!!
S!P3E_OCP_CPU0_PE3_C_TXN<12>!C1M13!2!@baseboard_fab2_lib.baseboard_fab2(sch_1):page106_i111@mstr_discrete.cap(chips)!CAP_0402-0.22UF,16V,10%,X7R,A3A!!!F4003!B!!!!
S!P3E_CPU0_PE3_OCP_TXP<11>!C1M14!1!@baseboard_fab2_lib.baseboard_fab2(sch_1):page106_i85@mstr_discrete.cap(chips)!CAP_0402-0.22UF,16V,10%,X7R,A3A!!!F4002!A!!!!
S!P3E_OCP_CPU0_PE3_C_TXP<11>!C1M14!2!@baseboard_fab2_lib.baseboard_fab2(sch_1):page106_i85@mstr_discrete.cap(chips)!CAP_0402-0.22UF,16V,10%,X7R,A3A!!!F4002!B!!!!
S!P3E_CPU0_PE3_OCP_TXN<11>!C1M15!1!@baseboard_fab2_lib.baseboard_fab2(sch_1):page106_i95@mstr_discrete.cap(chips)!CAP_0402-0.22UF,16V,10%,X7R,A3A!!!F4001!A!!!!
S!P3E_OCP_CPU0_PE3_C_TXN<11>!C1M15!2!@baseboard_fab2_lib.baseboard_fab2(sch_1):page106_i95@mstr_discrete.cap(chips)!CAP_0402-0.22UF,16V,10%,X7R,A3A!!!F4001!B!!!!
S!P3E_CPU0_PE3_OCP_TXP<10>!C1M16!1!@baseboard_fab2_lib.baseboard_fab2(sch_1):page106_i82@mstr_discrete.cap(chips)!CAP_0402-0.22UF,16V,10%,X7R,A3A!!!F4000!A!!!!
S!P3E_OCP_CPU0_PE3_C_TXP<10>!C1M16!2!@baseboard_fab2_lib.baseboard_fab2(sch_1):page106_i82@mstr_discrete.cap(chips)!CAP_0402-0.22UF,16V,10%,X7R,A3A!!!F4000!B!!!!
S!P3E_CPU0_PE3_OCP_TXN<10>!C1M17!1!@baseboard_fab2_lib.baseboard_fab2(sch_1):page106_i92@mstr_discrete.cap(chips)!CAP_0402-0.22UF,16V,10%,X7R,A3A!!!F3999!A!!!!
S!P3E_OCP_CPU0_PE3_C_TXN<10>!C1M17!2!@baseboard_fab2_lib.baseboard_fab2(sch_1):page106_i92@mstr_discrete.cap(chips)!CAP_0402-0.22UF,16V,10%,X7R,A3A!!!F3999!B!!!!
S!P3E_CPU0_PE3_OCP_TXP<9>!C1M18!1!@baseboard_fab2_lib.baseboard_fab2(sch_1):page106_i78@mstr_discrete.cap(chips)!CAP_0402-0.22UF,16V,10%,X7R,A3A!!!F3998!A!!!!
S!P3E_OCP_CPU0_PE3_C_TXP<9>!C1M18!2!@baseboard_fab2_lib.baseboard_fab2(sch_1):page106_i78@mstr_discrete.cap(chips)!CAP_0402-0.22UF,16V,10%,X7R,A3A!!!F3998!B!!!!
S!P3E_CPU0_PE3_OCP_TXN<9>!C1M19!1!@baseboard_fab2_lib.baseboard_fab2(sch_1):page106_i90@mstr_discrete.cap(chips)!CAP_0402-0.22UF,16V,10%,X7R,A3A!!!F3997!A!!!!
S!P3E_OCP_CPU0_PE3_C_TXN<9>!C1M19!2!@baseboard_fab2_lib.baseboard_fab2(sch_1):page106_i90@mstr_discrete.cap(chips)!CAP_0402-0.22UF,16V,10%,X7R,A3A!!!F3997!B!!!!
S!P3E_CPU0_PE3_OCP_TXP<8>!C2M14!1!@baseboard_fab2_lib.baseboard_fab2(sch_1):page106_i76@mstr_discrete.cap(chips)!CAP_0402-0.22UF,16V,10%,X7R,A3A!!!F3983!A!!!!
S!P3E_OCP_CPU0_PE3_C_TXP<8>!C2M14!2!@baseboard_fab2_lib.baseboard_fab2(sch_1):page106_i76@mstr_discrete.cap(chips)!CAP_0402-0.22UF,16V,10%,X7R,A3A!!!F3983!B!!!!
S!P3E_CPU0_PE3_OCP_TXN<8>!C2M15!1!@baseboard_fab2_lib.baseboard_fab2(sch_1):page106_i86@mstr_discrete.cap(chips)!CAP_0402-0.22UF,16V,10%,X7R,A3A!!!F3982!A!!!!
S!P3E_OCP_CPU0_PE3_C_TXN<8>!C2M15!2!@baseboard_fab2_lib.baseboard_fab2(sch_1):page106_i86@mstr_discrete.cap(chips)!CAP_0402-0.22UF,16V,10%,X7R,A3A!!!F3982!B!!!!
S!P3E_CPU0_PE2_SS_TXP<7>!C7G21!1!@baseboard_fab2_lib.baseboard_fab2(sch_1):page105_i51@mstr_discrete.cap(chips)!CAP_0402-0.22UF,16V,10%,X7R,A3A!!!F3864!A!!!!
S!P3E_CPU0_PE2_SS_C_TXP<7>!C7G21!2!@baseboard_fab2_lib.baseboard_fab2(sch_1):page105_i51@mstr_discrete.cap(chips)!CAP_0402-0.22UF,16V,10%,X7R,A3A!!!F3864!B!!!!
S!P3E_CPU0_PE2_SS_TXN<7>!C7G22!1!@baseboard_fab2_lib.baseboard_fab2(sch_1):page105_i37@mstr_discrete.cap(chips)!CAP_0402-0.22UF,16V,10%,X7R,A3A!!!F3863!A!!!!
S!P3E_CPU0_PE2_SS_C_TXN<7>!C7G22!2!@baseboard_fab2_lib.baseboard_fab2(sch_1):page105_i37@mstr_discrete.cap(chips)!CAP_0402-0.22UF,16V,10%,X7R,A3A!!!F3863!B!!!!
S!P3E_CPU0_PE2_SS_TXP<6>!C7G23!1!@baseboard_fab2_lib.baseboard_fab2(sch_1):page105_i52@mstr_discrete.cap(chips)!CAP_0402-0.22UF,16V,10%,X7R,A3A!!!F3862!A!!!!
S!P3E_CPU0_PE2_SS_C_TXP<6>!C7G23!2!@baseboard_fab2_lib.baseboard_fab2(sch_1):page105_i52@mstr_discrete.cap(chips)!CAP_0402-0.22UF,16V,10%,X7R,A3A!!!F3862!B!!!!
S!P3E_CPU0_PE2_SS_TXN<6>!C7G24!1!@baseboard_fab2_lib.baseboard_fab2(sch_1):page105_i1@mstr_discrete.cap(chips)!CAP_0402-0.22UF,16V,10%,X7R,A3A!!!F3861!A!!!!
S!P3E_CPU0_PE2_SS_C_TXN<6>!C7G24!2!@baseboard_fab2_lib.baseboard_fab2(sch_1):page105_i1@mstr_discrete.cap(chips)!CAP_0402-0.22UF,16V,10%,X7R,A3A!!!F3861!B!!!!
S!P3E_CPU0_PE2_SS_TXP<5>!C7G25!1!@baseboard_fab2_lib.baseboard_fab2(sch_1):page105_i69@mstr_discrete.cap(chips)!CAP_0402-0.22UF,16V,10%,X7R,A3A!!!F3860!A!!!!
S!P3E_CPU0_PE2_SS_C_TXP<5>!C7G25!2!@baseboard_fab2_lib.baseboard_fab2(sch_1):page105_i69@mstr_discrete.cap(chips)!CAP_0402-0.22UF,16V,10%,X7R,A3A!!!F3860!B!!!!
S!P3E_CPU0_PE2_SS_TXN<5>!C7G26!1!@baseboard_fab2_lib.baseboard_fab2(sch_1):page105_i55@mstr_discrete.cap(chips)!CAP_0402-0.22UF,16V,10%,X7R,A3A!!!F3859!A!!!!
S!P3E_CPU0_PE2_SS_C_TXN<5>!C7G26!2!@baseboard_fab2_lib.baseboard_fab2(sch_1):page105_i55@mstr_discrete.cap(chips)!CAP_0402-0.22UF,16V,10%,X7R,A3A!!!F3859!B!!!!
S!P3E_CPU0_PE2_SS_TXP<4>!C8G1!1!@baseboard_fab2_lib.baseboard_fab2(sch_1):page105_i70@mstr_discrete.cap(chips)!CAP_0402-0.22UF,16V,10%,X7R,A3A!!!F3854!A!!!!
S!P3E_CPU0_PE2_SS_C_TXP<4>!C8G1!2!@baseboard_fab2_lib.baseboard_fab2(sch_1):page105_i70@mstr_discrete.cap(chips)!CAP_0402-0.22UF,16V,10%,X7R,A3A!!!F3854!B!!!!
S!P3E_CPU0_PE2_SS_TXN<4>!C8G2!1!@baseboard_fab2_lib.baseboard_fab2(sch_1):page105_i58@mstr_discrete.cap(chips)!CAP_0402-0.22UF,16V,10%,X7R,A3A!!!F3853!A!!!!
S!P3E_CPU0_PE2_SS_C_TXN<4>!C8G2!2!@baseboard_fab2_lib.baseboard_fab2(sch_1):page105_i58@mstr_discrete.cap(chips)!CAP_0402-0.22UF,16V,10%,X7R,A3A!!!F3853!B!!!!
S!P3E_CPU0_PE2_SS_TXP<3>!C8G3!1!@baseboard_fab2_lib.baseboard_fab2(sch_1):page105_i71@mstr_discrete.cap(chips)!CAP_0402-0.22UF,16V,10%,X7R,A3A!!!F3852!A!!!!
S!P3E_CPU0_PE2_SS_C_TXP<3>!C8G3!2!@baseboard_fab2_lib.baseboard_fab2(sch_1):page105_i71@mstr_discrete.cap(chips)!CAP_0402-0.22UF,16V,10%,X7R,A3A!!!F3852!B!!!!
S!P3E_CPU0_PE2_SS_TXN<3>!C8G4!1!@baseboard_fab2_lib.baseboard_fab2(sch_1):page105_i56@mstr_discrete.cap(chips)!CAP_0402-0.22UF,16V,10%,X7R,A3A!!!F3851!A!!!!
S!P3E_CPU0_PE2_SS_C_TXN<3>!C8G4!2!@baseboard_fab2_lib.baseboard_fab2(sch_1):page105_i56@mstr_discrete.cap(chips)!CAP_0402-0.22UF,16V,10%,X7R,A3A!!!F3851!B!!!!
S!P3E_CPU0_PE2_SS_TXP<2>!C8G5!1!@baseboard_fab2_lib.baseboard_fab2(sch_1):page105_i75@mstr_discrete.cap(chips)!CAP_0402-0.22UF,16V,10%,X7R,A3A!!!F3850!A!!!!
S!P3E_CPU0_PE2_SS_C_TXP<2>!C8G5!2!@baseboard_fab2_lib.baseboard_fab2(sch_1):page105_i75@mstr_discrete.cap(chips)!CAP_0402-0.22UF,16V,10%,X7R,A3A!!!F3850!B!!!!
S!P3E_CPU0_PE2_SS_TXN<2>!C8G6!1!@baseboard_fab2_lib.baseboard_fab2(sch_1):page105_i61@mstr_discrete.cap(chips)!CAP_0402-0.22UF,16V,10%,X7R,A3A!!!F3849!A!!!!
S!P3E_CPU0_PE2_SS_C_TXN<2>!C8G6!2!@baseboard_fab2_lib.baseboard_fab2(sch_1):page105_i61@mstr_discrete.cap(chips)!CAP_0402-0.22UF,16V,10%,X7R,A3A!!!F3849!B!!!!
S!P3E_CPU0_PE2_SS_TXP<1>!C8G8!1!@baseboard_fab2_lib.baseboard_fab2(sch_1):page105_i76@mstr_discrete.cap(chips)!CAP_0402-0.22UF,16V,10%,X7R,A3A!!!F3847!A!!!!
S!P3E_CPU0_PE2_SS_C_TXP<1>!C8G8!2!@baseboard_fab2_lib.baseboard_fab2(sch_1):page105_i76@mstr_discrete.cap(chips)!CAP_0402-0.22UF,16V,10%,X7R,A3A!!!F3847!B!!!!
S!P3E_CPU0_PE2_SS_TXN<1>!C8G7!1!@baseboard_fab2_lib.baseboard_fab2(sch_1):page105_i62@mstr_discrete.cap(chips)!CAP_0402-0.22UF,16V,10%,X7R,A3A!!!F3848!A!!!!
S!P3E_CPU0_PE2_SS_C_TXN<1>!C8G7!2!@baseboard_fab2_lib.baseboard_fab2(sch_1):page105_i62@mstr_discrete.cap(chips)!CAP_0402-0.22UF,16V,10%,X7R,A3A!!!F3848!B!!!!
S!P3E_CPU0_PE2_SS_TXP<0>!C8G9!1!@baseboard_fab2_lib.baseboard_fab2(sch_1):page105_i93@mstr_discrete.cap(chips)!CAP_0402-0.22UF,16V,10%,X7R,A3A!!!F3846!A!!!!
S!P3E_CPU0_PE2_SS_C_TXP<0>!C8G9!2!@baseboard_fab2_lib.baseboard_fab2(sch_1):page105_i93@mstr_discrete.cap(chips)!CAP_0402-0.22UF,16V,10%,X7R,A3A!!!F3846!B!!!!
S!P3E_CPU0_PE2_SS_TXN<0>!C8G10!1!@baseboard_fab2_lib.baseboard_fab2(sch_1):page105_i96@mstr_discrete.cap(chips)!CAP_0402-0.22UF,16V,10%,X7R,A3A!!!F3845!A!!!!
S!P3E_CPU0_PE2_SS_C_TXN<0>!C8G10!2!@baseboard_fab2_lib.baseboard_fab2(sch_1):page105_i96@mstr_discrete.cap(chips)!CAP_0402-0.22UF,16V,10%,X7R,A3A!!!F3845!B!!!!
S!P3E_CPU0_PE2_SS_TXP<15>!C7G5!1!@baseboard_fab2_lib.baseboard_fab2(sch_1):page105_i20@mstr_discrete.cap(chips)!CAP_0402-0.22UF,16V,10%,X7R,A3A!!!F3880!A!!!!
S!P3E_CPU0_PE2_SS_C_TXP<15>!C7G5!2!@baseboard_fab2_lib.baseboard_fab2(sch_1):page105_i20@mstr_discrete.cap(chips)!CAP_0402-0.22UF,16V,10%,X7R,A3A!!!F3880!B!!!!
S!P3E_CPU0_PE2_SS_TXN<14>!C7G7!1!@baseboard_fab2_lib.baseboard_fab2(sch_1):page105_i7@mstr_discrete.cap(chips)!CAP_0402-0.22UF,16V,10%,X7R,A3A!!!F3878!A!!!!
S!P3E_CPU0_PE2_SS_C_TXN<14>!C7G7!2!@baseboard_fab2_lib.baseboard_fab2(sch_1):page105_i7@mstr_discrete.cap(chips)!CAP_0402-0.22UF,16V,10%,X7R,A3A!!!F3878!B!!!!
S!P3E_CPU0_PE2_SS_TXP<13>!C7G9!1!@baseboard_fab2_lib.baseboard_fab2(sch_1):page105_i21@mstr_discrete.cap(chips)!CAP_0402-0.22UF,16V,10%,X7R,A3A!!!F3876!A!!!!
S!P3E_CPU0_PE2_SS_C_TXP<13>!C7G9!2!@baseboard_fab2_lib.baseboard_fab2(sch_1):page105_i21@mstr_discrete.cap(chips)!CAP_0402-0.22UF,16V,10%,X7R,A3A!!!F3876!B!!!!
S!P3E_CPU0_PE2_SS_TXN<13>!C7G10!1!@baseboard_fab2_lib.baseboard_fab2(sch_1):page105_i8@mstr_discrete.cap(chips)!CAP_0402-0.22UF,16V,10%,X7R,A3A!!!F3875!A!!!!
S!P3E_CPU0_PE2_SS_C_TXN<13>!C7G10!2!@baseboard_fab2_lib.baseboard_fab2(sch_1):page105_i8@mstr_discrete.cap(chips)!CAP_0402-0.22UF,16V,10%,X7R,A3A!!!F3875!B!!!!
S!P3E_CPU0_PE2_SS_TXP<12>!C7G11!1!@baseboard_fab2_lib.baseboard_fab2(sch_1):page105_i27@mstr_discrete.cap(chips)!CAP_0402-0.22UF,16V,10%,X7R,A3A!!!F3874!A!!!!
S!P3E_CPU0_PE2_SS_C_TXP<12>!C7G11!2!@baseboard_fab2_lib.baseboard_fab2(sch_1):page105_i27@mstr_discrete.cap(chips)!CAP_0402-0.22UF,16V,10%,X7R,A3A!!!F3874!B!!!!
S!P3E_CPU0_PE2_SS_TXN<12>!C7G12!1!@baseboard_fab2_lib.baseboard_fab2(sch_1):page105_i12@mstr_discrete.cap(chips)!CAP_0402-0.22UF,16V,10%,X7R,A3A!!!F3873!A!!!!
S!P3E_CPU0_PE2_SS_C_TXN<12>!C7G12!2!@baseboard_fab2_lib.baseboard_fab2(sch_1):page105_i12@mstr_discrete.cap(chips)!CAP_0402-0.22UF,16V,10%,X7R,A3A!!!F3873!B!!!!
S!P3E_CPU0_PE2_SS_TXP<11>!C7G14!1!@baseboard_fab2_lib.baseboard_fab2(sch_1):page105_i28@mstr_discrete.cap(chips)!CAP_0402-0.22UF,16V,10%,X7R,A3A!!!F3871!A!!!!
S!P3E_CPU0_PE2_SS_C_TXP<11>!C7G14!2!@baseboard_fab2_lib.baseboard_fab2(sch_1):page105_i28@mstr_discrete.cap(chips)!CAP_0402-0.22UF,16V,10%,X7R,A3A!!!F3871!B!!!!
S!P3E_CPU0_PE2_SS_TXN<11>!C7G13!1!@baseboard_fab2_lib.baseboard_fab2(sch_1):page105_i13@mstr_discrete.cap(chips)!CAP_0402-0.22UF,16V,10%,X7R,A3A!!!F3872!A!!!!
S!P3E_CPU0_PE2_SS_C_TXN<11>!C7G13!2!@baseboard_fab2_lib.baseboard_fab2(sch_1):page105_i13@mstr_discrete.cap(chips)!CAP_0402-0.22UF,16V,10%,X7R,A3A!!!F3872!B!!!!
S!P3E_CPU0_PE2_SS_TXP<10>!C7G15!1!@baseboard_fab2_lib.baseboard_fab2(sch_1):page105_i45@mstr_discrete.cap(chips)!CAP_0402-0.22UF,16V,10%,X7R,A3A!!!F3870!A!!!!
S!P3E_CPU0_PE2_SS_C_TXP<10>!C7G15!2!@baseboard_fab2_lib.baseboard_fab2(sch_1):page105_i45@mstr_discrete.cap(chips)!CAP_0402-0.22UF,16V,10%,X7R,A3A!!!F3870!B!!!!
S!P3E_CPU0_PE2_SS_TXN<10>!C7G16!1!@baseboard_fab2_lib.baseboard_fab2(sch_1):page105_i31@mstr_discrete.cap(chips)!CAP_0402-0.22UF,16V,10%,X7R,A3A!!!F3869!A!!!!
S!P3E_CPU0_PE2_SS_C_TXN<10>!C7G16!2!@baseboard_fab2_lib.baseboard_fab2(sch_1):page105_i31@mstr_discrete.cap(chips)!CAP_0402-0.22UF,16V,10%,X7R,A3A!!!F3869!B!!!!
S!P3E_CPU0_PE2_SS_TXP<9>!C7G17!1!@baseboard_fab2_lib.baseboard_fab2(sch_1):page105_i44@mstr_discrete.cap(chips)!CAP_0402-0.22UF,16V,10%,X7R,A3A!!!F3868!A!!!!
S!P3E_CPU0_PE2_SS_C_TXP<9>!C7G17!2!@baseboard_fab2_lib.baseboard_fab2(sch_1):page105_i44@mstr_discrete.cap(chips)!CAP_0402-0.22UF,16V,10%,X7R,A3A!!!F3868!B!!!!
S!P3E_CPU0_PE2_SS_TXN<9>!C7G18!1!@baseboard_fab2_lib.baseboard_fab2(sch_1):page105_i32@mstr_discrete.cap(chips)!CAP_0402-0.22UF,16V,10%,X7R,A3A!!!F3867!A!!!!
S!P3E_CPU0_PE2_SS_C_TXN<9>!C7G18!2!@baseboard_fab2_lib.baseboard_fab2(sch_1):page105_i32@mstr_discrete.cap(chips)!CAP_0402-0.22UF,16V,10%,X7R,A3A!!!F3867!B!!!!
S!P3E_CPU0_PE2_SS_TXP<8>!C7G19!1!@baseboard_fab2_lib.baseboard_fab2(sch_1):page105_i46@mstr_discrete.cap(chips)!CAP_0402-0.22UF,16V,10%,X7R,A3A!!!F3866!A!!!!
S!P3E_CPU0_PE2_SS_C_TXP<8>!C7G19!2!@baseboard_fab2_lib.baseboard_fab2(sch_1):page105_i46@mstr_discrete.cap(chips)!CAP_0402-0.22UF,16V,10%,X7R,A3A!!!F3866!B!!!!
S!P3E_CPU0_PE2_SS_TXN<8>!C7G20!1!@baseboard_fab2_lib.baseboard_fab2(sch_1):page105_i34@mstr_discrete.cap(chips)!CAP_0402-0.22UF,16V,10%,X7R,A3A!!!F3865!A!!!!
S!P3E_CPU0_PE2_SS_C_TXN<8>!C7G20!2!@baseboard_fab2_lib.baseboard_fab2(sch_1):page105_i34@mstr_discrete.cap(chips)!CAP_0402-0.22UF,16V,10%,X7R,A3A!!!F3865!B!!!!
S!P3E_CPU0_PE2_SS_TXN<15>!C7G6!1!@baseboard_fab2_lib.baseboard_fab2(sch_1):page105_i6@mstr_discrete.cap(chips)!CAP_0402-0.22UF,16V,10%,X7R,A3A!!!F3879!A!!!!
S!P3E_CPU0_PE2_SS_C_TXN<15>!C7G6!2!@baseboard_fab2_lib.baseboard_fab2(sch_1):page105_i6@mstr_discrete.cap(chips)!CAP_0402-0.22UF,16V,10%,X7R,A3A!!!F3879!B!!!!
S!P3E_CPU0_PE2_SS_TXP<14>!C7G8!1!@baseboard_fab2_lib.baseboard_fab2(sch_1):page105_i22@mstr_discrete.cap(chips)!CAP_0402-0.22UF,16V,10%,X7R,A3A!!!F3877!A!!!!
S!P3E_CPU0_PE2_SS_C_TXP<14>!C7G8!2!@baseboard_fab2_lib.baseboard_fab2(sch_1):page105_i22@mstr_discrete.cap(chips)!CAP_0402-0.22UF,16V,10%,X7R,A3A!!!F3877!B!!!!
S!P3E_CPU1_PE3_MP_C_TXP<8>!C9N17!1!@baseboard_fab2_lib.baseboard_fab2(sch_1):page182_i12@mstr_discrete.cap(chips)!CAP_0402-0.22UF,16V,10%,X7R,A3A!!!F3830!A!!!!
S!P3E_CPU1_PE3_MP_TXP<8>!C9N17!2!@baseboard_fab2_lib.baseboard_fab2(sch_1):page182_i12@mstr_discrete.cap(chips)!CAP_0402-0.22UF,16V,10%,X7R,A3A!!!F3830!B!!!!
S!P3E_CPU1_PE3_MP_C_TXP<9>!C9N12!1!@baseboard_fab2_lib.baseboard_fab2(sch_1):page182_i16@mstr_discrete.cap(chips)!CAP_0402-0.22UF,16V,10%,X7R,A3A!!!F3834!A!!!!
S!P3E_CPU1_PE3_MP_TXP<9>!C9N12!2!@baseboard_fab2_lib.baseboard_fab2(sch_1):page182_i16@mstr_discrete.cap(chips)!CAP_0402-0.22UF,16V,10%,X7R,A3A!!!F3834!B!!!!
S!P3E_CPU1_PE3_MP_C_TXN<10>!C9N2!1!@baseboard_fab2_lib.baseboard_fab2(sch_1):page182_i15@mstr_discrete.cap(chips)!CAP_0402-0.22UF,16V,10%,X7R,A3A!!!F3843!A!!!!
S!P3E_CPU1_PE3_MP_TXN<10>!C9N2!2!@baseboard_fab2_lib.baseboard_fab2(sch_1):page182_i15@mstr_discrete.cap(chips)!CAP_0402-0.22UF,16V,10%,X7R,A3A!!!F3843!B!!!!
S!P3E_CPU1_PE3_MP_C_TXP<14>!C9N10!1!@baseboard_fab2_lib.baseboard_fab2(sch_1):page182_i53@mstr_discrete.cap(chips)!CAP_0402-0.22UF,16V,10%,X7R,A3A!!!F3835!A!!!!
S!P3E_CPU1_PE3_MP_TXP<14>!C9N10!2!@baseboard_fab2_lib.baseboard_fab2(sch_1):page182_i53@mstr_discrete.cap(chips)!CAP_0402-0.22UF,16V,10%,X7R,A3A!!!F3835!B!!!!
S!P3E_CPU1_PE3_MP_C_TXP<15>!C9N7!1!@baseboard_fab2_lib.baseboard_fab2(sch_1):page182_i54@mstr_discrete.cap(chips)!CAP_0402-0.22UF,16V,10%,X7R,A3A!!!F3838!A!!!!
S!P3E_CPU1_PE3_MP_TXP<15>!C9N7!2!@baseboard_fab2_lib.baseboard_fab2(sch_1):page182_i54@mstr_discrete.cap(chips)!CAP_0402-0.22UF,16V,10%,X7R,A3A!!!F3838!B!!!!
S!P3E_CPU1_PE3_MP_C_TXP<11>!C9N4!1!@baseboard_fab2_lib.baseboard_fab2(sch_1):page182_i55@mstr_discrete.cap(chips)!CAP_0402-0.22UF,16V,10%,X7R,A3A!!!F3841!A!!!!
S!P3E_CPU1_PE3_MP_TXP<11>!C9N4!2!@baseboard_fab2_lib.baseboard_fab2(sch_1):page182_i55@mstr_discrete.cap(chips)!CAP_0402-0.22UF,16V,10%,X7R,A3A!!!F3841!B!!!!
S!P3E_CPU1_PE3_MP_C_TXP<12>!C9N14!1!@baseboard_fab2_lib.baseboard_fab2(sch_1):page182_i56@mstr_discrete.cap(chips)!CAP_0402-0.22UF,16V,10%,X7R,A3A!!!F3833!A!!!!
S!P3E_CPU1_PE3_MP_TXP<12>!C9N14!2!@baseboard_fab2_lib.baseboard_fab2(sch_1):page182_i56@mstr_discrete.cap(chips)!CAP_0402-0.22UF,16V,10%,X7R,A3A!!!F3833!B!!!!
S!P3E_CPU1_PE3_MP_C_TXP<13>!C9N5!1!@baseboard_fab2_lib.baseboard_fab2(sch_1):page182_i83@mstr_discrete.cap(chips)!CAP_0402-0.22UF,16V,10%,X7R,A3A!!!F3840!A!!!!
S!P3E_CPU1_PE3_MP_TXP<13>!C9N5!2!@baseboard_fab2_lib.baseboard_fab2(sch_1):page182_i83@mstr_discrete.cap(chips)!CAP_0402-0.22UF,16V,10%,X7R,A3A!!!F3840!B!!!!
S!P3E_CPU1_PE3_MP_C_TXN<14>!C9N8!1!@baseboard_fab2_lib.baseboard_fab2(sch_1):page182_i50@mstr_discrete.cap(chips)!CAP_0402-0.22UF,16V,10%,X7R,A3A!!!F3837!A!!!!
S!P3E_CPU1_PE3_MP_TXN<14>!C9N8!2!@baseboard_fab2_lib.baseboard_fab2(sch_1):page182_i50@mstr_discrete.cap(chips)!CAP_0402-0.22UF,16V,10%,X7R,A3A!!!F3837!B!!!!
S!P3E_CPU1_PE3_MP_C_TXN<15>!C9N9!1!@baseboard_fab2_lib.baseboard_fab2(sch_1):page182_i49@mstr_discrete.cap(chips)!CAP_0402-0.22UF,16V,10%,X7R,A3A!!!F3836!A!!!!
S!P3E_CPU1_PE3_MP_TXN<15>!C9N9!2!@baseboard_fab2_lib.baseboard_fab2(sch_1):page182_i49@mstr_discrete.cap(chips)!CAP_0402-0.22UF,16V,10%,X7R,A3A!!!F3836!B!!!!
S!P3E_CPU1_PE3_MP_C_TXN<11>!C9N3!1!@baseboard_fab2_lib.baseboard_fab2(sch_1):page182_i51@mstr_discrete.cap(chips)!CAP_0402-0.22UF,16V,10%,X7R,A3A!!!F3842!A!!!!
S!P3E_CPU1_PE3_MP_TXN<11>!C9N3!2!@baseboard_fab2_lib.baseboard_fab2(sch_1):page182_i51@mstr_discrete.cap(chips)!CAP_0402-0.22UF,16V,10%,X7R,A3A!!!F3842!B!!!!
S!P3E_CPU1_PE3_MP_C_TXN<12>!C9N16!1!@baseboard_fab2_lib.baseboard_fab2(sch_1):page182_i52@mstr_discrete.cap(chips)!CAP_0402-0.22UF,16V,10%,X7R,A3A!!!F3831!A!!!!
S!P3E_CPU1_PE3_MP_TXN<12>!C9N16!2!@baseboard_fab2_lib.baseboard_fab2(sch_1):page182_i52@mstr_discrete.cap(chips)!CAP_0402-0.22UF,16V,10%,X7R,A3A!!!F3831!B!!!!
S!P3E_CPU1_PE3_MP_C_TXN<13>!C9N6!1!@baseboard_fab2_lib.baseboard_fab2(sch_1):page182_i81@mstr_discrete.cap(chips)!CAP_0402-0.22UF,16V,10%,X7R,A3A!!!F3839!A!!!!
S!P3E_CPU1_PE3_MP_TXN<13>!C9N6!2!@baseboard_fab2_lib.baseboard_fab2(sch_1):page182_i81@mstr_discrete.cap(chips)!CAP_0402-0.22UF,16V,10%,X7R,A3A!!!F3839!B!!!!
S!P3E_CPU1_PE3_MP_C_TXN<8>!C9N18!1!@baseboard_fab2_lib.baseboard_fab2(sch_1):page182_i9@mstr_discrete.cap(chips)!CAP_0402-0.22UF,16V,10%,X7R,A3A!!!F3829!A!!!!
S!P3E_CPU1_PE3_MP_TXN<8>!C9N18!2!@baseboard_fab2_lib.baseboard_fab2(sch_1):page182_i9@mstr_discrete.cap(chips)!CAP_0402-0.22UF,16V,10%,X7R,A3A!!!F3829!B!!!!
S!P3E_CPU1_PE3_MP_C_TXN<9>!C9N15!1!@baseboard_fab2_lib.baseboard_fab2(sch_1):page182_i13@mstr_discrete.cap(chips)!CAP_0402-0.22UF,16V,10%,X7R,A3A!!!F3832!A!!!!
S!P3E_CPU1_PE3_MP_TXN<9>!C9N15!2!@baseboard_fab2_lib.baseboard_fab2(sch_1):page182_i13@mstr_discrete.cap(chips)!CAP_0402-0.22UF,16V,10%,X7R,A3A!!!F3832!B!!!!
S!P3E_CPU1_PE3_MP_C_TXP<10>!C9N1!1!@baseboard_fab2_lib.baseboard_fab2(sch_1):page182_i14@mstr_discrete.cap(chips)!CAP_0402-0.22UF,16V,10%,X7R,A3A!!!F3844!A!!!!
S!P3E_CPU1_PE3_MP_TXP<10>!C9N1!2!@baseboard_fab2_lib.baseboard_fab2(sch_1):page182_i14@mstr_discrete.cap(chips)!CAP_0402-0.22UF,16V,10%,X7R,A3A!!!F3844!B!!!!
S!P5V_STBY!C7A41!1!@baseboard_fab2_lib.baseboard_fab2(sch_1):page236_i39@mstr_discrete.cap(chips)!CAP_0402-0.22UF,16V,10%,X7R,A3A!!!F3984!A!!!!
S!GND!C7A41!2!@baseboard_fab2_lib.baseboard_fab2(sch_1):page236_i39@mstr_discrete.cap(chips)!CAP_0402-0.22UF,16V,10%,X7R,A3A!!!F3984!B!!!!
S!P5V_STBY!C7A8!1!@baseboard_fab2_lib.baseboard_fab2(sch_1):page236_i16@mstr_discrete.cap(chips)!CAP_0402-0.22UF,16V,10%,X7R,A3A!!!F3892!A!!!!
S!GND!C7A8!2!@baseboard_fab2_lib.baseboard_fab2(sch_1):page236_i16@mstr_discrete.cap(chips)!CAP_0402-0.22UF,16V,10%,X7R,A3A!!!F3892!B!!!!
S!P5V_STBY!C4E23!1!@baseboard_fab2_lib.baseboard_fab2(sch_1):page214_i73@mstr_discrete.cap(chips)!CAP_0402-0.22UF,16V,10%,X7R,A3A!!!F3909!A!!!!
S!GND!C4E23!2!@baseboard_fab2_lib.baseboard_fab2(sch_1):page214_i73@mstr_discrete.cap(chips)!CAP_0402-0.22UF,16V,10%,X7R,A3A!!!F3909!B!!!!
S!P5V_STBY!C4D5!1!@baseboard_fab2_lib.baseboard_fab2(sch_1):page203_i48@mstr_discrete.cap(chips)!CAP_0402-0.22UF,16V,10%,X7R,A3A!!!F3913!A!!!!
S!GND!C4D5!2!@baseboard_fab2_lib.baseboard_fab2(sch_1):page203_i48@mstr_discrete.cap(chips)!CAP_0402-0.22UF,16V,10%,X7R,A3A!!!F3913!B!!!!
S!P5V_STBY!C4D13!1!@baseboard_fab2_lib.baseboard_fab2(sch_1):page203_i40@mstr_discrete.cap(chips)!CAP_0402-0.22UF,16V,10%,X7R,A3A!!!F3912!A!!!!
S!GND!C4D13!2!@baseboard_fab2_lib.baseboard_fab2(sch_1):page203_i40@mstr_discrete.cap(chips)!CAP_0402-0.22UF,16V,10%,X7R,A3A!!!F3912!B!!!!
S!P3E_PCH_M2_TX_C_DP<3>!C2T20!1!@baseboard_fab2_lib.baseboard_fab2(sch_1):page185_i66@mstr_discrete.cap(chips)!CAP_0402-0.22UF,16V,10%,X7R,A3A!!!F3973!A!!!!
S!P3E_PCH_M2_TX_DP<3>!C2T20!2!@baseboard_fab2_lib.baseboard_fab2(sch_1):page185_i66@mstr_discrete.cap(chips)!CAP_0402-0.22UF,16V,10%,X7R,A3A!!!F3973!B!!!!
S!P3E_PCH_M2_TX_C_DN<3>!C2T23!1!@baseboard_fab2_lib.baseboard_fab2(sch_1):page185_i67@mstr_discrete.cap(chips)!CAP_0402-0.22UF,16V,10%,X7R,A3A!!!F3972!A!!!!
S!P3E_PCH_M2_TX_DN<3>!C2T23!2!@baseboard_fab2_lib.baseboard_fab2(sch_1):page185_i67@mstr_discrete.cap(chips)!CAP_0402-0.22UF,16V,10%,X7R,A3A!!!F3972!B!!!!
S!P3E_PCH_M2_TX_C_DP<2>!C2T13!1!@baseboard_fab2_lib.baseboard_fab2(sch_1):page185_i64@mstr_discrete.cap(chips)!CAP_0402-0.22UF,16V,10%,X7R,A3A!!!F3975!A!!!!
S!P3E_PCH_M2_TX_DP<2>!C2T13!2!@baseboard_fab2_lib.baseboard_fab2(sch_1):page185_i64@mstr_discrete.cap(chips)!CAP_0402-0.22UF,16V,10%,X7R,A3A!!!F3975!B!!!!
S!P3E_PCH_M2_TX_C_DN<2>!C2T14!1!@baseboard_fab2_lib.baseboard_fab2(sch_1):page185_i65@mstr_discrete.cap(chips)!CAP_0402-0.22UF,16V,10%,X7R,A3A!!!F3974!A!!!!
S!P3E_PCH_M2_TX_DN<2>!C2T14!2!@baseboard_fab2_lib.baseboard_fab2(sch_1):page185_i65@mstr_discrete.cap(chips)!CAP_0402-0.22UF,16V,10%,X7R,A3A!!!F3974!B!!!!
S!P3E_PCH_M2_TX_C_DP<1>!C2T10!1!@baseboard_fab2_lib.baseboard_fab2(sch_1):page185_i63@mstr_discrete.cap(chips)!CAP_0402-0.22UF,16V,10%,X7R,A3A!!!F3977!A!!!!
S!P3E_PCH_M2_TX_DP<1>!C2T10!2!@baseboard_fab2_lib.baseboard_fab2(sch_1):page185_i63@mstr_discrete.cap(chips)!CAP_0402-0.22UF,16V,10%,X7R,A3A!!!F3977!B!!!!
S!P3E_PCH_M2_TX_C_DN<1>!C2T11!1!@baseboard_fab2_lib.baseboard_fab2(sch_1):page185_i62@mstr_discrete.cap(chips)!CAP_0402-0.22UF,16V,10%,X7R,A3A!!!F3976!A!!!!
S!P3E_PCH_M2_TX_DN<1>!C2T11!2!@baseboard_fab2_lib.baseboard_fab2(sch_1):page185_i62@mstr_discrete.cap(chips)!CAP_0402-0.22UF,16V,10%,X7R,A3A!!!F3976!B!!!!
S!DMI_CPU0_PCH_TX_DP<3>!C7B25!1!@baseboard_fab2_lib.baseboard_fab2(sch_1):page129_i35@mstr_discrete.cap(chips)!CAP_0402-0.22UF,16V,10%,X7R,A3A!!!F3889!A!!!!
S!DMI_CPU0_PCH_TX_C_DP<3>!C7B25!2!@baseboard_fab2_lib.baseboard_fab2(sch_1):page129_i35@mstr_discrete.cap(chips)!CAP_0402-0.22UF,16V,10%,X7R,A3A!!!F3889!B!!!!
S!DMI_CPU0_PCH_TX_DP<1>!C7B28!1!@baseboard_fab2_lib.baseboard_fab2(sch_1):page129_i70@mstr_discrete.cap(chips)!CAP_0402-0.22UF,16V,10%,X7R,A3A!!!F3886!A!!!!
S!DMI_CPU0_PCH_TX_C_DP<1>!C7B28!2!@baseboard_fab2_lib.baseboard_fab2(sch_1):page129_i70@mstr_discrete.cap(chips)!CAP_0402-0.22UF,16V,10%,X7R,A3A!!!F3886!B!!!!
S!DMI_CPU0_PCH_RX_DP<3>!C3N8!1!@baseboard_fab2_lib.baseboard_fab2(sch_1):page129_i75@mstr_discrete.cap(chips)!CAP_0402-0.22UF,16V,10%,X7R,A3A!!!F3934!A!!!!
S!DMI_CPU0_PCH_RX_C_DP<3>!C3N8!2!@baseboard_fab2_lib.baseboard_fab2(sch_1):page129_i75@mstr_discrete.cap(chips)!CAP_0402-0.22UF,16V,10%,X7R,A3A!!!F3934!B!!!!
S!DMI_CPU0_PCH_RX_DP<1>!C3M37!1!@baseboard_fab2_lib.baseboard_fab2(sch_1):page129_i73@mstr_discrete.cap(chips)!CAP_0402-0.22UF,16V,10%,X7R,A3A!!!F3939!A!!!!
S!DMI_CPU0_PCH_RX_C_DP<1>!C3M37!2!@baseboard_fab2_lib.baseboard_fab2(sch_1):page129_i73@mstr_discrete.cap(chips)!CAP_0402-0.22UF,16V,10%,X7R,A3A!!!F3939!B!!!!
S!DMI_CPU0_PCH_TX_DP<2>!C7B27!1!@baseboard_fab2_lib.baseboard_fab2(sch_1):page129_i69@mstr_discrete.cap(chips)!CAP_0402-0.22UF,16V,10%,X7R,A3A!!!F3887!A!!!!
S!DMI_CPU0_PCH_TX_C_DP<2>!C7B27!2!@baseboard_fab2_lib.baseboard_fab2(sch_1):page129_i69@mstr_discrete.cap(chips)!CAP_0402-0.22UF,16V,10%,X7R,A3A!!!F3887!B!!!!
S!DMI_CPU0_PCH_TX_DP<0>!C7C2!1!@baseboard_fab2_lib.baseboard_fab2(sch_1):page129_i71@mstr_discrete.cap(chips)!CAP_0402-0.22UF,16V,10%,X7R,A3A!!!F3883!A!!!!
S!DMI_CPU0_PCH_TX_C_DP<0>!C7C2!2!@baseboard_fab2_lib.baseboard_fab2(sch_1):page129_i71@mstr_discrete.cap(chips)!CAP_0402-0.22UF,16V,10%,X7R,A3A!!!F3883!B!!!!
S!DMI_CPU0_PCH_RX_DP<2>!C3N9!1!@baseboard_fab2_lib.baseboard_fab2(sch_1):page129_i74@mstr_discrete.cap(chips)!CAP_0402-0.22UF,16V,10%,X7R,A3A!!!F3933!A!!!!
S!DMI_CPU0_PCH_RX_C_DP<2>!C3N9!2!@baseboard_fab2_lib.baseboard_fab2(sch_1):page129_i74@mstr_discrete.cap(chips)!CAP_0402-0.22UF,16V,10%,X7R,A3A!!!F3933!B!!!!
S!DMI_CPU0_PCH_RX_DP<0>!C3M40!1!@baseboard_fab2_lib.baseboard_fab2(sch_1):page129_i72@mstr_discrete.cap(chips)!CAP_0402-0.22UF,16V,10%,X7R,A3A!!!F3938!A!!!!
S!DMI_CPU0_PCH_RX_C_DP<0>!C3M40!2!@baseboard_fab2_lib.baseboard_fab2(sch_1):page129_i72@mstr_discrete.cap(chips)!CAP_0402-0.22UF,16V,10%,X7R,A3A!!!F3938!B!!!!
S!DMI_CPU0_PCH_TX_DN<3>!C7B26!1!@baseboard_fab2_lib.baseboard_fab2(sch_1):page129_i79@mstr_discrete.cap(chips)!CAP_0402-0.22UF,16V,10%,X7R,A3A!!!F3888!A!!!!
S!DMI_CPU0_PCH_TX_C_DN<3>!C7B26!2!@baseboard_fab2_lib.baseboard_fab2(sch_1):page129_i79@mstr_discrete.cap(chips)!CAP_0402-0.22UF,16V,10%,X7R,A3A!!!F3888!B!!!!
S!DMI_CPU0_PCH_TX_DN<1>!C7C1!1!@baseboard_fab2_lib.baseboard_fab2(sch_1):page129_i77@mstr_discrete.cap(chips)!CAP_0402-0.22UF,16V,10%,X7R,A3A!!!F3884!A!!!!
S!DMI_CPU0_PCH_TX_C_DN<1>!C7C1!2!@baseboard_fab2_lib.baseboard_fab2(sch_1):page129_i77@mstr_discrete.cap(chips)!CAP_0402-0.22UF,16V,10%,X7R,A3A!!!F3884!B!!!!
S!DMI_CPU0_PCH_RX_DN<3>!C3N13!1!@baseboard_fab2_lib.baseboard_fab2(sch_1):page129_i83@mstr_discrete.cap(chips)!CAP_0402-0.22UF,16V,10%,X7R,A3A!!!F3932!A!!!!
S!DMI_CPU0_PCH_RX_C_DN<3>!C3N13!2!@baseboard_fab2_lib.baseboard_fab2(sch_1):page129_i83@mstr_discrete.cap(chips)!CAP_0402-0.22UF,16V,10%,X7R,A3A!!!F3932!B!!!!
S!DMI_CPU0_PCH_RX_DN<1>!C3M41!1!@baseboard_fab2_lib.baseboard_fab2(sch_1):page129_i81@mstr_discrete.cap(chips)!CAP_0402-0.22UF,16V,10%,X7R,A3A!!!F3937!A!!!!
S!DMI_CPU0_PCH_RX_C_DN<1>!C3M41!2!@baseboard_fab2_lib.baseboard_fab2(sch_1):page129_i81@mstr_discrete.cap(chips)!CAP_0402-0.22UF,16V,10%,X7R,A3A!!!F3937!B!!!!
S!DMI_CPU0_PCH_TX_DN<2>!C7B29!1!@baseboard_fab2_lib.baseboard_fab2(sch_1):page129_i78@mstr_discrete.cap(chips)!CAP_0402-0.22UF,16V,10%,X7R,A3A!!!F3885!A!!!!
S!DMI_CPU0_PCH_TX_C_DN<2>!C7B29!2!@baseboard_fab2_lib.baseboard_fab2(sch_1):page129_i78@mstr_discrete.cap(chips)!CAP_0402-0.22UF,16V,10%,X7R,A3A!!!F3885!B!!!!
S!DMI_CPU0_PCH_TX_DN<0>!C7C3!1!@baseboard_fab2_lib.baseboard_fab2(sch_1):page129_i76@mstr_discrete.cap(chips)!CAP_0402-0.22UF,16V,10%,X7R,A3A!!!F3882!A!!!!
S!DMI_CPU0_PCH_TX_C_DN<0>!C7C3!2!@baseboard_fab2_lib.baseboard_fab2(sch_1):page129_i76@mstr_discrete.cap(chips)!CAP_0402-0.22UF,16V,10%,X7R,A3A!!!F3882!B!!!!
S!DMI_CPU0_PCH_RX_DN<2>!C3M45!1!@baseboard_fab2_lib.baseboard_fab2(sch_1):page129_i82@mstr_discrete.cap(chips)!CAP_0402-0.22UF,16V,10%,X7R,A3A!!!F3935!A!!!!
S!DMI_CPU0_PCH_RX_C_DN<2>!C3M45!2!@baseboard_fab2_lib.baseboard_fab2(sch_1):page129_i82@mstr_discrete.cap(chips)!CAP_0402-0.22UF,16V,10%,X7R,A3A!!!F3935!B!!!!
S!DMI_CPU0_PCH_RX_DN<0>!C3M44!1!@baseboard_fab2_lib.baseboard_fab2(sch_1):page129_i80@mstr_discrete.cap(chips)!CAP_0402-0.22UF,16V,10%,X7R,A3A!!!F3936!A!!!!
S!DMI_CPU0_PCH_RX_C_DN<0>!C3M44!2!@baseboard_fab2_lib.baseboard_fab2(sch_1):page129_i80@mstr_discrete.cap(chips)!CAP_0402-0.22UF,16V,10%,X7R,A3A!!!F3936!B!!!!
S!P5V_STBY!C4E27!1!@baseboard_fab2_lib.baseboard_fab2(sch_1):page202_i24@mstr_discrete.cap(chips)!CAP_0402-0.22UF,16V,10%,X7R,A3A!!!F3911!A!!!!
S!GND!C4E27!2!@baseboard_fab2_lib.baseboard_fab2(sch_1):page202_i24@mstr_discrete.cap(chips)!CAP_0402-0.22UF,16V,10%,X7R,A3A!!!F3911!B!!!!
S!P5V_STBY!C4E5!1!@baseboard_fab2_lib.baseboard_fab2(sch_1):page202_i18@mstr_discrete.cap(chips)!CAP_0402-0.22UF,16V,10%,X7R,A3A!!!F3910!A!!!!
S!GND!C4E5!2!@baseboard_fab2_lib.baseboard_fab2(sch_1):page202_i18@mstr_discrete.cap(chips)!CAP_0402-0.22UF,16V,10%,X7R,A3A!!!F3910!B!!!!
S!P5V_STBY!C4D47!1!@baseboard_fab2_lib.baseboard_fab2(sch_1):page204_i18@mstr_discrete.cap(chips)!CAP_0402-0.22UF,16V,10%,X7R,A3A!!!F3914!A!!!!
S!GND!C4D47!2!@baseboard_fab2_lib.baseboard_fab2(sch_1):page204_i18@mstr_discrete.cap(chips)!CAP_0402-0.22UF,16V,10%,X7R,A3A!!!F3914!B!!!!
S!P5V_STBY!C4C5!1!@baseboard_fab2_lib.baseboard_fab2(sch_1):page205_i16@mstr_discrete.cap(chips)!CAP_0402-0.22UF,16V,10%,X7R,A3A!!!F3915!A!!!!
S!GND!C4C5!2!@baseboard_fab2_lib.baseboard_fab2(sch_1):page205_i16@mstr_discrete.cap(chips)!CAP_0402-0.22UF,16V,10%,X7R,A3A!!!F3915!B!!!!
S!P5V_STBY!C7G34!1!@baseboard_fab2_lib.baseboard_fab2(sch_1):page216_i54@mstr_discrete.cap(chips)!CAP_0402-0.22UF,16V,10%,X7R,A3A!!!F3858!A!!!!
S!GND!C7G34!2!@baseboard_fab2_lib.baseboard_fab2(sch_1):page216_i54@mstr_discrete.cap(chips)!CAP_0402-0.22UF,16V,10%,X7R,A3A!!!F3858!B!!!!
S!P5V_STBY!C7G41!1!@baseboard_fab2_lib.baseboard_fab2(sch_1):page216_i72@mstr_discrete.cap(chips)!CAP_0402-0.22UF,16V,10%,X7R,A3A!!!F3857!A!!!!
S!GND!C7G41!2!@baseboard_fab2_lib.baseboard_fab2(sch_1):page216_i72@mstr_discrete.cap(chips)!CAP_0402-0.22UF,16V,10%,X7R,A3A!!!F3857!B!!!!
S!P5V_STBY!C7A17!1!@baseboard_fab2_lib.baseboard_fab2(sch_1):page219_i54@mstr_discrete.cap(chips)!CAP_0402-0.22UF,16V,10%,X7R,A3A!!!F3891!A!!!!
S!GND!C7A17!2!@baseboard_fab2_lib.baseboard_fab2(sch_1):page219_i54@mstr_discrete.cap(chips)!CAP_0402-0.22UF,16V,10%,X7R,A3A!!!F3891!B!!!!
S!P5V_STBY!C7A25!1!@baseboard_fab2_lib.baseboard_fab2(sch_1):page219_i72@mstr_discrete.cap(chips)!CAP_0402-0.22UF,16V,10%,X7R,A3A!!!F3890!A!!!!
S!GND!C7A25!2!@baseboard_fab2_lib.baseboard_fab2(sch_1):page219_i72@mstr_discrete.cap(chips)!CAP_0402-0.22UF,16V,10%,X7R,A3A!!!F3890!B!!!!
S!P5V_STBY!C1B21!1!@baseboard_fab2_lib.baseboard_fab2(sch_1):page227_i54@mstr_discrete.cap(chips)!CAP_0402-0.22UF,16V,10%,X7R,A3A!!!F4036!A!!!!
S!GND!C1B21!2!@baseboard_fab2_lib.baseboard_fab2(sch_1):page227_i54@mstr_discrete.cap(chips)!CAP_0402-0.22UF,16V,10%,X7R,A3A!!!F4036!B!!!!
S!P5V_STBY!C1A13!1!@baseboard_fab2_lib.baseboard_fab2(sch_1):page227_i72@mstr_discrete.cap(chips)!CAP_0402-0.22UF,16V,10%,X7R,A3A!!!F4035!A!!!!
S!GND!C1A13!2!@baseboard_fab2_lib.baseboard_fab2(sch_1):page227_i72@mstr_discrete.cap(chips)!CAP_0402-0.22UF,16V,10%,X7R,A3A!!!F4035!B!!!!
S!P5V_STBY!C1G5!1!@baseboard_fab2_lib.baseboard_fab2(sch_1):page224_i54@mstr_discrete.cap(chips)!CAP_0402-0.22UF,16V,10%,X7R,A3A!!!F4011!A!!!!
S!GND!C1G5!2!@baseboard_fab2_lib.baseboard_fab2(sch_1):page224_i54@mstr_discrete.cap(chips)!CAP_0402-0.22UF,16V,10%,X7R,A3A!!!F4011!B!!!!
S!P5V_STBY!C1G29!1!@baseboard_fab2_lib.baseboard_fab2(sch_1):page224_i72@mstr_discrete.cap(chips)!CAP_0402-0.22UF,16V,10%,X7R,A3A!!!F4012!A!!!!
S!GND!C1G29!2!@baseboard_fab2_lib.baseboard_fab2(sch_1):page224_i72@mstr_discrete.cap(chips)!CAP_0402-0.22UF,16V,10%,X7R,A3A!!!F4012!B!!!!
S!P5V_STBY!C1E25!1!@baseboard_fab2_lib.baseboard_fab2(sch_1):page207_i36@mstr_discrete.cap(chips)!CAP_0402-0.22UF,16V,10%,X7R,A3A!!!F4030!A!!!!
S!GND!C1E25!2!@baseboard_fab2_lib.baseboard_fab2(sch_1):page207_i36@mstr_discrete.cap(chips)!CAP_0402-0.22UF,16V,10%,X7R,A3A!!!F4030!B!!!!
S!P5V_STBY!C1E7!1!@baseboard_fab2_lib.baseboard_fab2(sch_1):page207_i28@mstr_discrete.cap(chips)!CAP_0402-0.22UF,16V,10%,X7R,A3A!!!F4029!A!!!!
S!GND!C1E7!2!@baseboard_fab2_lib.baseboard_fab2(sch_1):page207_i28@mstr_discrete.cap(chips)!CAP_0402-0.22UF,16V,10%,X7R,A3A!!!F4029!B!!!!
S!P5V_STBY!C1D16!1!@baseboard_fab2_lib.baseboard_fab2(sch_1):page208_i38@mstr_discrete.cap(chips)!CAP_0402-0.22UF,16V,10%,X7R,A3A!!!F4031!A!!!!
S!GND!C1D16!2!@baseboard_fab2_lib.baseboard_fab2(sch_1):page208_i38@mstr_discrete.cap(chips)!CAP_0402-0.22UF,16V,10%,X7R,A3A!!!F4031!B!!!!
S!P5V_STBY!C1D6!1!@baseboard_fab2_lib.baseboard_fab2(sch_1):page208_i46@mstr_discrete.cap(chips)!CAP_0402-0.22UF,16V,10%,X7R,A3A!!!F4032!A!!!!
S!GND!C1D6!2!@baseboard_fab2_lib.baseboard_fab2(sch_1):page208_i46@mstr_discrete.cap(chips)!CAP_0402-0.22UF,16V,10%,X7R,A3A!!!F4032!B!!!!
S!P5V_STBY!C1C4!1!@baseboard_fab2_lib.baseboard_fab2(sch_1):page210_i22@mstr_discrete.cap(chips)!CAP_0402-0.22UF,16V,10%,X7R,A3A!!!F4034!A!!!!
S!GND!C1C4!2!@baseboard_fab2_lib.baseboard_fab2(sch_1):page210_i22@mstr_discrete.cap(chips)!CAP_0402-0.22UF,16V,10%,X7R,A3A!!!F4034!B!!!!
S!P3E_CPU1_PE3_MP_C_TXN<7>!C1F3!1!@baseboard_fab2_lib.baseboard_fab2(sch_1):page181_i167@mstr_discrete.cap(chips)!CAP_0402-0.22UF,16V,10%,X7R,A3A!!!F4027!A!!!!
S!P3E_CPU1_PE3_MP_TXN<7>!C1F3!2!@baseboard_fab2_lib.baseboard_fab2(sch_1):page181_i167@mstr_discrete.cap(chips)!CAP_0402-0.22UF,16V,10%,X7R,A3A!!!F4027!B!!!!
S!P3E_CPU1_PE3_MP_C_TXP<3>!C1F12!1!@baseboard_fab2_lib.baseboard_fab2(sch_1):page181_i168@mstr_discrete.cap(chips)!CAP_0402-0.22UF,16V,10%,X7R,A3A!!!F4020!A!!!!
S!P3E_CPU1_PE3_MP_TXP<3>!C1F12!2!@baseboard_fab2_lib.baseboard_fab2(sch_1):page181_i168@mstr_discrete.cap(chips)!CAP_0402-0.22UF,16V,10%,X7R,A3A!!!F4020!B!!!!
S!P3E_CPU1_PE3_MP_C_TXP<4>!C1F11!1!@baseboard_fab2_lib.baseboard_fab2(sch_1):page181_i169@mstr_discrete.cap(chips)!CAP_0402-0.22UF,16V,10%,X7R,A3A!!!F4021!A!!!!
S!P3E_CPU1_PE3_MP_TXP<4>!C1F11!2!@baseboard_fab2_lib.baseboard_fab2(sch_1):page181_i169@mstr_discrete.cap(chips)!CAP_0402-0.22UF,16V,10%,X7R,A3A!!!F4021!B!!!!
S!P3E_CPU1_PE3_MP_C_TXN<5>!C1F8!1!@baseboard_fab2_lib.baseboard_fab2(sch_1):page181_i170@mstr_discrete.cap(chips)!CAP_0402-0.22UF,16V,10%,X7R,A3A!!!F4023!A!!!!
S!P3E_CPU1_PE3_MP_TXN<5>!C1F8!2!@baseboard_fab2_lib.baseboard_fab2(sch_1):page181_i170@mstr_discrete.cap(chips)!CAP_0402-0.22UF,16V,10%,X7R,A3A!!!F4023!B!!!!
S!P3E_CPU1_PE3_MP_C_TXP<0>!C1F18!1!@baseboard_fab2_lib.baseboard_fab2(sch_1):page181_i171@mstr_discrete.cap(chips)!CAP_0402-0.22UF,16V,10%,X7R,A3A!!!F4014!A!!!!
S!P3E_CPU1_PE3_MP_TXP<0>!C1F18!2!@baseboard_fab2_lib.baseboard_fab2(sch_1):page181_i171@mstr_discrete.cap(chips)!CAP_0402-0.22UF,16V,10%,X7R,A3A!!!F4014!B!!!!
S!P3E_CPU1_PE3_MP_C_TXP<1>!C1F17!1!@baseboard_fab2_lib.baseboard_fab2(sch_1):page181_i173@mstr_discrete.cap(chips)!CAP_0402-0.22UF,16V,10%,X7R,A3A!!!F4015!A!!!!
S!P3E_CPU1_PE3_MP_TXP<1>!C1F17!2!@baseboard_fab2_lib.baseboard_fab2(sch_1):page181_i173@mstr_discrete.cap(chips)!CAP_0402-0.22UF,16V,10%,X7R,A3A!!!F4015!B!!!!
S!P3E_CPU1_PE3_MP_C_TXP<2>!C1F14!1!@baseboard_fab2_lib.baseboard_fab2(sch_1):page181_i175@mstr_discrete.cap(chips)!CAP_0402-0.22UF,16V,10%,X7R,A3A!!!F4018!A!!!!
S!P3E_CPU1_PE3_MP_TXP<2>!C1F14!2!@baseboard_fab2_lib.baseboard_fab2(sch_1):page181_i175@mstr_discrete.cap(chips)!CAP_0402-0.22UF,16V,10%,X7R,A3A!!!F4018!B!!!!
S!P3E_CPU1_PE3_MP_C_TXP<6>!C1F5!1!@baseboard_fab2_lib.baseboard_fab2(sch_1):page181_i161@mstr_discrete.cap(chips)!CAP_0402-0.22UF,16V,10%,X7R,A3A!!!F4025!A!!!!
S!P3E_CPU1_PE3_MP_TXP<6>!C1F5!2!@baseboard_fab2_lib.baseboard_fab2(sch_1):page181_i161@mstr_discrete.cap(chips)!CAP_0402-0.22UF,16V,10%,X7R,A3A!!!F4025!B!!!!
S!P3E_CPU1_PE3_MP_C_TXN<6>!C1F4!1!@baseboard_fab2_lib.baseboard_fab2(sch_1):page181_i160@mstr_discrete.cap(chips)!CAP_0402-0.22UF,16V,10%,X7R,A3A!!!F4026!A!!!!
S!P3E_CPU1_PE3_MP_TXN<6>!C1F4!2!@baseboard_fab2_lib.baseboard_fab2(sch_1):page181_i160@mstr_discrete.cap(chips)!CAP_0402-0.22UF,16V,10%,X7R,A3A!!!F4026!B!!!!
S!P3E_CPU1_PE3_MP_C_TXP<7>!C1F2!1!@baseboard_fab2_lib.baseboard_fab2(sch_1):page181_i162@mstr_discrete.cap(chips)!CAP_0402-0.22UF,16V,10%,X7R,A3A!!!F4028!A!!!!
S!P3E_CPU1_PE3_MP_TXP<7>!C1F2!2!@baseboard_fab2_lib.baseboard_fab2(sch_1):page181_i162@mstr_discrete.cap(chips)!CAP_0402-0.22UF,16V,10%,X7R,A3A!!!F4028!B!!!!
S!P3E_CPU1_PE3_MP_C_TXN<3>!C1F13!1!@baseboard_fab2_lib.baseboard_fab2(sch_1):page181_i163@mstr_discrete.cap(chips)!CAP_0402-0.22UF,16V,10%,X7R,A3A!!!F4019!A!!!!
S!P3E_CPU1_PE3_MP_TXN<3>!C1F13!2!@baseboard_fab2_lib.baseboard_fab2(sch_1):page181_i163@mstr_discrete.cap(chips)!CAP_0402-0.22UF,16V,10%,X7R,A3A!!!F4019!B!!!!
S!P3E_CPU1_PE3_MP_C_TXN<4>!C1F10!1!@baseboard_fab2_lib.baseboard_fab2(sch_1):page181_i164@mstr_discrete.cap(chips)!CAP_0402-0.22UF,16V,10%,X7R,A3A!!!F4022!A!!!!
S!P3E_CPU1_PE3_MP_TXN<4>!C1F10!2!@baseboard_fab2_lib.baseboard_fab2(sch_1):page181_i164@mstr_discrete.cap(chips)!CAP_0402-0.22UF,16V,10%,X7R,A3A!!!F4022!B!!!!
S!P3E_CPU1_PE3_MP_C_TXP<5>!C1F6!1!@baseboard_fab2_lib.baseboard_fab2(sch_1):page181_i165@mstr_discrete.cap(chips)!CAP_0402-0.22UF,16V,10%,X7R,A3A!!!F4024!A!!!!
S!P3E_CPU1_PE3_MP_TXP<5>!C1F6!2!@baseboard_fab2_lib.baseboard_fab2(sch_1):page181_i165@mstr_discrete.cap(chips)!CAP_0402-0.22UF,16V,10%,X7R,A3A!!!F4024!B!!!!
S!P3E_CPU1_PE3_MP_C_TXN<0>!C1F20!1!@baseboard_fab2_lib.baseboard_fab2(sch_1):page181_i166@mstr_discrete.cap(chips)!CAP_0402-0.22UF,16V,10%,X7R,A3A!!!F4013!A!!!!
S!P3E_CPU1_PE3_MP_TXN<0>!C1F20!2!@baseboard_fab2_lib.baseboard_fab2(sch_1):page181_i166@mstr_discrete.cap(chips)!CAP_0402-0.22UF,16V,10%,X7R,A3A!!!F4013!B!!!!
S!P3E_CPU1_PE3_MP_C_TXN<1>!C1F16!1!@baseboard_fab2_lib.baseboard_fab2(sch_1):page181_i172@mstr_discrete.cap(chips)!CAP_0402-0.22UF,16V,10%,X7R,A3A!!!F4016!A!!!!
S!P3E_CPU1_PE3_MP_TXN<1>!C1F16!2!@baseboard_fab2_lib.baseboard_fab2(sch_1):page181_i172@mstr_discrete.cap(chips)!CAP_0402-0.22UF,16V,10%,X7R,A3A!!!F4016!B!!!!
S!P3E_CPU1_PE3_MP_C_TXN<2>!C1F15!1!@baseboard_fab2_lib.baseboard_fab2(sch_1):page181_i174@mstr_discrete.cap(chips)!CAP_0402-0.22UF,16V,10%,X7R,A3A!!!F4017!A!!!!
S!P3E_CPU1_PE3_MP_TXN<2>!C1F15!2!@baseboard_fab2_lib.baseboard_fab2(sch_1):page181_i174@mstr_discrete.cap(chips)!CAP_0402-0.22UF,16V,10%,X7R,A3A!!!F4017!B!!!!
S!P5V_STBY!C1D33!1!@baseboard_fab2_lib.baseboard_fab2(sch_1):page209_i22@mstr_discrete.cap(chips)!CAP_0402-0.22UF,16V,10%,X7R,A3A!!!F4033!A!!!!
S!GND!C1D33!2!@baseboard_fab2_lib.baseboard_fab2(sch_1):page209_i22@mstr_discrete.cap(chips)!CAP_0402-0.22UF,16V,10%,X7R,A3A!!!F4033!B!!!!
S!P5V_STBY!C7C18!1!@baseboard_fab2_lib.baseboard_fab2(sch_1):page212_i33@mstr_discrete.cap(chips)!CAP_0402-0.22UF,16V,10%,X7R,A3A!!!F3881!A!!!!
S!GND!C7C18!2!@baseboard_fab2_lib.baseboard_fab2(sch_1):page212_i33@mstr_discrete.cap(chips)!CAP_0402-0.22UF,16V,10%,X7R,A3A!!!F3881!B!!!!
S!GND_LAN_TRCT1234_C!C9G5!1!@baseboard_fab2_lib.baseboard_fab2(sch_1):page141_i48@mstr_discrete.cap(chips)!CAP_0402-1.0UF,16V,10%,X7S,G71A!!!F3758!A!!!!
S!GND!C9G5!2!@baseboard_fab2_lib.baseboard_fab2(sch_1):page141_i48@mstr_discrete.cap(chips)!CAP_0402-1.0UF,16V,10%,X7S,G71A!!!F3758!B!!!!
S!VR_FET_SW_P12V_STBY_PVDDQ_DEF!C7A14!1!@baseboard_fab2_lib.baseboard_fab2(sch_1):page236_i65@mstr_discrete.cap(chips)!CAP_1210-100UF,16V,20%,X5R,644A!!!F2278!A!!!!
S!GND!C7A14!2!@baseboard_fab2_lib.baseboard_fab2(sch_1):page236_i65@mstr_discrete.cap(chips)!CAP_1210-100UF,16V,20%,X5R,644A!!!F2278!B!!!!
S!VR_FET_SW_P12V_STBY_PVDDQ_DEF!C7A13!1!@baseboard_fab2_lib.baseboard_fab2(sch_1):page236_i63@mstr_discrete.cap(chips)!CAP_1210-100UF,16V,20%,X5R,644A!!!F2279!A!!!!
S!GND!C7A13!2!@baseboard_fab2_lib.baseboard_fab2(sch_1):page236_i63@mstr_discrete.cap(chips)!CAP_1210-100UF,16V,20%,X5R,644A!!!F2279!B!!!!
S!VR_FET_SW_P12V_STBY_PVCCIO_CPU0!C7C7!1!@baseboard_fab2_lib.baseboard_fab2(sch_1):page212_i54@mstr_discrete.cap(chips)!CAP_1210-100UF,16V,20%,X5R,644A!!!F2277!A!!!!
S!GND!C7C7!2!@baseboard_fab2_lib.baseboard_fab2(sch_1):page212_i54@mstr_discrete.cap(chips)!CAP_1210-100UF,16V,20%,X5R,644A!!!F2277!B!!!!
S!VR_FET_SW_P12V_STBY_PVCCIO_CPU0!C7C8!1!@baseboard_fab2_lib.baseboard_fab2(sch_1):page212_i51@mstr_discrete.cap(chips)!CAP_1210-100UF,16V,20%,X5R,644A!!!F2276!A!!!!
S!GND!C7C8!2!@baseboard_fab2_lib.baseboard_fab2(sch_1):page212_i51@mstr_discrete.cap(chips)!CAP_1210-100UF,16V,20%,X5R,644A!!!F2276!B!!!!
S!VR_FET_SW_P12V_STBY_PVCCIN_CPU0!C4E8!1!@baseboard_fab2_lib.baseboard_fab2(sch_1):page214_i29@mstr_discrete.cap(chips)!CAP_1210-100UF,16V,20%,X5R,644A!!!F2282!A!!!!
S!GND!C4E8!2!@baseboard_fab2_lib.baseboard_fab2(sch_1):page214_i29@mstr_discrete.cap(chips)!CAP_1210-100UF,16V,20%,X5R,644A!!!F2282!B!!!!
S!VR_FET_SW_P12V_STBY_PVCCIN_CPU0!C4E9!1!@baseboard_fab2_lib.baseboard_fab2(sch_1):page214_i8@mstr_discrete.cap(chips)!CAP_1210-100UF,16V,20%,X5R,644A!!!F2281!A!!!!
S!GND!C4E9!2!@baseboard_fab2_lib.baseboard_fab2(sch_1):page214_i8@mstr_discrete.cap(chips)!CAP_1210-100UF,16V,20%,X5R,644A!!!F2281!B!!!!
S!VR_FET_SW_P12V_STBY_PVCCIN_CPU0!C4E14!1!@baseboard_fab2_lib.baseboard_fab2(sch_1):page214_i31@mstr_discrete.cap(chips)!CAP_1210-100UF,16V,20%,X5R,644A!!!F2280!A!!!!
S!GND!C4E14!2!@baseboard_fab2_lib.baseboard_fab2(sch_1):page214_i31@mstr_discrete.cap(chips)!CAP_1210-100UF,16V,20%,X5R,644A!!!F2280!B!!!!
S!FAN_PWM_OUT_SYS0_BUF!R2U42!1!@baseboard_fab2_lib.baseboard_fab2(sch_1):page161_i99@mstr_discrete.res(chips)!RES_0402-221,1.0%,1/16W,CHIP,GA!!!F853!A!!!!
S!FAN_PWM_OUT_SYS0_R!R2U42!2!@baseboard_fab2_lib.baseboard_fab2(sch_1):page161_i99@mstr_discrete.res(chips)!RES_0402-221,1.0%,1/16W,CHIP,GA!!!F853!B!!!!
S!FAN_PWM_OUT_SYS1_BUF!R2U44!1!@baseboard_fab2_lib.baseboard_fab2(sch_1):page161_i102@mstr_discrete.res(chips)!RES_0402-221,1.0%,1/16W,CHIP,GA!!!F852!A!!!!
S!FAN_PWM_OUT_SYS1_R!R2U44!2!@baseboard_fab2_lib.baseboard_fab2(sch_1):page161_i102@mstr_discrete.res(chips)!RES_0402-221,1.0%,1/16W,CHIP,GA!!!F852!B!!!!
S!P3V3_STBY!R9F28!1!@baseboard_fab2_lib.baseboard_fab2(sch_1):page177_i72@mstr_discrete.res(chips)!RES_0402-221,1.0%,1/16W,CHIP,GA!!!F846!A!!!!
S!FM_RED_LED_ANODE!R9F28!2!@baseboard_fab2_lib.baseboard_fab2(sch_1):page177_i72@mstr_discrete.res(chips)!RES_0402-221,1.0%,1/16W,CHIP,GA!!!F846!B!!!!
S!FM_PWR_LED_A!R9A20!1!@baseboard_fab2_lib.baseboard_fab2(sch_1):page119_i178@mstr_discrete.res(chips)!RES_0402-221,1.0%,1/16W,CHIP,GA!!!F848!A!!!!
S!P3V3_STBY!R9A20!2!@baseboard_fab2_lib.baseboard_fab2(sch_1):page119_i178@mstr_discrete.res(chips)!RES_0402-221,1.0%,1/16W,CHIP,GA!!!F848!B!!!!
S!SVID_ALERT1_CPU0_N!R6B3!1!@baseboard_fab2_lib.baseboard_fab2(sch_1):page21_i152@mstr_discrete.res(chips)!RES_0402-221,1.0%,1/16W,CHIP,GA!!!F850!A!!!!
S!SVID_ALERT1_CPU0_R_N!R6B3!2!@baseboard_fab2_lib.baseboard_fab2(sch_1):page21_i152@mstr_discrete.res(chips)!RES_0402-221,1.0%,1/16W,CHIP,GA!!!F850!B!!!!
S!SVID_ALERT0_CPU0_N!R6N10!1!@baseboard_fab2_lib.baseboard_fab2(sch_1):page21_i149@mstr_discrete.res(chips)!RES_0402-221,1.0%,1/16W,CHIP,GA!!!F849!A!!!!
S!SVID_ALERT0_CPU0_R_N!R6N10!2!@baseboard_fab2_lib.baseboard_fab2(sch_1):page21_i149@mstr_discrete.res(chips)!RES_0402-221,1.0%,1/16W,CHIP,GA!!!F849!B!!!!
S!SVID_ALERT1_CPU1_N!R1C1!1!@baseboard_fab2_lib.baseboard_fab2(sch_1):page55_i26@mstr_discrete.res(chips)!RES_0402-221,1.0%,1/16W,CHIP,GA!!!F855!A!!!!
S!SVID_ALERT1_CPU1_R_N!R1C1!2!@baseboard_fab2_lib.baseboard_fab2(sch_1):page55_i26@mstr_discrete.res(chips)!RES_0402-221,1.0%,1/16W,CHIP,GA!!!F855!B!!!!
S!SVID_ALERT0_CPU1_N!R3B1!1!@baseboard_fab2_lib.baseboard_fab2(sch_1):page55_i27@mstr_discrete.res(chips)!RES_0402-221,1.0%,1/16W,CHIP,GA!!!F851!A!!!!
S!SVID_ALERT0_CPU1_R_N!R3B1!2!@baseboard_fab2_lib.baseboard_fab2(sch_1):page55_i27@mstr_discrete.res(chips)!RES_0402-221,1.0%,1/16W,CHIP,GA!!!F851!B!!!!
S!FM_HEARTBEAT_LED_A!R9E24!1!@baseboard_fab2_lib.baseboard_fab2(sch_1):page147_i57@mstr_discrete.res(chips)!RES_0402-221,1.0%,1/16W,CHIP,GA!!!F847!A!!!!
S!P3V3_STBY!R9E24!2!@baseboard_fab2_lib.baseboard_fab2(sch_1):page147_i57@mstr_discrete.res(chips)!RES_0402-221,1.0%,1/16W,CHIP,GA!!!F847!B!!!!
S!FM_BEEP_LED_P!R1L33!1!@baseboard_fab2_lib.baseboard_fab2(sch_1):page175_i45@mstr_discrete.res(chips)!RES_0402-221,1.0%,1/16W,CHIP,GA!!!F854!A!!!!
S!P3V3_STBY!R1L33!2!@baseboard_fab2_lib.baseboard_fab2(sch_1):page175_i45@mstr_discrete.res(chips)!RES_0402-221,1.0%,1/16W,CHIP,GA!!!F854!B!!!!
S!P3V3_STBY!R8C16!1!@baseboard_fab2_lib.baseboard_fab2(sch_1):page138_i91@mstr_discrete.res(chips)!RES_0402-3.3K,5%,1/16W,CHIP,G2A!!!F763!A!!!!
S!SMB_HOST_STBY_LVC3_SDA!R8C16!2!@baseboard_fab2_lib.baseboard_fab2(sch_1):page138_i91@mstr_discrete.res(chips)!RES_0402-3.3K,5%,1/16W,CHIP,G2A!!!F763!B!!!!
S!P3V3_STBY!R8C15!1!@baseboard_fab2_lib.baseboard_fab2(sch_1):page138_i92@mstr_discrete.res(chips)!RES_0402-3.3K,5%,1/16W,CHIP,G2A!!!F764!A!!!!
S!SMB_HOST_STBY_LVC3_SCL!R8C15!2!@baseboard_fab2_lib.baseboard_fab2(sch_1):page138_i92@mstr_discrete.res(chips)!RES_0402-3.3K,5%,1/16W,CHIP,G2A!!!F764!B!!!!
S!P3V3_STBY!R8B24!1!@baseboard_fab2_lib.baseboard_fab2(sch_1):page138_i95@mstr_discrete.res(chips)!RES_0402-3.3K,5%,1/16W,CHIP,G2A!!!F766!A!!!!
S!SMB_SLOTX24_PCH_STBY_LVC3_SDA!R8B24!2!@baseboard_fab2_lib.baseboard_fab2(sch_1):page138_i95@mstr_discrete.res(chips)!RES_0402-3.3K,5%,1/16W,CHIP,G2A!!!F766!B!!!!
S!P3V3_STBY!R8B26!1!@baseboard_fab2_lib.baseboard_fab2(sch_1):page138_i96@mstr_discrete.res(chips)!RES_0402-3.3K,5%,1/16W,CHIP,G2A!!!F765!A!!!!
S!SMB_SLOTX24_PCH_STBY_LVC3_SCL!R8B26!2!@baseboard_fab2_lib.baseboard_fab2(sch_1):page138_i96@mstr_discrete.res(chips)!RES_0402-3.3K,5%,1/16W,CHIP,G2A!!!F765!B!!!!
S!P1V8_PCH_STBY!R8A12!1!@baseboard_fab2_lib.baseboard_fab2(sch_1):page237_i15@mstr_discrete.res(chips)!RES_0603-475.0,1%,1/10W,CHIP,GA!!!F256!A!!!!
S!GND!R8A12!2!@baseboard_fab2_lib.baseboard_fab2(sch_1):page237_i15@mstr_discrete.res(chips)!RES_0603-475.0,1%,1/10W,CHIP,GA!!!F256!B!!!!
S!A_HSC_INAP!R9P12!1!@baseboard_fab2_lib.baseboard_fab2(sch_1):page200_i218@mstr_discrete.res(chips)!RES_0402-4.99K,1%,1/16W,CHIP,GA!!!F495!A!!!!
S!AGND_HSC!R9P12!2!@baseboard_fab2_lib.baseboard_fab2(sch_1):page200_i218@mstr_discrete.res(chips)!RES_0402-4.99K,1%,1/16W,CHIP,GA!!!F495!B!!!!
S!PD_SPRV_RSET!R9E23!1!@baseboard_fab2_lib.baseboard_fab2(sch_1):page139_i174@mstr_discrete.res(chips)!RES_0402-4.99K,1%,1/16W,CHIP,GA!!!F496!A!!!!
S!GND!R9E23!2!@baseboard_fab2_lib.baseboard_fab2(sch_1):page139_i174@mstr_discrete.res(chips)!RES_0402-4.99K,1%,1/16W,CHIP,GA!!!F496!B!!!!
S!P3V3_STBY!C9F2!1!@baseboard_fab2_lib.baseboard_fab2(sch_1):page139_i140@mstr_discrete.cap(chips)!CAP_1210-47UF,16V,20%,EMPTY,D3A!!!F2274!A!!!!
S!GND!C9F2!2!@baseboard_fab2_lib.baseboard_fab2(sch_1):page139_i140@mstr_discrete.cap(chips)!CAP_1210-47UF,16V,20%,EMPTY,D3A!!!F2274!B!!!!
S!P1V5_LAN!C9E6!1!@baseboard_fab2_lib.baseboard_fab2(sch_1):page139_i155@mstr_discrete.cap(chips)!CAP_1210-47UF,16V,20%,EMPTY,D3A!!!F2275!A!!!!
S!GND!C9E6!2!@baseboard_fab2_lib.baseboard_fab2(sch_1):page139_i155@mstr_discrete.cap(chips)!CAP_1210-47UF,16V,20%,EMPTY,D3A!!!F2275!B!!!!
S!GND!Y7C1!4!!CRYSTAL_2013-48.000MHZ,IC,D717A!!!!!!!!
S!GND!Y7C1!2!!CRYSTAL_2013-48.000MHZ,IC,D717A!!!!!!!!
S!XTAL_PCH_48M_IN!Y7C1!1!@baseboard_fab2_lib.baseboard_fab2(sch_1):page114_i49@mstr_discrete.crystal(chips)!CRYSTAL_2013-48.000MHZ,IC,D717A!!!F2230!A!!!!
S!XTAL_PCH_48M_OUT!Y7C1!3!@baseboard_fab2_lib.baseboard_fab2(sch_1):page114_i49@mstr_discrete.crystal(chips)!CRYSTAL_2013-48.000MHZ,IC,D717A!!!F2230!B!!!!
S!GND!Y8F1!4!!CRYSTAL_2013LF-25.000MHZ,IC,D7B!!!!!!!!
S!GND!Y8F1!2!!CRYSTAL_2013LF-25.000MHZ,IC,D7B!!!!!!!!
S!XTAL_CK_MNG_IN!Y8F1!1!@baseboard_fab2_lib.baseboard_fab2(sch_1):page101_i52@mstr_discrete.crystal(chips)!CRYSTAL_2013LF-25.000MHZ,IC,D7B!!!F2229!A!!!!
S!XTAL_CK_MNG_OUT!Y8F1!3!@baseboard_fab2_lib.baseboard_fab2(sch_1):page101_i52@mstr_discrete.crystal(chips)!CRYSTAL_2013LF-25.000MHZ,IC,D7B!!!F2229!B!!!!
S!XTAL_33K_RTC1!Y7C2!1!@baseboard_fab2_lib.baseboard_fab2(sch_1):page114_i55@mstr_discrete.crystal(chips)!CRYSTAL_SM-32.768KHZ,IC,C13544A!!!F2227!A!!!!
S!XTAL_33K_RTC2!Y7C2!2!@baseboard_fab2_lib.baseboard_fab2(sch_1):page114_i55@mstr_discrete.crystal(chips)!CRYSTAL_SM-32.768KHZ,IC,C13544A!!!F2227!B!!!!
S!FM_DB_UART_SEL0_N!CR1L1!2!@baseboard_fab2_lib.baseboard_fab2(sch_1):page168_i2@mstr_discrete.diode(chips)!DIODE_SM-1N4148W,IC,D89194-001!!!F2222!A!!!!
S!FM_DB_UART_SEL1_N!CR1L1!1!@baseboard_fab2_lib.baseboard_fab2(sch_1):page168_i2@mstr_discrete.diode(chips)!DIODE_SM-1N4148W,IC,D89194-001!!!F2222!C!!!!
S!FM_DB_UART_SEL1_N!CR1L2!2!@baseboard_fab2_lib.baseboard_fab2(sch_1):page168_i3@mstr_discrete.diode(chips)!DIODE_SM-1N4148W,IC,D89194-001!!!F2221!A!!!!
S!FM_DB_UART_SEL2_N!CR1L2!1!@baseboard_fab2_lib.baseboard_fab2(sch_1):page168_i3@mstr_discrete.diode(chips)!DIODE_SM-1N4148W,IC,D89194-001!!!F2221!C!!!!
S!FM_DB_UART_SEL2_N!CR1L3!2!@baseboard_fab2_lib.baseboard_fab2(sch_1):page168_i4@mstr_discrete.diode(chips)!DIODE_SM-1N4148W,IC,D89194-001!!!F2220!A!!!!
S!FM_DB_UART_SEL3_N!CR1L3!1!@baseboard_fab2_lib.baseboard_fab2(sch_1):page168_i4@mstr_discrete.diode(chips)!DIODE_SM-1N4148W,IC,D89194-001!!!F2220!C!!!!
S!FM_DB_UART_SEL3_N!CR1L4!2!@baseboard_fab2_lib.baseboard_fab2(sch_1):page168_i5@mstr_discrete.diode(chips)!DIODE_SM-1N4148W,IC,D89194-001!!!F2219!A!!!!
S!FM_DB_UART_SEL4_N!CR1L4!1!@baseboard_fab2_lib.baseboard_fab2(sch_1):page168_i5@mstr_discrete.diode(chips)!DIODE_SM-1N4148W,IC,D89194-001!!!F2219!C!!!!
S!P3V3!FB6P1!1!@baseboard_fab2_lib.baseboard_fab2(sch_1):page102_i8@mstr_discrete.ferrite(chips)!FERRITE_SMLF-600,FB,656554-043!!!F2183!A!!!!
S!P3V3_DB1200!FB6P1!2!@baseboard_fab2_lib.baseboard_fab2(sch_1):page102_i8@mstr_discrete.ferrite(chips)!FERRITE_SMLF-600,FB,656554-043!!!F2183!B!!!!
S!P3V3_STBY!FB2T2!1!@baseboard_fab2_lib.baseboard_fab2(sch_1):page101_i114@mstr_discrete.ferrite(chips)!FERRITE_SMLF-600,FB,656554-043!!!F2184!A!!!!
S!P3V3_STBY_MNG!FB2T2!2!@baseboard_fab2_lib.baseboard_fab2(sch_1):page101_i114@mstr_discrete.ferrite(chips)!FERRITE_SMLF-600,FB,656554-043!!!F2184!B!!!!
S!CLK_25M_BMC_R!EU8F2!16!@baseboard_fab2_lib.baseboard_fab2(sch_1):page101_i34@mstr_clock.ics9fgp204(chips)!ICS9FGP204_MLFP-IC,E95226-001!!!F2119!\25mhz_0\!!!!
S!CLK_25M_CPLD_R!EU8F2!17!@baseboard_fab2_lib.baseboard_fab2(sch_1):page101_i34@mstr_clock.ics9fgp204(chips)!ICS9FGP204_MLFP-IC,E95226-001!!!F2119!\25mhz_1\!!!!
S!CLK_32K_SUSCLK_PLD_R!EU8F2!13!@baseboard_fab2_lib.baseboard_fab2(sch_1):page101_i34@mstr_clock.ics9fgp204(chips)!ICS9FGP204_MLFP-IC,E95226-001!!!F2119!\32khz\!!!!
S!TP_33P_33M_SMBADR!EU8F2!22!@baseboard_fab2_lib.baseboard_fab2(sch_1):page101_i34@mstr_clock.ics9fgp204(chips)!ICS9FGP204_MLFP-IC,E95226-001!!!F2119!\33mhz_smbadr\!!!!
S!TP_CLK_100M_R_DN!EU8F2!8!@baseboard_fab2_lib.baseboard_fab2(sch_1):page101_i34@mstr_clock.ics9fgp204(chips)!ICS9FGP204_MLFP-IC,E95226-001!!!F2119!CPUCLKC0!!!!
S!TP_CLK_100M_R_DP!EU8F2!7!@baseboard_fab2_lib.baseboard_fab2(sch_1):page101_i34@mstr_clock.ics9fgp204(chips)!ICS9FGP204_MLFP-IC,E95226-001!!!F2119!CPUCLKT0!!!!
S!TP_CLK_96M_CKMNG_N!EU8F2!4!@baseboard_fab2_lib.baseboard_fab2(sch_1):page101_i34@mstr_clock.ics9fgp204(chips)!ICS9FGP204_MLFP-IC,E95226-001!!!F2119!DOT96SSC!!!!
S!TP_CLK_96M_CKMNG_P!EU8F2!3!@baseboard_fab2_lib.baseboard_fab2(sch_1):page101_i34@mstr_clock.ics9fgp204(chips)!ICS9FGP204_MLFP-IC,E95226-001!!!F2119!DOT96SST!!!!
S!GND!EU8F2!14!@baseboard_fab2_lib.baseboard_fab2(sch_1):page101_i34@mstr_clock.ics9fgp204(chips)!ICS9FGP204_MLFP-IC,E95226-001!!!F2119!GND32K!!!!
S!GND!EU8F2!21!@baseboard_fab2_lib.baseboard_fab2(sch_1):page101_i34@mstr_clock.ics9fgp204(chips)!ICS9FGP204_MLFP-IC,E95226-001!!!F2119!GND33!!!!
S!GND!EU8F2!1!@baseboard_fab2_lib.baseboard_fab2(sch_1):page101_i34@mstr_clock.ics9fgp204(chips)!ICS9FGP204_MLFP-IC,E95226-001!!!F2119!GND(0)!!!!
S!GND!EU8F2!41!@baseboard_fab2_lib.baseboard_fab2(sch_1):page101_i34@mstr_clock.ics9fgp204(chips)!ICS9FGP204_MLFP-IC,E95226-001!!!F2119!GND(1)!!!!
S!GND!EU8F2!10!@baseboard_fab2_lib.baseboard_fab2(sch_1):page101_i34@mstr_clock.ics9fgp204(chips)!ICS9FGP204_MLFP-IC,E95226-001!!!F2119!GNDCPU!!!!
S!GND!EU8F2!18!@baseboard_fab2_lib.baseboard_fab2(sch_1):page101_i34@mstr_clock.ics9fgp204(chips)!ICS9FGP204_MLFP-IC,E95226-001!!!F2119!GNDREF!!!!
S!GND!EU8F2!27!@baseboard_fab2_lib.baseboard_fab2(sch_1):page101_i34@mstr_clock.ics9fgp204(chips)!ICS9FGP204_MLFP-IC,E95226-001!!!F2119!GNDRMII(0)!!!!
S!GND!EU8F2!30!@baseboard_fab2_lib.baseboard_fab2(sch_1):page101_i34@mstr_clock.ics9fgp204(chips)!ICS9FGP204_MLFP-IC,E95226-001!!!F2119!GNDRMII(1)!!!!
S!GND!EU8F2!35!@baseboard_fab2_lib.baseboard_fab2(sch_1):page101_i34@mstr_clock.ics9fgp204(chips)!ICS9FGP204_MLFP-IC,E95226-001!!!F2119!GND_RGMII!!!!
S!A_COMP_CKMNG!EU8F2!11!@baseboard_fab2_lib.baseboard_fab2(sch_1):page101_i34@mstr_clock.ics9fgp204(chips)!ICS9FGP204_MLFP-IC,E95226-001!!!F2119!IREF!!!!
S!PD_CKMNG_OE!EU8F2!5!@baseboard_fab2_lib.baseboard_fab2(sch_1):page101_i34@mstr_clock.ics9fgp204(chips)!ICS9FGP204_MLFP-IC,E95226-001!!!F2119!OE_96!!!!
S!PD_CKMNG_OE!EU8F2!6!@baseboard_fab2_lib.baseboard_fab2(sch_1):page101_i34@mstr_clock.ics9fgp204(chips)!ICS9FGP204_MLFP-IC,E95226-001!!!F2119!OE_CPU!!!!
S!TP_CLK_125M_BMCA!EU8F2!37!@baseboard_fab2_lib.baseboard_fab2(sch_1):page101_i34@mstr_clock.ics9fgp204(chips)!ICS9FGP204_MLFP-IC,E95226-001!!!F2119!RGMII(0)!!!!
S!TP_CLK_125M!EU8F2!36!@baseboard_fab2_lib.baseboard_fab2(sch_1):page101_i34@mstr_clock.ics9fgp204(chips)!ICS9FGP204_MLFP-IC,E95226-001!!!F2119!RGMII(1)!!!!
S!CLK_50M_CKMNG_OCP_R!EU8F2!33!@baseboard_fab2_lib.baseboard_fab2(sch_1):page101_i34@mstr_clock.ics9fgp204(chips)!ICS9FGP204_MLFP-IC,E95226-001!!!F2119!RMII(0)!!!!
S!CLK_50M_CKMNG_BMC_1_R!EU8F2!32!@baseboard_fab2_lib.baseboard_fab2(sch_1):page101_i34@mstr_clock.ics9fgp204(chips)!ICS9FGP204_MLFP-IC,E95226-001!!!F2119!RMII(1)!!!!
S!CLK_50M_CKMNG_BMC_2_R!EU8F2!29!@baseboard_fab2_lib.baseboard_fab2(sch_1):page101_i34@mstr_clock.ics9fgp204(chips)!ICS9FGP204_MLFP-IC,E95226-001!!!F2119!RMII(2)!!!!
S!CLK_50M_CKMNG_SPRVLLE_R!EU8F2!28!@baseboard_fab2_lib.baseboard_fab2(sch_1):page101_i34@mstr_clock.ics9fgp204(chips)!ICS9FGP204_MLFP-IC,E95226-001!!!F2119!RMII(3)!!!!
S!CLK_50M_CKMNG_PCH_10GBE_R!EU8F2!25!@baseboard_fab2_lib.baseboard_fab2(sch_1):page101_i34@mstr_clock.ics9fgp204(chips)!ICS9FGP204_MLFP-IC,E95226-001!!!F2119!RMII(4)!!!!
S!TP_CLK5_50M_CKMNG!EU8F2!24!@baseboard_fab2_lib.baseboard_fab2(sch_1):page101_i34@mstr_clock.ics9fgp204(chips)!ICS9FGP204_MLFP-IC,E95226-001!!!F2119!RMII(5)!!!!
S!SMB_HOST_STBY_LVC3_SCL!EU8F2!38!@baseboard_fab2_lib.baseboard_fab2(sch_1):page101_i34@mstr_clock.ics9fgp204(chips)!ICS9FGP204_MLFP-IC,E95226-001!!!F2119!SMBCLK!!!!
S!SMB_HOST_STBY_LVC3_SDA!EU8F2!39!@baseboard_fab2_lib.baseboard_fab2(sch_1):page101_i34@mstr_clock.ics9fgp204(chips)!ICS9FGP204_MLFP-IC,E95226-001!!!F2119!SMBDAT!!!!
S!P3V3_STBY_MNG!EU8F2!12!@baseboard_fab2_lib.baseboard_fab2(sch_1):page101_i34@mstr_clock.ics9fgp204(chips)!ICS9FGP204_MLFP-IC,E95226-001!!!F2119!VDD32K!!!!
S!P3V3_STBY_MNG!EU8F2!23!@baseboard_fab2_lib.baseboard_fab2(sch_1):page101_i34@mstr_clock.ics9fgp204(chips)!ICS9FGP204_MLFP-IC,E95226-001!!!F2119!VDD33!!!!
S!P3V3_STBY_MNG!EU8F2!2!@baseboard_fab2_lib.baseboard_fab2(sch_1):page101_i34@mstr_clock.ics9fgp204(chips)!ICS9FGP204_MLFP-IC,E95226-001!!!F2119!VDD96!!!!
S!P3V3_STBY_MNG_CPU!EU8F2!9!@baseboard_fab2_lib.baseboard_fab2(sch_1):page101_i34@mstr_clock.ics9fgp204(chips)!ICS9FGP204_MLFP-IC,E95226-001!!!F2119!VDDCPU!!!!
S!P3V3_STBY_MNG!EU8F2!15!@baseboard_fab2_lib.baseboard_fab2(sch_1):page101_i34@mstr_clock.ics9fgp204(chips)!ICS9FGP204_MLFP-IC,E95226-001!!!F2119!VDDREF!!!!
S!P3V3_STBY_MNG_RMII!EU8F2!26!@baseboard_fab2_lib.baseboard_fab2(sch_1):page101_i34@mstr_clock.ics9fgp204(chips)!ICS9FGP204_MLFP-IC,E95226-001!!!F2119!VDDRMII(0)!!!!
S!P3V3_STBY_MNG_RMII!EU8F2!31!@baseboard_fab2_lib.baseboard_fab2(sch_1):page101_i34@mstr_clock.ics9fgp204(chips)!ICS9FGP204_MLFP-IC,E95226-001!!!F2119!VDDRMII(1)!!!!
S!P3V3_STBY_MNG_RGMII!EU8F2!34!@baseboard_fab2_lib.baseboard_fab2(sch_1):page101_i34@mstr_clock.ics9fgp204(chips)!ICS9FGP204_MLFP-IC,E95226-001!!!F2119!VDD_RGMII!!!!
S!PWRGD_P3V3_STBY!EU8F2!40!@baseboard_fab2_lib.baseboard_fab2(sch_1):page101_i34@mstr_clock.ics9fgp204(chips)!ICS9FGP204_MLFP-IC,E95226-001!!!F2119!VTTPWR_GD_PD_N!!!!
S!XTAL_CK_MNG_IN!EU8F2!19!@baseboard_fab2_lib.baseboard_fab2(sch_1):page101_i34@mstr_clock.ics9fgp204(chips)!ICS9FGP204_MLFP-IC,E95226-001!!!F2119!X1_25!!!!
S!XTAL_CK_MNG_OUT!EU8F2!20!@baseboard_fab2_lib.baseboard_fab2(sch_1):page101_i34@mstr_clock.ics9fgp204(chips)!ICS9FGP204_MLFP-IC,E95226-001!!!F2119!X2_25!!!!
S!P3V3_DB1200!R6P25!1!@baseboard_fab2_lib.baseboard_fab2(sch_1):page102_i26@mstr_discrete.res(chips)!RES_0603-2.2,1.0%,1/10W,CHIP,GA!!!F258!A!!!!
S!P3V3_DB1200_R!R6P25!2!@baseboard_fab2_lib.baseboard_fab2(sch_1):page102_i26@mstr_discrete.res(chips)!RES_0603-2.2,1.0%,1/10W,CHIP,GA!!!F258!B!!!!
S!P3V3_DB1200!R3D14!1!@baseboard_fab2_lib.baseboard_fab2(sch_1):page102_i21@mstr_discrete.res(chips)!RES_0603-2.2,1.0%,1/10W,CHIP,GA!!!F259!A!!!!
S!P3V3_DB1200_A!R3D14!2!@baseboard_fab2_lib.baseboard_fab2(sch_1):page102_i21@mstr_discrete.res(chips)!RES_0603-2.2,1.0%,1/10W,CHIP,GA!!!F259!B!!!!
S!P3V3_STBY_MNG!R2T21!1!@baseboard_fab2_lib.baseboard_fab2(sch_1):page101_i105@mstr_discrete.res(chips)!RES_0603-2.2,1.0%,1/10W,CHIP,GA!!!F262!A!!!!
S!P3V3_STBY_MNG_CPU!R2T21!2!@baseboard_fab2_lib.baseboard_fab2(sch_1):page101_i105@mstr_discrete.res(chips)!RES_0603-2.2,1.0%,1/10W,CHIP,GA!!!F262!B!!!!
S!P3V3_STBY_MNG!R2T52!1!@baseboard_fab2_lib.baseboard_fab2(sch_1):page101_i95@mstr_discrete.res(chips)!RES_0603-2.2,1.0%,1/10W,CHIP,GA!!!F260!A!!!!
S!P3V3_STBY_MNG_RMII!R2T52!2!@baseboard_fab2_lib.baseboard_fab2(sch_1):page101_i95@mstr_discrete.res(chips)!RES_0603-2.2,1.0%,1/10W,CHIP,GA!!!F260!B!!!!
S!P3V3_STBY_MNG!R2T23!1!@baseboard_fab2_lib.baseboard_fab2(sch_1):page101_i94@mstr_discrete.res(chips)!RES_0603-2.2,1.0%,1/10W,CHIP,GA!!!F261!A!!!!
S!P3V3_STBY_MNG_RGMII!R2T23!2!@baseboard_fab2_lib.baseboard_fab2(sch_1):page101_i94@mstr_discrete.res(chips)!RES_0603-2.2,1.0%,1/10W,CHIP,GA!!!F261!B!!!!
S!A_CTOP!C9E7!1!@baseboard_fab2_lib.baseboard_fab2(sch_1):page139_i76@mstr_discrete.cap(chips)!CAP_0402LF-0.039UF,25V,10%,X7RA!!!F3490!A!!!!
S!A_CBOT!C9E7!2!@baseboard_fab2_lib.baseboard_fab2(sch_1):page139_i76@mstr_discrete.cap(chips)!CAP_0402LF-0.039UF,25V,10%,X7RA!!!F3490!B!!!!
S!!DS9A2!3!!LED_1NCLF-GREEN,IC,C96565-011!!!!!!!!
S!FP_LED_HDD_ACTIVITY_AND_R_N!DS9A2!2!@baseboard_fab2_lib.baseboard_fab2(sch_1):page177_i42@mstr_discrete.led(chips)!LED_1NCLF-GREEN,IC,C96565-011!!!F2037!A!!!!
S!FP_LED_HDD_ACTIVITY_AND_N!DS9A2!1!@baseboard_fab2_lib.baseboard_fab2(sch_1):page177_i42@mstr_discrete.led(chips)!LED_1NCLF-GREEN,IC,C96565-011!!!F2037!C!!!!
S!A_CBOT!EU9E1!37!@baseboard_fab2_lib.baseboard_fab2(sch_1):page139_i72@mstr_intel.springville(chips)!SPRINGVILLE_SM1-IC,G47144-004!!!F67!CBOT!!!!
S!A_CTOP!EU9E1!40!@baseboard_fab2_lib.baseboard_fab2(sch_1):page139_i72@mstr_intel.springville(chips)!SPRINGVILLE_SM1-IC,G47144-004!!!F67!CTOP!!!!
S!FM_1GB_LOM_DISABLE_N!EU9E1!28!@baseboard_fab2_lib.baseboard_fab2(sch_1):page139_i72@mstr_intel.springville(chips)!SPRINGVILLE_SM1-IC,G47144-004!!!F67!DEV_OFF_N!!!!
S!GND!EU9E1!65!@baseboard_fab2_lib.baseboard_fab2(sch_1):page139_i72@mstr_intel.springville(chips)!SPRINGVILLE_SM1-IC,G47144-004!!!F67!GND!!!!
S!PU_JTAG_SPRV_TCK!EU9E1!19!@baseboard_fab2_lib.baseboard_fab2(sch_1):page139_i72@mstr_intel.springville(chips)!SPRINGVILLE_SM1-IC,G47144-004!!!F67!JTAG_CLK!!!!
S!PU_JTAG_SPRV_TDI!EU9E1!29!@baseboard_fab2_lib.baseboard_fab2(sch_1):page139_i72@mstr_intel.springville(chips)!SPRINGVILLE_SM1-IC,G47144-004!!!F67!JTAG_TDI!!!!
S!PU_JTAG_SPRV_TDO!EU9E1!4!@baseboard_fab2_lib.baseboard_fab2(sch_1):page139_i72@mstr_intel.springville(chips)!SPRINGVILLE_SM1-IC,G47144-004!!!F67!JTAG_TDO!!!!
S!PU_JTAG_SPRV_TMS!EU9E1!18!@baseboard_fab2_lib.baseboard_fab2(sch_1):page139_i72@mstr_intel.springville(chips)!SPRINGVILLE_SM1-IC,G47144-004!!!F67!JTAG_TMS!!!!
S!PU_SPRV_LAN_PWR_GOOD!EU9E1!1!@baseboard_fab2_lib.baseboard_fab2(sch_1):page139_i72@mstr_intel.springville(chips)!SPRINGVILLE_SM1-IC,G47144-004!!!F67!LAN_PWR_GOOD!!!!
S!LED_LAN_0_N!EU9E1!31!@baseboard_fab2_lib.baseboard_fab2(sch_1):page139_i72@mstr_intel.springville(chips)!SPRINGVILLE_SM1-IC,G47144-004!!!F67!LED0!!!!
S!LED_LAN_1_N!EU9E1!30!@baseboard_fab2_lib.baseboard_fab2(sch_1):page139_i72@mstr_intel.springville(chips)!SPRINGVILLE_SM1-IC,G47144-004!!!F67!LED1!!!!
S!LED_LAN_2_N!EU9E1!33!@baseboard_fab2_lib.baseboard_fab2(sch_1):page139_i72@mstr_intel.springville(chips)!SPRINGVILLE_SM1-IC,G47144-004!!!F67!LED2!!!!
S!NIC_MDI_SPRV_RJ45_0_DN!EU9E1!57!@baseboard_fab2_lib.baseboard_fab2(sch_1):page139_i72@mstr_intel.springville(chips)!SPRINGVILLE_SM1-IC,G47144-004!!!F67!MDI_MINUS0_SFP_I2C_DATA!!!!
S!NIC_MDI_SPRV_RJ45_1_DN!EU9E1!54!@baseboard_fab2_lib.baseboard_fab2(sch_1):page139_i72@mstr_intel.springville(chips)!SPRINGVILLE_SM1-IC,G47144-004!!!F67!MDI_MINUS1_SRDS_SIG_DET!!!!
S!NIC_SET_N_MDI_2_DN!EU9E1!52!@baseboard_fab2_lib.baseboard_fab2(sch_1):page139_i72@mstr_intel.springville(chips)!SPRINGVILLE_SM1-IC,G47144-004!!!F67!MDI_MINUS2_SETN!!!!
S!NIC_SER_N_MDI_3_DN!EU9E1!49!@baseboard_fab2_lib.baseboard_fab2(sch_1):page139_i72@mstr_intel.springville(chips)!SPRINGVILLE_SM1-IC,G47144-004!!!F67!MDI_MINUS3_SERN!!!!
S!NIC_MDI_SPRV_RJ45_0_DP!EU9E1!58!@baseboard_fab2_lib.baseboard_fab2(sch_1):page139_i72@mstr_intel.springville(chips)!SPRINGVILLE_SM1-IC,G47144-004!!!F67!MDI_PLUS0_NC!!!!
S!NIC_MDI_SPRV_RJ45_1_DP!EU9E1!55!@baseboard_fab2_lib.baseboard_fab2(sch_1):page139_i72@mstr_intel.springville(chips)!SPRINGVILLE_SM1-IC,G47144-004!!!F67!MDI_PLUS1_SFP_I2C_CLK!!!!
S!NIC_SET_P_MDI_2_DP!EU9E1!53!@baseboard_fab2_lib.baseboard_fab2(sch_1):page139_i72@mstr_intel.springville(chips)!SPRINGVILLE_SM1-IC,G47144-004!!!F67!MDI_PLUS2_SETP!!!!
S!NIC_SER_P_MDI_3_DP!EU9E1!50!@baseboard_fab2_lib.baseboard_fab2(sch_1):page139_i72@mstr_intel.springville(chips)!SPRINGVILLE_SM1-IC,G47144-004!!!F67!MDI_PLUS3_SERP!!!!
S!NC_SPRNGVLLE_22!EU9E1!22!@baseboard_fab2_lib.baseboard_fab2(sch_1):page139_i72@mstr_intel.springville(chips)!SPRINGVILLE_SM1-IC,G47144-004!!!F67!NC!!!!
S!RMII_PCH_SPRNGVLLE_ARB_OUT!EU9E1!43!@baseboard_fab2_lib.baseboard_fab2(sch_1):page139_i72@mstr_intel.springville(chips)!SPRINGVILLE_SM1-IC,G47144-004!!!F67!NC_SI_ARB_IN!!!!
S!RMII_PCH_SPRNGVLLE_ARB_IN_R!EU9E1!44!@baseboard_fab2_lib.baseboard_fab2(sch_1):page139_i72@mstr_intel.springville(chips)!SPRINGVILLE_SM1-IC,G47144-004!!!F67!NC_SI_ARB_OUT!!!!
S!CLK_50M_CKMNG_SPRVLLE!EU9E1!2!@baseboard_fab2_lib.baseboard_fab2(sch_1):page139_i72@mstr_intel.springville(chips)!SPRINGVILLE_SM1-IC,G47144-004!!!F67!NC_SI_CLK_IN!!!!
S!RMII_BMC_PCH_SPRNGVLLE_CRSDV_R!EU9E1!3!@baseboard_fab2_lib.baseboard_fab2(sch_1):page139_i72@mstr_intel.springville(chips)!SPRINGVILLE_SM1-IC,G47144-004!!!F67!NC_SI_CRS_DV!!!!
S!RMII_SPRNGVLLE_BMC_PCH_RXD0_R!EU9E1!6!@baseboard_fab2_lib.baseboard_fab2(sch_1):page139_i72@mstr_intel.springville(chips)!SPRINGVILLE_SM1-IC,G47144-004!!!F67!NC_SI_RXD0!!!!
S!RMII_SPRNGVLLE_BMC_PCH_RXD1_R!EU9E1!5!@baseboard_fab2_lib.baseboard_fab2(sch_1):page139_i72@mstr_intel.springville(chips)!SPRINGVILLE_SM1-IC,G47144-004!!!F67!NC_SI_RXD1!!!!
S!RMII_BMC_PCH_SPRNGVLLE_TXD0!EU9E1!9!@baseboard_fab2_lib.baseboard_fab2(sch_1):page139_i72@mstr_intel.springville(chips)!SPRINGVILLE_SM1-IC,G47144-004!!!F67!NC_SI_TXD0!!!!
S!RMII_BMC_PCH_SPRNGVLLE_TXD1!EU9E1!8!@baseboard_fab2_lib.baseboard_fab2(sch_1):page139_i72@mstr_intel.springville(chips)!SPRINGVILLE_SM1-IC,G47144-004!!!F67!NC_SI_TXD1!!!!
S!RMII_BMC_PCH_SPRNGVLLE_TXEN!EU9E1!7!@baseboard_fab2_lib.baseboard_fab2(sch_1):page139_i72@mstr_intel.springville(chips)!SPRINGVILLE_SM1-IC,G47144-004!!!F67!NC_SI_TX_EN!!!!
S!SPI_NIC_CS_R_N!EU9E1!15!@baseboard_fab2_lib.baseboard_fab2(sch_1):page139_i72@mstr_intel.springville(chips)!SPRINGVILLE_SM1-IC,G47144-004!!!F67!NVM_CS_N!!!!
S!SPI_NIC_MOSI_R!EU9E1!12!@baseboard_fab2_lib.baseboard_fab2(sch_1):page139_i72@mstr_intel.springville(chips)!SPRINGVILLE_SM1-IC,G47144-004!!!F67!NVM_SI!!!!
S!SPI_NIC_SCLK_R!EU9E1!13!@baseboard_fab2_lib.baseboard_fab2(sch_1):page139_i72@mstr_intel.springville(chips)!SPRINGVILLE_SM1-IC,G47144-004!!!F67!NVM_SK!!!!
S!SPI_NIC_MISO!EU9E1!14!@baseboard_fab2_lib.baseboard_fab2(sch_1):page139_i72@mstr_intel.springville(chips)!SPRINGVILLE_SM1-IC,G47144-004!!!F67!NVM_SO!!!!
S!CLK_100M_SPRV_DN!EU9E1!25!@baseboard_fab2_lib.baseboard_fab2(sch_1):page139_i72@mstr_intel.springville(chips)!SPRINGVILLE_SM1-IC,G47144-004!!!F67!PECLKN!!!!
S!CLK_100M_SPRV_DP!EU9E1!26!@baseboard_fab2_lib.baseboard_fab2(sch_1):page139_i72@mstr_intel.springville(chips)!SPRINGVILLE_SM1-IC,G47144-004!!!F67!PECLKP!!!!
S!PE_PCH_SPRV_TX_C_DN!EU9E1!23!@baseboard_fab2_lib.baseboard_fab2(sch_1):page139_i72@mstr_intel.springville(chips)!SPRINGVILLE_SM1-IC,G47144-004!!!F67!PE_RN!!!!
S!PE_PCH_SPRV_TX_C_DP!EU9E1!24!@baseboard_fab2_lib.baseboard_fab2(sch_1):page139_i72@mstr_intel.springville(chips)!SPRINGVILLE_SM1-IC,G47144-004!!!F67!PE_RP!!!!
S!RST_PLTRST_SPRV_R_N!EU9E1!17!@baseboard_fab2_lib.baseboard_fab2(sch_1):page139_i72@mstr_intel.springville(chips)!SPRINGVILLE_SM1-IC,G47144-004!!!F67!PE_RST_N!!!!
S!PE_PCH_SPRV_RX_DN!EU9E1!20!@baseboard_fab2_lib.baseboard_fab2(sch_1):page139_i72@mstr_intel.springville(chips)!SPRINGVILLE_SM1-IC,G47144-004!!!F67!PE_TN!!!!
S!PE_PCH_SPRV_RX_DP!EU9E1!21!@baseboard_fab2_lib.baseboard_fab2(sch_1):page139_i72@mstr_intel.springville(chips)!SPRINGVILLE_SM1-IC,G47144-004!!!F67!PE_TP!!!!
S!FM_PE_SPRV_WAKE_N!EU9E1!16!@baseboard_fab2_lib.baseboard_fab2(sch_1):page139_i72@mstr_intel.springville(chips)!SPRINGVILLE_SM1-IC,G47144-004!!!F67!PE_WAKE_N!!!!
S!PD_SPRV_RSET!EU9E1!48!@baseboard_fab2_lib.baseboard_fab2(sch_1):page139_i72@mstr_intel.springville(chips)!SPRINGVILLE_SM1-IC,G47144-004!!!F67!RSET!!!!
S!TP_SPRV_SDP0!EU9E1!63!@baseboard_fab2_lib.baseboard_fab2(sch_1):page139_i72@mstr_intel.springville(chips)!SPRINGVILLE_SM1-IC,G47144-004!!!F67!SDP0!!!!
S!TP_SPRV_SDP1!EU9E1!61!@baseboard_fab2_lib.baseboard_fab2(sch_1):page139_i72@mstr_intel.springville(chips)!SPRINGVILLE_SM1-IC,G47144-004!!!F67!SDP1_PCIE_DIS_SDP1!!!!
S!TP_SPRV_SDP2!EU9E1!62!@baseboard_fab2_lib.baseboard_fab2(sch_1):page139_i72@mstr_intel.springville(chips)!SPRINGVILLE_SM1-IC,G47144-004!!!F67!SDP2!!!!
S!TP_SPRV_SDP3!EU9E1!60!@baseboard_fab2_lib.baseboard_fab2(sch_1):page139_i72@mstr_intel.springville(chips)!SPRINGVILLE_SM1-IC,G47144-004!!!F67!SDP3!!!!
S!IRQ_LOM_ALERT_N!EU9E1!35!@baseboard_fab2_lib.baseboard_fab2(sch_1):page139_i72@mstr_intel.springville(chips)!SPRINGVILLE_SM1-IC,G47144-004!!!F67!SMB_ALRT_N!!!!
S!SMB_SPRINGVILLE_STBY_LVC3_SCL!EU9E1!34!@baseboard_fab2_lib.baseboard_fab2(sch_1):page139_i72@mstr_intel.springville(chips)!SPRINGVILLE_SM1-IC,G47144-004!!!F67!SMB_CLK!!!!
S!SMB_SPRINGVILLE_STBY_LVC3_SDA!EU9E1!36!@baseboard_fab2_lib.baseboard_fab2(sch_1):page139_i72@mstr_intel.springville(chips)!SPRINGVILLE_SM1-IC,G47144-004!!!F67!SMB_DATA!!!!
S!P0V9_LAN!EU9E1!59!@baseboard_fab2_lib.baseboard_fab2(sch_1):page139_i72@mstr_intel.springville(chips)!SPRINGVILLE_SM1-IC,G47144-004!!!F67!VDD0P9(0)!!!!
S!P0V9_LAN!EU9E1!32!@baseboard_fab2_lib.baseboard_fab2(sch_1):page139_i72@mstr_intel.springville(chips)!SPRINGVILLE_SM1-IC,G47144-004!!!F67!VDD0P9(1)!!!!
S!P0V9_LAN!EU9E1!11!@baseboard_fab2_lib.baseboard_fab2(sch_1):page139_i72@mstr_intel.springville(chips)!SPRINGVILLE_SM1-IC,G47144-004!!!F67!VDD0P9(2)!!!!
S!P0V9_LAN!EU9E1!42!@baseboard_fab2_lib.baseboard_fab2(sch_1):page139_i72@mstr_intel.springville(chips)!SPRINGVILLE_SM1-IC,G47144-004!!!F67!VDD0P9(3)!!!!
S!P0V9_LAN_I210!EU9E1!38!@baseboard_fab2_lib.baseboard_fab2(sch_1):page139_i72@mstr_intel.springville(chips)!SPRINGVILLE_SM1-IC,G47144-004!!!F67!VDD0P9_OUT!!!!
S!P1V5_LAN_I210!EU9E1!56!@baseboard_fab2_lib.baseboard_fab2(sch_1):page139_i72@mstr_intel.springville(chips)!SPRINGVILLE_SM1-IC,G47144-004!!!F67!VDD1P5(0)!!!!
S!P1V5_LAN!EU9E1!47!@baseboard_fab2_lib.baseboard_fab2(sch_1):page139_i72@mstr_intel.springville(chips)!SPRINGVILLE_SM1-IC,G47144-004!!!F67!VDD1P5(1)!!!!
S!P1V5_LAN!EU9E1!39!@baseboard_fab2_lib.baseboard_fab2(sch_1):page139_i72@mstr_intel.springville(chips)!SPRINGVILLE_SM1-IC,G47144-004!!!F67!VDD1P5_OUT!!!!
S!P3V3_STBY!EU9E1!64!@baseboard_fab2_lib.baseboard_fab2(sch_1):page139_i72@mstr_intel.springville(chips)!SPRINGVILLE_SM1-IC,G47144-004!!!F67!VDD3P3(0)!!!!
S!P3V3_STBY_P1V5_LAN_I210!EU9E1!51!@baseboard_fab2_lib.baseboard_fab2(sch_1):page139_i72@mstr_intel.springville(chips)!SPRINGVILLE_SM1-IC,G47144-004!!!F67!VDD3P3(1)!!!!
S!P3V3_STBY!EU9E1!41!@baseboard_fab2_lib.baseboard_fab2(sch_1):page139_i72@mstr_intel.springville(chips)!SPRINGVILLE_SM1-IC,G47144-004!!!F67!VDD3P3(2)!!!!
S!P3V3_STBY!EU9E1!27!@baseboard_fab2_lib.baseboard_fab2(sch_1):page139_i72@mstr_intel.springville(chips)!SPRINGVILLE_SM1-IC,G47144-004!!!F67!VDD3P3(3)!!!!
S!P3V3_STBY!EU9E1!10!@baseboard_fab2_lib.baseboard_fab2(sch_1):page139_i72@mstr_intel.springville(chips)!SPRINGVILLE_SM1-IC,G47144-004!!!F67!VDD3P3(4)!!!!
S!XTAL_25MHZ_IN_R!EU9E1!46!@baseboard_fab2_lib.baseboard_fab2(sch_1):page139_i72@mstr_intel.springville(chips)!SPRINGVILLE_SM1-IC,G47144-004!!!F67!XTAL1!!!!
S!XTAL_25MHZ_OUT!EU9E1!45!@baseboard_fab2_lib.baseboard_fab2(sch_1):page139_i72@mstr_intel.springville(chips)!SPRINGVILLE_SM1-IC,G47144-004!!!F67!XTAL2!!!!
S!GND!TH1A1!1!@baseboard_fab2_lib.baseboard_fab2(sch_1):page195_i56@mstr_misc.mtg_keyhole(chips)!MTG_KEYHOLE_TH-EMPTY,NA!!!F2013!\1\!!!!
S!GND!TH4A1!1!@baseboard_fab2_lib.baseboard_fab2(sch_1):page195_i62@mstr_misc.mtg_keyhole(chips)!MTG_KEYHOLE_TH-EMPTY,NA!!!F2012!\1\!!!!
S!GND!TH7A1!1!@baseboard_fab2_lib.baseboard_fab2(sch_1):page195_i65@mstr_misc.mtg_keyhole(chips)!MTG_KEYHOLE_TH-EMPTY,NA!!!F2010!\1\!!!!
S!GND!TH9A1!1!@baseboard_fab2_lib.baseboard_fab2(sch_1):page195_i54@mstr_misc.mtg_keyhole(chips)!MTG_KEYHOLE_TH-EMPTY,NA!!!F2008!\1\!!!!
S!GND!TH4G1!1!@baseboard_fab2_lib.baseboard_fab2(sch_1):page195_i49@mstr_misc.mtg_keyhole(chips)!MTG_KEYHOLE_TH-EMPTY,NA!!!F2011!\1\!!!!
S!GND!TH7G1!1!@baseboard_fab2_lib.baseboard_fab2(sch_1):page195_i67@mstr_misc.mtg_keyhole(chips)!MTG_KEYHOLE_TH-EMPTY,NA!!!F2009!\1\!!!!
S!GND!TH9G1!1!@baseboard_fab2_lib.baseboard_fab2(sch_1):page195_i52@mstr_misc.mtg_keyhole(chips)!MTG_KEYHOLE_TH-EMPTY,NA!!!F2007!\1\!!!!
S!PVCCIO_CPU1!R6P33!1!@baseboard_fab2_lib.baseboard_fab2(sch_1):page213_i30@mstr_discrete.res(chips)!RES_0402-110,1%,1/16W,EMPTY,G2A!!!F1110!A!!!!
S!SVID_CLK0_CPU1_R!R6P33!2!@baseboard_fab2_lib.baseboard_fab2(sch_1):page213_i30@mstr_discrete.res(chips)!RES_0402-110,1%,1/16W,EMPTY,G2A!!!F1110!B!!!!
S!A_USB2_COMP!R8B9!1!@baseboard_fab2_lib.baseboard_fab2(sch_1):page115_i90@mstr_discrete.res(chips)!RES_0402-113,1%,1/16W,CHIP,G21A!!!F1109!A!!!!
S!GND!R8B9!2!@baseboard_fab2_lib.baseboard_fab2(sch_1):page115_i90@mstr_discrete.res(chips)!RES_0402-113,1%,1/16W,CHIP,G21A!!!F1109!B!!!!
S!A_HSC_UV!R1D42!1!@baseboard_fab2_lib.baseboard_fab2(sch_1):page199_i13@mstr_discrete.res(chips)!RES_0402-11K,1%,1/16W,CHIP,G21A!!!F1108!A!!!!
S!AGND_HSC!R1D42!2!@baseboard_fab2_lib.baseboard_fab2(sch_1):page199_i13@mstr_discrete.res(chips)!RES_0402-11K,1%,1/16W,CHIP,G21A!!!F1108!B!!!!
S!P3V3_STBY!R1U49!1!@baseboard_fab2_lib.baseboard_fab2(sch_1):page169_i163@mstr_discrete.res(chips)!RES_0402-2.7K,1%,1/16W,CHIP,G2A!!!F991!A!!!!
S!FM_BATTERY_SENSE_EN!R1U49!2!@baseboard_fab2_lib.baseboard_fab2(sch_1):page169_i163@mstr_discrete.res(chips)!RES_0402-2.7K,1%,1/16W,CHIP,G2A!!!F991!B!!!!
S!P3V3_STBY!R9G35!1!@baseboard_fab2_lib.baseboard_fab2(sch_1):page169_i164@mstr_discrete.res(chips)!RES_0402-2.7K,1%,1/16W,CHIP,G2A!!!F987!A!!!!
S!FM_BATTERY_SENSE_EN_N!R9G35!2!@baseboard_fab2_lib.baseboard_fab2(sch_1):page169_i164@mstr_discrete.res(chips)!RES_0402-2.7K,1%,1/16W,CHIP,G2A!!!F987!B!!!!
S!P3V3_STBY!R1T4!1!@baseboard_fab2_lib.baseboard_fab2(sch_1):page164_i14@mstr_discrete.res(chips)!RES_0402-2.7K,1%,1/16W,CHIP,G2A!!!F994!A!!!!
S!FM_BOARD_REV_ID0!R1T4!2!@baseboard_fab2_lib.baseboard_fab2(sch_1):page164_i14@mstr_discrete.res(chips)!RES_0402-2.7K,1%,1/16W,CHIP,G2A!!!F994!B!!!!
S!P3V3_STBY!R1U23!1!@baseboard_fab2_lib.baseboard_fab2(sch_1):page164_i28@mstr_discrete.res(chips)!RES_0402-2.7K,1%,1/16W,CHIP,G2A!!!F993!A!!!!
S!FM_BOARD_SKU_ID0!R1U23!2!@baseboard_fab2_lib.baseboard_fab2(sch_1):page164_i28@mstr_discrete.res(chips)!RES_0402-2.7K,1%,1/16W,CHIP,G2A!!!F993!B!!!!
S!P3V3_STBY!R1U24!1!@baseboard_fab2_lib.baseboard_fab2(sch_1):page164_i25@mstr_discrete.res(chips)!RES_0402-2.7K,1%,1/16W,CHIP,G2A!!!F992!A!!!!
S!FM_BOARD_SKU_ID2!R1U24!2!@baseboard_fab2_lib.baseboard_fab2(sch_1):page164_i25@mstr_discrete.res(chips)!RES_0402-2.7K,1%,1/16W,CHIP,G2A!!!F992!B!!!!
S!P3V3_STBY!R9P4!1!@baseboard_fab2_lib.baseboard_fab2(sch_1):page200_i210@mstr_discrete.res(chips)!RES_0402-2.7K,1%,1/16W,CHIP,G2A!!!F989!A!!!!
S!IRQ_UV_DETECT_N!R9P4!2!@baseboard_fab2_lib.baseboard_fab2(sch_1):page200_i210@mstr_discrete.res(chips)!RES_0402-2.7K,1%,1/16W,CHIP,G2A!!!F989!B!!!!
S!P3V3_STBY!R9P20!1!@baseboard_fab2_lib.baseboard_fab2(sch_1):page200_i86@mstr_discrete.res(chips)!RES_0402-2.7K,1%,1/16W,CHIP,G2A!!!F988!A!!!!
S!FM_HSC_TIMER_EXP_N!R9P20!2!@baseboard_fab2_lib.baseboard_fab2(sch_1):page200_i86@mstr_discrete.res(chips)!RES_0402-2.7K,1%,1/16W,CHIP,G2A!!!F988!B!!!!
S!A_DACRSET!R9G8!1!@baseboard_fab2_lib.baseboard_fab2(sch_1):page144_i457@mstr_discrete.res(chips)!RES_0402-2.7K,1%,1/16W,CHIP,G2A!!!F990!A!!!!
S!GND!R9G8!2!@baseboard_fab2_lib.baseboard_fab2(sch_1):page144_i457@mstr_discrete.res(chips)!RES_0402-2.7K,1%,1/16W,CHIP,G2A!!!F990!B!!!!
S!P3V3_STBY!FB1U1!1!@baseboard_fab2_lib.baseboard_fab2(sch_1):page149_i140@mstr_discrete.ferrite(chips)!FERRITE_SMLF-300,FB,693286-046!!!F2187!A!!!!
S!P3V3_STBY_BMC_ADCAV33!FB1U1!2!@baseboard_fab2_lib.baseboard_fab2(sch_1):page149_i140@mstr_discrete.ferrite(chips)!FERRITE_SMLF-300,FB,693286-046!!!F2187!B!!!!
S!P1V26_BMC_STBY!FB9F1!1!@baseboard_fab2_lib.baseboard_fab2(sch_1):page149_i107@mstr_discrete.ferrite(chips)!FERRITE_SMLF-300,FB,693286-046!!!F2186!A!!!!
S!P1V26_BMC_STBY_V1PLLAV12!FB9F1!2!@baseboard_fab2_lib.baseboard_fab2(sch_1):page149_i107@mstr_discrete.ferrite(chips)!FERRITE_SMLF-300,FB,693286-046!!!F2186!B!!!!
S!P3V3_STBY!FB1T2!1!@baseboard_fab2_lib.baseboard_fab2(sch_1):page149_i122@mstr_discrete.ferrite(chips)!FERRITE_SMLF-300,FB,693286-046!!!F2188!A!!!!
S!P3V3_STBY_BMC_HPLLAV33!FB1T2!2!@baseboard_fab2_lib.baseboard_fab2(sch_1):page149_i122@mstr_discrete.ferrite(chips)!FERRITE_SMLF-300,FB,693286-046!!!F2188!B!!!!
S!VR_P1V05_PCH_STBY_PH1_PHASE_SW!L7A4!1!@baseboard_fab2_lib.baseboard_fab2(sch_1):page236_i45@mstr_discrete.inductor(chips)!INDUCTOR_SM-0.3UH,IND,D92183-0A!!!F2097!INA!!!!
S!P1V05_PCH_STBY!L7A4!2!@baseboard_fab2_lib.baseboard_fab2(sch_1):page236_i45@mstr_discrete.inductor(chips)!INDUCTOR_SM-0.3UH,IND,D92183-0A!!!F2097!INB!!!!
S!VR_PVNN_PCH_PH1_PHASE_SW!L7A2!1!@baseboard_fab2_lib.baseboard_fab2(sch_1):page236_i10@mstr_discrete.inductor(chips)!INDUCTOR_SM-0.3UH,IND,D92183-0A!!!F2098!INA!!!!
S!PVNN_PCH_STBY!L7A2!2!@baseboard_fab2_lib.baseboard_fab2(sch_1):page236_i10@mstr_discrete.inductor(chips)!INDUCTOR_SM-0.3UH,IND,D92183-0A!!!F2098!INB!!!!
S!VR_PVSA_CPU0_PHASE_SW!L4C2!1!@baseboard_fab2_lib.baseboard_fab2(sch_1):page205_i7@mstr_discrete.inductor(chips)!INDUCTOR_SM-0.3UH,IND,D92183-0A!!!F2099!INA!!!!
S!PVSA_CPU0!L4C2!2!@baseboard_fab2_lib.baseboard_fab2(sch_1):page205_i7@mstr_discrete.inductor(chips)!INDUCTOR_SM-0.3UH,IND,D92183-0A!!!F2099!INB!!!!
S!VR_PVSA_CPU1_PHASE_SW!L1C1!1!@baseboard_fab2_lib.baseboard_fab2(sch_1):page210_i10@mstr_discrete.inductor(chips)!INDUCTOR_SM-0.3UH,IND,D92183-0A!!!F2100!INA!!!!
S!PVSA_CPU1!L1C1!2!@baseboard_fab2_lib.baseboard_fab2(sch_1):page210_i10@mstr_discrete.inductor(chips)!INDUCTOR_SM-0.3UH,IND,D92183-0A!!!F2100!INB!!!!
S!VR_PVPP_DEF_PHASE!L7B1!1!@baseboard_fab2_lib.baseboard_fab2(sch_1):page232_i239@mstr_discrete.inductor(chips)!INDUCTOR_SM-0.47UH,IND,E13358-A!!!F2094!INA!!!!
S!PVPP_DEF!L7B1!2!@baseboard_fab2_lib.baseboard_fab2(sch_1):page232_i239@mstr_discrete.inductor(chips)!INDUCTOR_SM-0.47UH,IND,E13358-A!!!F2094!INB!!!!
S!VR_PVPP_GHJ_PHASE!L4G1!1!@baseboard_fab2_lib.baseboard_fab2(sch_1):page233_i277@mstr_discrete.inductor(chips)!INDUCTOR_SM-0.47UH,IND,E13358-A!!!F2095!INA!!!!
S!PVPP_GHJ!L4G1!2!@baseboard_fab2_lib.baseboard_fab2(sch_1):page233_i277@mstr_discrete.inductor(chips)!INDUCTOR_SM-0.47UH,IND,E13358-A!!!F2095!INB!!!!
S!VR_PVPP_KLM_PHASE!L4A1!1!@baseboard_fab2_lib.baseboard_fab2(sch_1):page234_i164@mstr_discrete.inductor(chips)!INDUCTOR_SM-0.47UH,IND,E13358-A!!!F2096!INA!!!!
S!PVPP_KLM!L4A1!2!@baseboard_fab2_lib.baseboard_fab2(sch_1):page234_i164@mstr_discrete.inductor(chips)!INDUCTOR_SM-0.47UH,IND,E13358-A!!!F2096!INB!!!!
S!VR_PVPP_ABC_PHASE!L7F1!1!@baseboard_fab2_lib.baseboard_fab2(sch_1):page231_i178@mstr_discrete.inductor(chips)!INDUCTOR_SM-0.47UH,IND,E13358-A!!!F2093!INA!!!!
S!PVPP_ABC!L7F1!2!@baseboard_fab2_lib.baseboard_fab2(sch_1):page231_i178@mstr_discrete.inductor(chips)!INDUCTOR_SM-0.47UH,IND,E13358-A!!!F2093!INB!!!!
S!P12V_PSU!J1D1!A1!@baseboard_fab2_lib.baseboard_fab2(sch_1):page195_i78@mstr_conn.conn12_g98257001(chips)!CONN12_G98257001_THMT-CONN,G98A!!!F2255!A1!!!!
S!P12V_PSU!J1D1!A2!@baseboard_fab2_lib.baseboard_fab2(sch_1):page195_i78@mstr_conn.conn12_g98257001(chips)!CONN12_G98257001_THMT-CONN,G98A!!!F2255!A2!!!!
S!P12V_PSU!J1D1!A3!@baseboard_fab2_lib.baseboard_fab2(sch_1):page195_i78@mstr_conn.conn12_g98257001(chips)!CONN12_G98257001_THMT-CONN,G98A!!!F2255!A3!!!!
S!P12V_PSU!J1D1!B1!@baseboard_fab2_lib.baseboard_fab2(sch_1):page195_i78@mstr_conn.conn12_g98257001(chips)!CONN12_G98257001_THMT-CONN,G98A!!!F2255!B1!!!!
S!P12V_PSU!J1D1!B2!@baseboard_fab2_lib.baseboard_fab2(sch_1):page195_i78@mstr_conn.conn12_g98257001(chips)!CONN12_G98257001_THMT-CONN,G98A!!!F2255!B2!!!!
S!P12V_PSU!J1D1!B3!@baseboard_fab2_lib.baseboard_fab2(sch_1):page195_i78@mstr_conn.conn12_g98257001(chips)!CONN12_G98257001_THMT-CONN,G98A!!!F2255!B3!!!!
S!GND!J1D1!C1!@baseboard_fab2_lib.baseboard_fab2(sch_1):page195_i78@mstr_conn.conn12_g98257001(chips)!CONN12_G98257001_THMT-CONN,G98A!!!F2255!C1!!!!
S!GND!J1D1!C2!@baseboard_fab2_lib.baseboard_fab2(sch_1):page195_i78@mstr_conn.conn12_g98257001(chips)!CONN12_G98257001_THMT-CONN,G98A!!!F2255!C2!!!!
S!GND!J1D1!C3!@baseboard_fab2_lib.baseboard_fab2(sch_1):page195_i78@mstr_conn.conn12_g98257001(chips)!CONN12_G98257001_THMT-CONN,G98A!!!F2255!C3!!!!
S!GND!J1D1!D1!@baseboard_fab2_lib.baseboard_fab2(sch_1):page195_i78@mstr_conn.conn12_g98257001(chips)!CONN12_G98257001_THMT-CONN,G98A!!!F2255!D1!!!!
S!GND!J1D1!D2!@baseboard_fab2_lib.baseboard_fab2(sch_1):page195_i78@mstr_conn.conn12_g98257001(chips)!CONN12_G98257001_THMT-CONN,G98A!!!F2255!D2!!!!
S!GND!J1D1!D3!@baseboard_fab2_lib.baseboard_fab2(sch_1):page195_i78@mstr_conn.conn12_g98257001(chips)!CONN12_G98257001_THMT-CONN,G98A!!!F2255!D3!!!!
S!P12V_PSU!J1E1!A1!@baseboard_fab2_lib.baseboard_fab2(sch_1):page195_i29@mstr_conn.conn12_g98257001(chips)!CONN12_G98257001_THMT-CONN,G98A!!!F2254!A1!!!!
S!P12V_PSU!J1E1!A2!@baseboard_fab2_lib.baseboard_fab2(sch_1):page195_i29@mstr_conn.conn12_g98257001(chips)!CONN12_G98257001_THMT-CONN,G98A!!!F2254!A2!!!!
S!P12V_PSU!J1E1!A3!@baseboard_fab2_lib.baseboard_fab2(sch_1):page195_i29@mstr_conn.conn12_g98257001(chips)!CONN12_G98257001_THMT-CONN,G98A!!!F2254!A3!!!!
S!P12V_PSU!J1E1!B1!@baseboard_fab2_lib.baseboard_fab2(sch_1):page195_i29@mstr_conn.conn12_g98257001(chips)!CONN12_G98257001_THMT-CONN,G98A!!!F2254!B1!!!!
S!P12V_PSU!J1E1!B2!@baseboard_fab2_lib.baseboard_fab2(sch_1):page195_i29@mstr_conn.conn12_g98257001(chips)!CONN12_G98257001_THMT-CONN,G98A!!!F2254!B2!!!!
S!P12V_PSU!J1E1!B3!@baseboard_fab2_lib.baseboard_fab2(sch_1):page195_i29@mstr_conn.conn12_g98257001(chips)!CONN12_G98257001_THMT-CONN,G98A!!!F2254!B3!!!!
S!GND!J1E1!C1!@baseboard_fab2_lib.baseboard_fab2(sch_1):page195_i29@mstr_conn.conn12_g98257001(chips)!CONN12_G98257001_THMT-CONN,G98A!!!F2254!C1!!!!
S!GND!J1E1!C2!@baseboard_fab2_lib.baseboard_fab2(sch_1):page195_i29@mstr_conn.conn12_g98257001(chips)!CONN12_G98257001_THMT-CONN,G98A!!!F2254!C2!!!!
S!GND!J1E1!C3!@baseboard_fab2_lib.baseboard_fab2(sch_1):page195_i29@mstr_conn.conn12_g98257001(chips)!CONN12_G98257001_THMT-CONN,G98A!!!F2254!C3!!!!
S!GND!J1E1!D1!@baseboard_fab2_lib.baseboard_fab2(sch_1):page195_i29@mstr_conn.conn12_g98257001(chips)!CONN12_G98257001_THMT-CONN,G98A!!!F2254!D1!!!!
S!GND!J1E1!D2!@baseboard_fab2_lib.baseboard_fab2(sch_1):page195_i29@mstr_conn.conn12_g98257001(chips)!CONN12_G98257001_THMT-CONN,G98A!!!F2254!D2!!!!
S!GND!J1E1!D3!@baseboard_fab2_lib.baseboard_fab2(sch_1):page195_i29@mstr_conn.conn12_g98257001(chips)!CONN12_G98257001_THMT-CONN,G98A!!!F2254!D3!!!!
S!P1V05_PCH_STBY!FB3M1!1!@baseboard_fab2_lib.baseboard_fab2(sch_1):page127_i8@mstr_discrete.ferrite(chips)!FERRITE_SM-120,FB,693286-027!!!F2202!A!!!!
S!P1V05_PCH_STBY_VCCA_PLL1!FB3M1!2!@baseboard_fab2_lib.baseboard_fab2(sch_1):page127_i8@mstr_discrete.ferrite(chips)!FERRITE_SM-120,FB,693286-027!!!F2202!B!!!!
S!P1V05_PCH_STBY!FB3M2!1!@baseboard_fab2_lib.baseboard_fab2(sch_1):page127_i17@mstr_discrete.ferrite(chips)!FERRITE_SM-120,FB,693286-027!!!F2201!A!!!!
S!P1V05_PCH_STBY_VCCA_PLL0!FB3M2!2!@baseboard_fab2_lib.baseboard_fab2(sch_1):page127_i17@mstr_discrete.ferrite(chips)!FERRITE_SM-120,FB,693286-027!!!F2201!B!!!!
S!P1V05_PCH_STBY!FB3M3!1!@baseboard_fab2_lib.baseboard_fab2(sch_1):page127_i26@mstr_discrete.ferrite(chips)!FERRITE_SM-120,FB,693286-027!!!F2200!A!!!!
S!P1V05_PCH_STBY_VCCA_XTAL!FB3M3!2!@baseboard_fab2_lib.baseboard_fab2(sch_1):page127_i26@mstr_discrete.ferrite(chips)!FERRITE_SM-120,FB,693286-027!!!F2200!B!!!!
S!P1V05_PCH_STBY!FB3M4!1!@baseboard_fab2_lib.baseboard_fab2(sch_1):page127_i56@mstr_discrete.ferrite(chips)!FERRITE_SM-120,FB,693286-027!!!F2199!A!!!!
S!P1V05_PCH_STBY_ISCLK_PLL!FB3M4!2!@baseboard_fab2_lib.baseboard_fab2(sch_1):page127_i56@mstr_discrete.ferrite(chips)!FERRITE_SM-120,FB,693286-027!!!F2199!B!!!!
S!P1V05_PCH_STBY!FB2M1!1!@baseboard_fab2_lib.baseboard_fab2(sch_1):page127_i46@mstr_discrete.ferrite(chips)!FERRITE_SM-120,FB,693286-027!!!F2204!A!!!!
S!P1V05_PCH_STBY_WM20_PLL!FB2M1!2!@baseboard_fab2_lib.baseboard_fab2(sch_1):page127_i46@mstr_discrete.ferrite(chips)!FERRITE_SM-120,FB,693286-027!!!F2204!B!!!!
S!P1V05_PCH_STBY!FB2M2!1!@baseboard_fab2_lib.baseboard_fab2(sch_1):page127_i69@mstr_discrete.ferrite(chips)!FERRITE_SM-120,FB,693286-027!!!F2203!A!!!!
S!P1V05_PCH_STBY_WM26_PLL!FB2M2!2!@baseboard_fab2_lib.baseboard_fab2(sch_1):page127_i69@mstr_discrete.ferrite(chips)!FERRITE_SM-120,FB,693286-027!!!F2203!B!!!!
S!LED_LAN_0_R_N!R9G3!1!@baseboard_fab2_lib.baseboard_fab2(sch_1):page141_i28@mstr_discrete.res(chips)!RES_0402-330.0,5%,1/16W,CHIP,GA!!!F661!A!!!!
S!LED_LAN_0_N!R9G3!2!@baseboard_fab2_lib.baseboard_fab2(sch_1):page141_i28@mstr_discrete.res(chips)!RES_0402-330.0,5%,1/16W,CHIP,GA!!!F661!B!!!!
S!LED_LAN_2_R_N!R9G2!1!@baseboard_fab2_lib.baseboard_fab2(sch_1):page141_i30@mstr_discrete.res(chips)!RES_0402-330.0,5%,1/16W,CHIP,GA!!!F662!A!!!!
S!LED_LAN_2_N!R9G2!2!@baseboard_fab2_lib.baseboard_fab2(sch_1):page141_i30@mstr_discrete.res(chips)!RES_0402-330.0,5%,1/16W,CHIP,GA!!!F662!B!!!!
S!LED_LAN_1_N!R9G1!1!@baseboard_fab2_lib.baseboard_fab2(sch_1):page141_i54@mstr_discrete.res(chips)!RES_0402-330.0,5%,1/16W,CHIP,GA!!!F663!A!!!!
S!LED_LAN_1_R_N!R9G1!2!@baseboard_fab2_lib.baseboard_fab2(sch_1):page141_i54@mstr_discrete.res(chips)!RES_0402-330.0,5%,1/16W,CHIP,GA!!!F663!B!!!!
S!FM_BOARD_REV_ID0!R1T10!1!@baseboard_fab2_lib.baseboard_fab2(sch_1):page164_i5@mstr_discrete.res(chips)!RES_0402-1.00K,1%,1/16W,EMPTY,A!!!F1428!A!!!!
S!GND!R1T10!2!@baseboard_fab2_lib.baseboard_fab2(sch_1):page164_i5@mstr_discrete.res(chips)!RES_0402-1.00K,1%,1/16W,EMPTY,A!!!F1428!B!!!!
S!FM_BOARD_SKU_ID2!R1U17!1!@baseboard_fab2_lib.baseboard_fab2(sch_1):page164_i21@mstr_discrete.res(chips)!RES_0402-1.00K,1%,1/16W,EMPTY,A!!!F1427!A!!!!
S!GND!R1U17!2!@baseboard_fab2_lib.baseboard_fab2(sch_1):page164_i21@mstr_discrete.res(chips)!RES_0402-1.00K,1%,1/16W,EMPTY,A!!!F1427!B!!!!
S!FM_BOARD_SKU_ID0!R1U18!1!@baseboard_fab2_lib.baseboard_fab2(sch_1):page164_i19@mstr_discrete.res(chips)!RES_0402-1.00K,1%,1/16W,EMPTY,A!!!F1426!A!!!!
S!GND!R1U18!2!@baseboard_fab2_lib.baseboard_fab2(sch_1):page164_i19@mstr_discrete.res(chips)!RES_0402-1.00K,1%,1/16W,EMPTY,A!!!F1426!B!!!!
S!P3V3_STBY!R7E19!1!@baseboard_fab2_lib.baseboard_fab2(sch_1):page192_i57@mstr_discrete.res(chips)!RES_0402-1.00K,1%,1/16W,EMPTY,A!!!F1410!A!!!!
S!FM_MEM_EVENT_FUNC!R7E19!2!@baseboard_fab2_lib.baseboard_fab2(sch_1):page192_i57@mstr_discrete.res(chips)!RES_0402-1.00K,1%,1/16W,EMPTY,A!!!F1410!B!!!!
S!JTAG_MCP_TRST_N!R1M23!1!@baseboard_fab2_lib.baseboard_fab2(sch_1):page113_i199@mstr_discrete.res(chips)!RES_0402-1.00K,1%,1/16W,EMPTY,A!!!F1411!A!!!!
S!GND!R1M23!2!@baseboard_fab2_lib.baseboard_fab2(sch_1):page113_i199@mstr_discrete.res(chips)!RES_0402-1.00K,1%,1/16W,EMPTY,A!!!F1411!B!!!!
S!P3V3_STBY!R2N14!1!@baseboard_fab2_lib.baseboard_fab2(sch_1):page125_i83@mstr_discrete.res(chips)!RES_0402-1.00K,1%,1/16W,EMPTY,A!!!F1425!A!!!!
S!FM_USB_P0_EN_BOOT_BIOS_STRAP_N!R2N14!2!@baseboard_fab2_lib.baseboard_fab2(sch_1):page125_i83@mstr_discrete.res(chips)!RES_0402-1.00K,1%,1/16W,EMPTY,A!!!F1425!B!!!!
S!FM_OC_DETECT_EN_N!R7D19!1!@baseboard_fab2_lib.baseboard_fab2(sch_1):page126_i6@mstr_discrete.res(chips)!RES_0402-1.00K,1%,1/16W,EMPTY,A!!!F1418!A!!!!
S!GND!R7D19!2!@baseboard_fab2_lib.baseboard_fab2(sch_1):page126_i6@mstr_discrete.res(chips)!RES_0402-1.00K,1%,1/16W,EMPTY,A!!!F1418!B!!!!
S!P3V3_STBY!R8E6!1!@baseboard_fab2_lib.baseboard_fab2(sch_1):page125_i21@mstr_discrete.res(chips)!RES_0402-1.00K,1%,1/16W,EMPTY,A!!!F1414!A!!!!
S!SPI_PCH_MOSI!R8E6!2!@baseboard_fab2_lib.baseboard_fab2(sch_1):page125_i21@mstr_discrete.res(chips)!RES_0402-1.00K,1%,1/16W,EMPTY,A!!!F1414!B!!!!
S!P3V3_STBY!R3N17!1!@baseboard_fab2_lib.baseboard_fab2(sch_1):page125_i78@mstr_discrete.res(chips)!RES_0402-1.00K,1%,1/16W,EMPTY,A!!!F1421!A!!!!
S!SPI_PCH_IO3!R3N17!2!@baseboard_fab2_lib.baseboard_fab2(sch_1):page125_i78@mstr_discrete.res(chips)!RES_0402-1.00K,1%,1/16W,EMPTY,A!!!F1421!B!!!!
S!FM_QAT_EN_N!R2N24!1!@baseboard_fab2_lib.baseboard_fab2(sch_1):page134_i18@mstr_discrete.res(chips)!RES_0402-1.00K,1%,1/16W,EMPTY,A!!!F1424!A!!!!
S!GND!R2N24!2!@baseboard_fab2_lib.baseboard_fab2(sch_1):page134_i18@mstr_discrete.res(chips)!RES_0402-1.00K,1%,1/16W,EMPTY,A!!!F1424!B!!!!
S!FM_PMBUS_ALERT_BUF_EN_N!R2P11!1!@baseboard_fab2_lib.baseboard_fab2(sch_1):page170_i63@mstr_discrete.res(chips)!RES_0402-1.00K,1%,1/16W,EMPTY,A!!!F1423!A!!!!
S!GND!R2P11!2!@baseboard_fab2_lib.baseboard_fab2(sch_1):page170_i63@mstr_discrete.res(chips)!RES_0402-1.00K,1%,1/16W,EMPTY,A!!!F1423!B!!!!
S!P3V3!R9A1!1!@baseboard_fab2_lib.baseboard_fab2(sch_1):page111_i95@mstr_discrete.res(chips)!RES_0402-1.00K,1%,1/16W,EMPTY,A!!!F1412!A!!!!
S!XDP_CPU_TCK_BUF!R9A1!2!@baseboard_fab2_lib.baseboard_fab2(sch_1):page111_i95@mstr_discrete.res(chips)!RES_0402-1.00K,1%,1/16W,EMPTY,A!!!F1412!B!!!!
S!PU_SPI_BMC_BT_WP_N!R8F35!1!@baseboard_fab2_lib.baseboard_fab2(sch_1):page162_i24@mstr_discrete.res(chips)!RES_0402-1.00K,1%,1/16W,EMPTY,A!!!F1413!A!!!!
S!GND!R8F35!2!@baseboard_fab2_lib.baseboard_fab2(sch_1):page162_i24@mstr_discrete.res(chips)!RES_0402-1.00K,1%,1/16W,EMPTY,A!!!F1413!B!!!!
S!PU_PCH_TLS_ENABLE_STRAP!R8C17!1!@baseboard_fab2_lib.baseboard_fab2(sch_1):page125_i41@mstr_discrete.res(chips)!RES_0402-1.00K,1%,1/16W,EMPTY,A!!!F1417!A!!!!
S!GND!R8C17!2!@baseboard_fab2_lib.baseboard_fab2(sch_1):page125_i41@mstr_discrete.res(chips)!RES_0402-1.00K,1%,1/16W,EMPTY,A!!!F1417!B!!!!
S!SPI_PCH_MOSI!R8E4!1!@baseboard_fab2_lib.baseboard_fab2(sch_1):page125_i24@mstr_discrete.res(chips)!RES_0402-1.00K,1%,1/16W,EMPTY,A!!!F1415!A!!!!
S!GND!R8E4!2!@baseboard_fab2_lib.baseboard_fab2(sch_1):page125_i24@mstr_discrete.res(chips)!RES_0402-1.00K,1%,1/16W,EMPTY,A!!!F1415!B!!!!
S!SPI_PCH_IO2!R2R11!1!@baseboard_fab2_lib.baseboard_fab2(sch_1):page125_i11@mstr_discrete.res(chips)!RES_0402-1.00K,1%,1/16W,EMPTY,A!!!F1422!A!!!!
S!GND!R2R11!2!@baseboard_fab2_lib.baseboard_fab2(sch_1):page125_i11@mstr_discrete.res(chips)!RES_0402-1.00K,1%,1/16W,EMPTY,A!!!F1422!B!!!!
S!PU_ADR_TIMER_HOLD_OFF_N!R8D5!1!@baseboard_fab2_lib.baseboard_fab2(sch_1):page125_i50@mstr_discrete.res(chips)!RES_0402-1.00K,1%,1/16W,EMPTY,A!!!F1416!A!!!!
S!GND!R8D5!2!@baseboard_fab2_lib.baseboard_fab2(sch_1):page125_i50@mstr_discrete.res(chips)!RES_0402-1.00K,1%,1/16W,EMPTY,A!!!F1416!B!!!!
S!VSENSE_PVCCIN_CPU1_P!R1E5!1!@baseboard_fab2_lib.baseboard_fab2(sch_1):page209_i3@mstr_discrete.res(chips)!RES_0402-1.00K,1%,1/16W,EMPTY,A!!!F1429!A!!!!
S!VSENSE_PVCCIN_CPU1_N!R1E5!2!@baseboard_fab2_lib.baseboard_fab2(sch_1):page209_i3@mstr_discrete.res(chips)!RES_0402-1.00K,1%,1/16W,EMPTY,A!!!F1429!B!!!!
S!VSENSE_PVSA_CPU0_P!R4C3!1!@baseboard_fab2_lib.baseboard_fab2(sch_1):page205_i37@mstr_discrete.res(chips)!RES_0402-1.00K,1%,1/16W,EMPTY,A!!!F1420!A!!!!
S!VSENSE_PVSA_CPU0_N!R4C3!2!@baseboard_fab2_lib.baseboard_fab2(sch_1):page205_i37@mstr_discrete.res(chips)!RES_0402-1.00K,1%,1/16W,EMPTY,A!!!F1420!B!!!!
S!VSENSE_PVCCIN_CPU0_P!R4E15!1!@baseboard_fab2_lib.baseboard_fab2(sch_1):page204_i63@mstr_discrete.res(chips)!RES_0402-1.00K,1%,1/16W,EMPTY,A!!!F1419!A!!!!
S!VSENSE_PVCCIN_CPU0_N!R4E15!2!@baseboard_fab2_lib.baseboard_fab2(sch_1):page204_i63@mstr_discrete.res(chips)!RES_0402-1.00K,1%,1/16W,EMPTY,A!!!F1419!B!!!!
S!VSENSE_PVSA_CPU1_P!R1C6!1!@baseboard_fab2_lib.baseboard_fab2(sch_1):page210_i34@mstr_discrete.res(chips)!RES_0402-1.00K,1%,1/16W,EMPTY,A!!!F1430!A!!!!
S!VSENSE_PVSA_CPU1_N!R1C6!2!@baseboard_fab2_lib.baseboard_fab2(sch_1):page210_i34@mstr_discrete.res(chips)!RES_0402-1.00K,1%,1/16W,EMPTY,A!!!F1430!B!!!!
S!P3V3_STBY!R2N10!1!@baseboard_fab2_lib.baseboard_fab2(sch_1):page126_i10@mstr_discrete.res(chips)!RES_0402-1.0M,1%,1/16W,CHIP,G2A!!!F1401!A!!!!
S!FM_PCH_BMC_THERMTRIP_EXI_STRAP_!R2N10!2!@baseboard_fab2_lib.baseboard_fab2(sch_1):page126_i10@mstr_discrete.res(chips)!RES_0402-1.0M,1%,1/16W,CHIP,G2A!!!F1401!B!!!!
S!P3V3!R6L4!1!@baseboard_fab2_lib.baseboard_fab2(sch_1):page222_i37@mstr_discrete.res(chips)!RES_0402-1.0M,1%,1/16W,EMPTY,GA!!!F1400!A!!!!
S!FM_PVTT_DEF_EN_R!R6L4!2!@baseboard_fab2_lib.baseboard_fab2(sch_1):page222_i37@mstr_discrete.res(chips)!RES_0402-1.0M,1%,1/16W,EMPTY,GA!!!F1400!B!!!!
S!P3V3!R6U3!1!@baseboard_fab2_lib.baseboard_fab2(sch_1):page229_i34@mstr_discrete.res(chips)!RES_0402-1.0M,1%,1/16W,EMPTY,GA!!!F1398!A!!!!
S!FM_PVTT_GHJ_EN_R!R6U3!2!@baseboard_fab2_lib.baseboard_fab2(sch_1):page229_i34@mstr_discrete.res(chips)!RES_0402-1.0M,1%,1/16W,EMPTY,GA!!!F1398!B!!!!
S!P3V3!R6U15!1!@baseboard_fab2_lib.baseboard_fab2(sch_1):page221_i37@mstr_discrete.res(chips)!RES_0402-1.0M,1%,1/16W,EMPTY,GA!!!F1397!A!!!!
S!FM_PVTT_ABC_EN_R!R6U15!2!@baseboard_fab2_lib.baseboard_fab2(sch_1):page221_i37@mstr_discrete.res(chips)!RES_0402-1.0M,1%,1/16W,EMPTY,GA!!!F1397!B!!!!
S!P3V3!R6L5!1!@baseboard_fab2_lib.baseboard_fab2(sch_1):page230_i37@mstr_discrete.res(chips)!RES_0402-1.0M,1%,1/16W,EMPTY,GA!!!F1399!A!!!!
S!FM_PVTT_KLM_EN_R!R6L5!2!@baseboard_fab2_lib.baseboard_fab2(sch_1):page230_i37@mstr_discrete.res(chips)!RES_0402-1.0M,1%,1/16W,EMPTY,GA!!!F1399!B!!!!
S!GND!R7C11!1!@baseboard_fab2_lib.baseboard_fab2(sch_1):page137_i11@mstr_discrete.res(chips)!RES_0402-1.0M,1%,1/16W,EMPTY,GA!!!F1396!A!!!!
S!RST_RTCRST_N!R7C11!2!@baseboard_fab2_lib.baseboard_fab2(sch_1):page137_i11@mstr_discrete.res(chips)!RES_0402-1.0M,1%,1/16W,EMPTY,GA!!!F1396!B!!!!
S!VR_PVDDQ_KLM_VINSEN!R1B9!1!@baseboard_fab2_lib.baseboard_fab2(sch_1):page226_i58@mstr_discrete.res(chips)!RES_0402-1.5K,1%,1/16W,CHIP,G2A!!!F1394!A!!!!
S!GND!R1B9!2!@baseboard_fab2_lib.baseboard_fab2(sch_1):page226_i58@mstr_discrete.res(chips)!RES_0402-1.5K,1%,1/16W,CHIP,G2A!!!F1394!B!!!!
S!VR_PVCCIN_CPU1_AVINSEN!R1C16!1!@baseboard_fab2_lib.baseboard_fab2(sch_1):page206_i56@mstr_discrete.res(chips)!RES_0402-1.5K,1%,1/16W,CHIP,G2A!!!F1393!A!!!!
S!GND!R1C16!2!@baseboard_fab2_lib.baseboard_fab2(sch_1):page206_i56@mstr_discrete.res(chips)!RES_0402-1.5K,1%,1/16W,CHIP,G2A!!!F1393!B!!!!
S!VR_PVDDQ_GHJ_VINSEN!R1G24!1!@baseboard_fab2_lib.baseboard_fab2(sch_1):page223_i58@mstr_discrete.res(chips)!RES_0402-1.5K,1%,1/16W,CHIP,G2A!!!F1392!A!!!!
S!GND!R1G24!2!@baseboard_fab2_lib.baseboard_fab2(sch_1):page223_i58@mstr_discrete.res(chips)!RES_0402-1.5K,1%,1/16W,CHIP,G2A!!!F1392!B!!!!
S!VR_PVNN_PCH_VINSEN!R2L10!1!@baseboard_fab2_lib.baseboard_fab2(sch_1):page235_i166@mstr_discrete.res(chips)!RES_0402-1.5K,1%,1/16W,CHIP,G2A!!!F1390!A!!!!
S!GND!R2L10!2!@baseboard_fab2_lib.baseboard_fab2(sch_1):page235_i166@mstr_discrete.res(chips)!RES_0402-1.5K,1%,1/16W,CHIP,G2A!!!F1390!B!!!!
S!VR_PVCCIO_CPU0_VINSEN!R3P16!1!@baseboard_fab2_lib.baseboard_fab2(sch_1):page211_i32@mstr_discrete.res(chips)!RES_0402-1.5K,1%,1/16W,CHIP,G2A!!!F1389!A!!!!
S!GND!R3P16!2!@baseboard_fab2_lib.baseboard_fab2(sch_1):page211_i32@mstr_discrete.res(chips)!RES_0402-1.5K,1%,1/16W,CHIP,G2A!!!F1389!B!!!!
S!VR_PVCCIN_CPU0_AVINSEN!R4D32!1!@baseboard_fab2_lib.baseboard_fab2(sch_1):page201_i55@mstr_discrete.res(chips)!RES_0402-1.5K,1%,1/16W,CHIP,G2A!!!F1388!A!!!!
S!GND!R4D32!2!@baseboard_fab2_lib.baseboard_fab2(sch_1):page201_i55@mstr_discrete.res(chips)!RES_0402-1.5K,1%,1/16W,CHIP,G2A!!!F1388!B!!!!
S!VR_PVCCIO_CPU1_VINSEN!R4D57!1!@baseboard_fab2_lib.baseboard_fab2(sch_1):page213_i32@mstr_discrete.res(chips)!RES_0402-1.5K,1%,1/16W,CHIP,G2A!!!F1387!A!!!!
S!GND!R4D57!2!@baseboard_fab2_lib.baseboard_fab2(sch_1):page213_i32@mstr_discrete.res(chips)!RES_0402-1.5K,1%,1/16W,CHIP,G2A!!!F1387!B!!!!
S!VR_PVDDQ_DEF_VINSEN!R7A16!1!@baseboard_fab2_lib.baseboard_fab2(sch_1):page218_i54@mstr_discrete.res(chips)!RES_0402-1.5K,1%,1/16W,CHIP,G2A!!!F1386!A!!!!
S!GND!R7A16!2!@baseboard_fab2_lib.baseboard_fab2(sch_1):page218_i54@mstr_discrete.res(chips)!RES_0402-1.5K,1%,1/16W,CHIP,G2A!!!F1386!B!!!!
S!VR_PVDDQ_ABC_VINSEN!R7G3!1!@baseboard_fab2_lib.baseboard_fab2(sch_1):page215_i337@mstr_discrete.res(chips)!RES_0402-1.5K,1%,1/16W,CHIP,G2A!!!F1385!A!!!!
S!GND!R7G3!2!@baseboard_fab2_lib.baseboard_fab2(sch_1):page215_i337@mstr_discrete.res(chips)!RES_0402-1.5K,1%,1/16W,CHIP,G2A!!!F1385!B!!!!
S!P3V3_STBY!R1U52!1!@baseboard_fab2_lib.baseboard_fab2(sch_1):page144_i557@mstr_discrete.res(chips)!RES_0402-1.5K,1%,1/16W,CHIP,G2A!!!F1391!A!!!!
S!USB_PCH_BMC_P4_DN!R1U52!2!@baseboard_fab2_lib.baseboard_fab2(sch_1):page144_i557@mstr_discrete.res(chips)!RES_0402-1.5K,1%,1/16W,CHIP,G2A!!!F1391!B!!!!
S!P12V_PSU!R9T6!1!@baseboard_fab2_lib.baseboard_fab2(sch_1):page181_i183@mstr_discrete.res(chips)!RES_0402-15.0K,1%,1/16W,CHIP,GA!!!F1103!A!!!!
S!FM_P12V_HOTSWAP0_EN!R9T6!2!@baseboard_fab2_lib.baseboard_fab2(sch_1):page181_i183@mstr_discrete.res(chips)!RES_0402-15.0K,1%,1/16W,CHIP,GA!!!F1103!B!!!!
S!P12V_STBY!R9P18!1!@baseboard_fab2_lib.baseboard_fab2(sch_1):page199_i41@mstr_discrete.res(chips)!RES_0402-15.0K,1%,1/16W,CHIP,GA!!!F1104!A!!!!
S!PWRGD_P12V_R!R9P18!2!@baseboard_fab2_lib.baseboard_fab2(sch_1):page199_i41@mstr_discrete.res(chips)!RES_0402-15.0K,1%,1/16W,CHIP,GA!!!F1104!B!!!!
S!P3V3_STBY!R9M17!1!@baseboard_fab2_lib.baseboard_fab2(sch_1):page163_i15@mstr_discrete.res(chips)!RES_0402-2.0K,1%,1/16W,CHIP,G2A!!!F1037!A!!!!
S!SMB_PEHPCPU1_STBY_LVC3_R_SCL!R9M17!2!@baseboard_fab2_lib.baseboard_fab2(sch_1):page163_i15@mstr_discrete.res(chips)!RES_0402-2.0K,1%,1/16W,CHIP,G2A!!!F1037!B!!!!
S!P3V3_STBY!R9M16!1!@baseboard_fab2_lib.baseboard_fab2(sch_1):page163_i16@mstr_discrete.res(chips)!RES_0402-2.0K,1%,1/16W,CHIP,G2A!!!F1038!A!!!!
S!SMB_PEHPCPU1_STBY_LVC3_R_SDA!R9M16!2!@baseboard_fab2_lib.baseboard_fab2(sch_1):page163_i16@mstr_discrete.res(chips)!RES_0402-2.0K,1%,1/16W,CHIP,G2A!!!F1038!B!!!!
S!P3V3_STBY!R8D17!1!@baseboard_fab2_lib.baseboard_fab2(sch_1):page138_i87@mstr_discrete.res(chips)!RES_0402-2.0K,1%,1/16W,CHIP,G2A!!!F1039!A!!!!
S!SMB_VR_STBY_LVC3_SDA!R8D17!2!@baseboard_fab2_lib.baseboard_fab2(sch_1):page138_i87@mstr_discrete.res(chips)!RES_0402-2.0K,1%,1/16W,CHIP,G2A!!!F1039!B!!!!
S!P3V3_STBY!R8D15!1!@baseboard_fab2_lib.baseboard_fab2(sch_1):page138_i88@mstr_discrete.res(chips)!RES_0402-2.0K,1%,1/16W,CHIP,G2A!!!F1040!A!!!!
S!SMB_VR_STBY_LVC3_SCL!R8D15!2!@baseboard_fab2_lib.baseboard_fab2(sch_1):page138_i88@mstr_discrete.res(chips)!RES_0402-2.0K,1%,1/16W,CHIP,G2A!!!F1040!B!!!!
S!GND!R3N3!1!@baseboard_fab2_lib.baseboard_fab2(sch_1):page133_i120@mstr_discrete.res(chips)!RES_0402-2.0K,1%,1/16W,CHIP,G2A!!!F1041!A!!!!
S!PWRGD_PCH_PWROK!R3N3!2!@baseboard_fab2_lib.baseboard_fab2(sch_1):page133_i120@mstr_discrete.res(chips)!RES_0402-2.0K,1%,1/16W,CHIP,G2A!!!F1041!B!!!!
S!P3V3_STBY!R2L12!1!@baseboard_fab2_lib.baseboard_fab2(sch_1):page178_i2@mstr_discrete.res(chips)!RES_0402-2.0K,1%,1/16W,CHIP,G2A!!!F1045!A!!!!
S!SGPIO_PCH_SATA_LOAD_R!R2L12!2!@baseboard_fab2_lib.baseboard_fab2(sch_1):page178_i2@mstr_discrete.res(chips)!RES_0402-2.0K,1%,1/16W,CHIP,G2A!!!F1045!B!!!!
S!P3V3_STBY!R2L5!1!@baseboard_fab2_lib.baseboard_fab2(sch_1):page178_i20@mstr_discrete.res(chips)!RES_0402-2.0K,1%,1/16W,CHIP,G2A!!!F1048!A!!!!
S!SGPIO_PCH_SSATA_LOAD_R!R2L5!2!@baseboard_fab2_lib.baseboard_fab2(sch_1):page178_i20@mstr_discrete.res(chips)!RES_0402-2.0K,1%,1/16W,CHIP,G2A!!!F1048!B!!!!
S!P3V3_STBY!R2L4!1!@baseboard_fab2_lib.baseboard_fab2(sch_1):page178_i18@mstr_discrete.res(chips)!RES_0402-2.0K,1%,1/16W,CHIP,G2A!!!F1049!A!!!!
S!SGPIO_PCH_SSATA_DOUT0_R!R2L4!2!@baseboard_fab2_lib.baseboard_fab2(sch_1):page178_i18@mstr_discrete.res(chips)!RES_0402-2.0K,1%,1/16W,CHIP,G2A!!!F1049!B!!!!
S!P3V3_STBY!R2L15!1!@baseboard_fab2_lib.baseboard_fab2(sch_1):page178_i12@mstr_discrete.res(chips)!RES_0402-2.0K,1%,1/16W,CHIP,G2A!!!F1044!A!!!!
S!SGPIO_PCH_SATA_DOUT0_R!R2L15!2!@baseboard_fab2_lib.baseboard_fab2(sch_1):page178_i12@mstr_discrete.res(chips)!RES_0402-2.0K,1%,1/16W,CHIP,G2A!!!F1044!B!!!!
S!P3V3_STBY!R2L6!1!@baseboard_fab2_lib.baseboard_fab2(sch_1):page178_i17@mstr_discrete.res(chips)!RES_0402-2.0K,1%,1/16W,CHIP,G2A!!!F1047!A!!!!
S!SGPIO_PCH_SSATA_CLOCK_R!R2L6!2!@baseboard_fab2_lib.baseboard_fab2(sch_1):page178_i17@mstr_discrete.res(chips)!RES_0402-2.0K,1%,1/16W,CHIP,G2A!!!F1047!B!!!!
S!P3V3_STBY!R2L11!1!@baseboard_fab2_lib.baseboard_fab2(sch_1):page178_i13@mstr_discrete.res(chips)!RES_0402-2.0K,1%,1/16W,CHIP,G2A!!!F1046!A!!!!
S!SGPIO_PCH_SATA_CLOCK_R!R2L11!2!@baseboard_fab2_lib.baseboard_fab2(sch_1):page178_i13@mstr_discrete.res(chips)!RES_0402-2.0K,1%,1/16W,CHIP,G2A!!!F1046!B!!!!
S!P3V3!R2L21!1!@baseboard_fab2_lib.baseboard_fab2(sch_1):page173_i263@mstr_discrete.res(chips)!RES_0402-2.0K,1%,1/16W,CHIP,G2A!!!F1043!A!!!!
S!PU_DATAIN1_SATA_0_R!R2L21!2!@baseboard_fab2_lib.baseboard_fab2(sch_1):page173_i263@mstr_discrete.res(chips)!RES_0402-2.0K,1%,1/16W,CHIP,G2A!!!F1043!B!!!!
S!P3V3!R2L23!1!@baseboard_fab2_lib.baseboard_fab2(sch_1):page173_i261@mstr_discrete.res(chips)!RES_0402-2.0K,1%,1/16W,CHIP,G2A!!!F1042!A!!!!
S!PU_DATAIN1_SATA_1_R!R2L23!2!@baseboard_fab2_lib.baseboard_fab2(sch_1):page173_i261@mstr_discrete.res(chips)!RES_0402-2.0K,1%,1/16W,CHIP,G2A!!!F1042!B!!!!
S!P3V3!R1L1!1!@baseboard_fab2_lib.baseboard_fab2(sch_1):page174_i25@mstr_discrete.res(chips)!RES_0402-2.0K,1%,1/16W,CHIP,G2A!!!F1050!A!!!!
S!PU_DATAIN1_SATA_2!R1L1!2!@baseboard_fab2_lib.baseboard_fab2(sch_1):page174_i25@mstr_discrete.res(chips)!RES_0402-2.0K,1%,1/16W,CHIP,G2A!!!F1050!B!!!!
S!P3V3_STBY!R9A7!1!@baseboard_fab2_lib.baseboard_fab2(sch_1):page155_i80@mstr_discrete.res(chips)!RES_0402-2.21K,1%,1/16W,CHIP,GA!!!F1026!A!!!!
S!SPA_SIN_SW_R!R9A7!2!@baseboard_fab2_lib.baseboard_fab2(sch_1):page155_i80@mstr_discrete.res(chips)!RES_0402-2.21K,1%,1/16W,CHIP,GA!!!F1026!B!!!!
S!P3V3_STBY!R1R18!1!@baseboard_fab2_lib.baseboard_fab2(sch_1):page188_i88@mstr_discrete.res(chips)!RES_0402-2.21K,1%,1/16W,CHIP,GA!!!F1023!A!!!!
S!SMB_PCH_MEZZ_LOM0_SCL!R1R18!2!@baseboard_fab2_lib.baseboard_fab2(sch_1):page188_i88@mstr_discrete.res(chips)!RES_0402-2.21K,1%,1/16W,CHIP,GA!!!F1023!B!!!!
S!P3V3_STBY!R1R19!1!@baseboard_fab2_lib.baseboard_fab2(sch_1):page188_i89@mstr_discrete.res(chips)!RES_0402-2.21K,1%,1/16W,CHIP,GA!!!F1022!A!!!!
S!SMB_PCH_MEZZ_LOM0_SDA!R1R19!2!@baseboard_fab2_lib.baseboard_fab2(sch_1):page188_i89@mstr_discrete.res(chips)!RES_0402-2.21K,1%,1/16W,CHIP,GA!!!F1022!B!!!!
S!P3V3_STBY!R1R20!1!@baseboard_fab2_lib.baseboard_fab2(sch_1):page188_i91@mstr_discrete.res(chips)!RES_0402-2.21K,1%,1/16W,CHIP,GA!!!F1021!A!!!!
S!SMB_PCH_MEZZ_LOM1_SCL!R1R20!2!@baseboard_fab2_lib.baseboard_fab2(sch_1):page188_i91@mstr_discrete.res(chips)!RES_0402-2.21K,1%,1/16W,CHIP,GA!!!F1021!B!!!!
S!P3V3_STBY!R1R21!1!@baseboard_fab2_lib.baseboard_fab2(sch_1):page188_i90@mstr_discrete.res(chips)!RES_0402-2.21K,1%,1/16W,CHIP,GA!!!F1020!A!!!!
S!SMB_PCH_MEZZ_LOM1_SDA!R1R21!2!@baseboard_fab2_lib.baseboard_fab2(sch_1):page188_i90@mstr_discrete.res(chips)!RES_0402-2.21K,1%,1/16W,CHIP,GA!!!F1020!B!!!!
S!P3V3_STBY!R1R16!1!@baseboard_fab2_lib.baseboard_fab2(sch_1):page188_i93@mstr_discrete.res(chips)!RES_0402-2.21K,1%,1/16W,CHIP,GA!!!F1019!A!!!!
S!SMB_PCH_MEZZ_LOM2_SCL!R1R16!2!@baseboard_fab2_lib.baseboard_fab2(sch_1):page188_i93@mstr_discrete.res(chips)!RES_0402-2.21K,1%,1/16W,CHIP,GA!!!F1019!B!!!!
S!P3V3_STBY!R1R17!1!@baseboard_fab2_lib.baseboard_fab2(sch_1):page188_i94@mstr_discrete.res(chips)!RES_0402-2.21K,1%,1/16W,CHIP,GA!!!F1018!A!!!!
S!SMB_PCH_MEZZ_LOM2_SDA!R1R17!2!@baseboard_fab2_lib.baseboard_fab2(sch_1):page188_i94@mstr_discrete.res(chips)!RES_0402-2.21K,1%,1/16W,CHIP,GA!!!F1018!B!!!!
S!P3V3_STBY!R1R23!1!@baseboard_fab2_lib.baseboard_fab2(sch_1):page188_i95@mstr_discrete.res(chips)!RES_0402-2.21K,1%,1/16W,CHIP,GA!!!F1017!A!!!!
S!SMB_PCH_MEZZ_LOM3_SCL!R1R23!2!@baseboard_fab2_lib.baseboard_fab2(sch_1):page188_i95@mstr_discrete.res(chips)!RES_0402-2.21K,1%,1/16W,CHIP,GA!!!F1017!B!!!!
S!P3V3_STBY!R1R22!1!@baseboard_fab2_lib.baseboard_fab2(sch_1):page188_i92@mstr_discrete.res(chips)!RES_0402-2.21K,1%,1/16W,CHIP,GA!!!F1016!A!!!!
S!SMB_PCH_MEZZ_LOM3_SDA!R1R22!2!@baseboard_fab2_lib.baseboard_fab2(sch_1):page188_i92@mstr_discrete.res(chips)!RES_0402-2.21K,1%,1/16W,CHIP,GA!!!F1016!B!!!!
S!PVPP_ABC!R4U2!1!@baseboard_fab2_lib.baseboard_fab2(sch_1):page94_i100@mstr_discrete.res(chips)!RES_0402-2.21K,1%,1/16W,CHIP,GA!!!F1028!A!!!!
S!FM_DIMM_EVENT_COD_N!R4U2!2!@baseboard_fab2_lib.baseboard_fab2(sch_1):page94_i100@mstr_discrete.res(chips)!RES_0402-2.21K,1%,1/16W,CHIP,GA!!!F1028!B!!!!
S!P3V3_STBY!R8F23!1!@baseboard_fab2_lib.baseboard_fab2(sch_1):page157_i296@mstr_discrete.res(chips)!RES_0402-2.21K,1%,1/16W,CHIP,GA!!!F1027!A!!!!
S!IRQ_MEZZ_LAN_ALERT_N!R8F23!2!@baseboard_fab2_lib.baseboard_fab2(sch_1):page157_i296@mstr_discrete.res(chips)!RES_0402-2.21K,1%,1/16W,CHIP,GA!!!F1027!B!!!!
S!P3V3_STBY!R2T29!1!@baseboard_fab2_lib.baseboard_fab2(sch_1):page157_i298@mstr_discrete.res(chips)!RES_0402-2.21K,1%,1/16W,CHIP,GA!!!F1029!A!!!!
S!IRQ_OOB_MGMT_RISER_ALERT_N!R2T29!2!@baseboard_fab2_lib.baseboard_fab2(sch_1):page157_i298@mstr_discrete.res(chips)!RES_0402-2.21K,1%,1/16W,CHIP,GA!!!F1029!B!!!!
S!PU_KEY_CONN_PIN2_R!R9A16!1!@baseboard_fab2_lib.baseboard_fab2(sch_1):page134_i12@mstr_discrete.res(chips)!RES_0402-2.21K,1%,1/16W,CHIP,GA!!!F1024!A!!!!
S!P3V3_STBY!R9A16!2!@baseboard_fab2_lib.baseboard_fab2(sch_1):page134_i12@mstr_discrete.res(chips)!RES_0402-2.21K,1%,1/16W,CHIP,GA!!!F1024!B!!!!
S!FM_PCH_SATA_RAID_KEY_R!R9A12!1!@baseboard_fab2_lib.baseboard_fab2(sch_1):page134_i11@mstr_discrete.res(chips)!RES_0402-2.21K,1%,1/16W,CHIP,GA!!!F1025!A!!!!
S!P3V3_STBY!R9A12!2!@baseboard_fab2_lib.baseboard_fab2(sch_1):page134_i11@mstr_discrete.res(chips)!RES_0402-2.21K,1%,1/16W,CHIP,GA!!!F1025!B!!!!
S!P3V3_STBY!R8G6!1!@baseboard_fab2_lib.baseboard_fab2(sch_1):page159_i212@mstr_discrete.res(chips)!RES_0402-2.26K,1.0%,1/16W,EMPTA!!!F996!A!!!!
S!SMB_OCP_LAN_STBY_LVC3_SDA_R!R8G6!2!@baseboard_fab2_lib.baseboard_fab2(sch_1):page159_i212@mstr_discrete.res(chips)!RES_0402-2.26K,1.0%,1/16W,EMPTA!!!F996!B!!!!
S!P3V3_STBY!R8G3!1!@baseboard_fab2_lib.baseboard_fab2(sch_1):page159_i210@mstr_discrete.res(chips)!RES_0402-2.26K,1.0%,1/16W,EMPTA!!!F997!A!!!!
S!SMB_OCP_LAN_STBY_LVC3_SCL_R!R8G3!2!@baseboard_fab2_lib.baseboard_fab2(sch_1):page159_i210@mstr_discrete.res(chips)!RES_0402-2.26K,1.0%,1/16W,EMPTA!!!F997!B!!!!
S!P3V3_STBY!R2U13!1!@baseboard_fab2_lib.baseboard_fab2(sch_1):page159_i216@mstr_discrete.res(chips)!RES_0402-2.26K,1.0%,1/16W,EMPTA!!!F1005!A!!!!
S!SMB_OCP_FRU_STBY_LVC3_SDA_R!R2U13!2!@baseboard_fab2_lib.baseboard_fab2(sch_1):page159_i216@mstr_discrete.res(chips)!RES_0402-2.26K,1.0%,1/16W,EMPTA!!!F1005!B!!!!
S!P3V3_STBY!R2U5!1!@baseboard_fab2_lib.baseboard_fab2(sch_1):page159_i214@mstr_discrete.res(chips)!RES_0402-2.26K,1.0%,1/16W,EMPTA!!!F1006!A!!!!
S!SMB_OCP_FRU_STBY_LVC3_SCL_R!R2U5!2!@baseboard_fab2_lib.baseboard_fab2(sch_1):page159_i214@mstr_discrete.res(chips)!RES_0402-2.26K,1.0%,1/16W,EMPTA!!!F1006!B!!!!
S!P3V3_STBY!R2L24!1!@baseboard_fab2_lib.baseboard_fab2(sch_1):page235_i148@mstr_discrete.res(chips)!RES_0402-2.26K,1.0%,1/16W,EMPTA!!!F998!A!!!!
S!PU_VR_PVNN_PCH_FAULT1!R2L24!2!@baseboard_fab2_lib.baseboard_fab2(sch_1):page235_i148@mstr_discrete.res(chips)!RES_0402-2.26K,1.0%,1/16W,EMPTA!!!F998!B!!!!
S!P3V3_STBY!R6P49!1!@baseboard_fab2_lib.baseboard_fab2(sch_1):page213_i14@mstr_discrete.res(chips)!RES_0402-2.26K,1.0%,1/16W,EMPTA!!!F1001!A!!!!
S!PU_VR_PVCCIO_CPU1_FAULT1!R6P49!2!@baseboard_fab2_lib.baseboard_fab2(sch_1):page213_i14@mstr_discrete.res(chips)!RES_0402-2.26K,1.0%,1/16W,EMPTA!!!F1001!B!!!!
S!P3V3_STBY!R3N23!1!@baseboard_fab2_lib.baseboard_fab2(sch_1):page211_i60@mstr_discrete.res(chips)!RES_0402-2.26K,1.0%,1/16W,EMPTA!!!F1004!A!!!!
S!PU_VR_PVCCIO_CPU0_FAULT1!R3N23!2!@baseboard_fab2_lib.baseboard_fab2(sch_1):page211_i60@mstr_discrete.res(chips)!RES_0402-2.26K,1.0%,1/16W,EMPTA!!!F1004!B!!!!
S!P3V3_STBY!R7A9!1!@baseboard_fab2_lib.baseboard_fab2(sch_1):page218_i14@mstr_discrete.res(chips)!RES_0402-2.26K,1.0%,1/16W,EMPTA!!!F1000!A!!!!
S!PU_VR_PVDDQ_DEF_FAULT1!R7A9!2!@baseboard_fab2_lib.baseboard_fab2(sch_1):page218_i14@mstr_discrete.res(chips)!RES_0402-2.26K,1.0%,1/16W,EMPTA!!!F1000!B!!!!
S!P3V3_STBY!R1G6!1!@baseboard_fab2_lib.baseboard_fab2(sch_1):page223_i13@mstr_discrete.res(chips)!RES_0402-2.26K,1.0%,1/16W,EMPTA!!!F1007!A!!!!
S!PU_VR_PVDDQ_GHJ_FAULT1!R1G6!2!@baseboard_fab2_lib.baseboard_fab2(sch_1):page223_i13@mstr_discrete.res(chips)!RES_0402-2.26K,1.0%,1/16W,EMPTA!!!F1007!B!!!!
S!P3V3_STBY!R1B13!1!@baseboard_fab2_lib.baseboard_fab2(sch_1):page226_i13@mstr_discrete.res(chips)!RES_0402-2.26K,1.0%,1/16W,EMPTA!!!F1010!A!!!!
S!PU_VR_PVDDQ_KLM_FAULT1!R1B13!2!@baseboard_fab2_lib.baseboard_fab2(sch_1):page226_i13@mstr_discrete.res(chips)!RES_0402-2.26K,1.0%,1/16W,EMPTA!!!F1010!B!!!!
S!P3V3_STBY!R4E20!1!@baseboard_fab2_lib.baseboard_fab2(sch_1):page201_i116@mstr_discrete.res(chips)!RES_0402-2.26K,1.0%,1/16W,EMPTA!!!F1003!A!!!!
S!PU_VR_PVCCIN_CPU0_FLT1_SMBALT_N!R4E20!2!@baseboard_fab2_lib.baseboard_fab2(sch_1):page201_i116@mstr_discrete.res(chips)!RES_0402-2.26K,1.0%,1/16W,EMPTA!!!F1003!B!!!!
S!P3V3_STBY!R7F36!1!@baseboard_fab2_lib.baseboard_fab2(sch_1):page215_i300@mstr_discrete.res(chips)!RES_0402-2.26K,1.0%,1/16W,EMPTA!!!F999!A!!!!
S!PU_VR_PVDDQ_ABC_FAULT1!R7F36!2!@baseboard_fab2_lib.baseboard_fab2(sch_1):page215_i300@mstr_discrete.res(chips)!RES_0402-2.26K,1.0%,1/16W,EMPTA!!!F999!B!!!!
S!P3V3_STBY!R4D31!1!@baseboard_fab2_lib.baseboard_fab2(sch_1):page201_i22@mstr_discrete.res(chips)!RES_0402-2.26K,1.0%,1/16W,EMPTA!!!F1002!A!!!!
S!PU_VR_PVCCIN_CPU0_IMON!R4D31!2!@baseboard_fab2_lib.baseboard_fab2(sch_1):page201_i22@mstr_discrete.res(chips)!RES_0402-2.26K,1.0%,1/16W,EMPTA!!!F1002!B!!!!
S!P3V3_STBY!R1D53!1!@baseboard_fab2_lib.baseboard_fab2(sch_1):page206_i33@mstr_discrete.res(chips)!RES_0402-2.26K,1.0%,1/16W,EMPTA!!!F1009!A!!!!
S!PU_VR_PVCCIN_CPU1_FLT1_SMBALT_N!R1D53!2!@baseboard_fab2_lib.baseboard_fab2(sch_1):page206_i33@mstr_discrete.res(chips)!RES_0402-2.26K,1.0%,1/16W,EMPTA!!!F1009!B!!!!
S!P3V3_STBY!R1C18!1!@baseboard_fab2_lib.baseboard_fab2(sch_1):page206_i34@mstr_discrete.res(chips)!RES_0402-2.26K,1.0%,1/16W,EMPTA!!!F1008!A!!!!
S!PU_VR_PVCCIN_CPU1_IMON!R1C18!2!@baseboard_fab2_lib.baseboard_fab2(sch_1):page206_i34@mstr_discrete.res(chips)!RES_0402-2.26K,1.0%,1/16W,EMPTA!!!F1008!B!!!!
S!P3V3_STBY!R1R7!1!@baseboard_fab2_lib.baseboard_fab2(sch_1):page140_i12@mstr_discrete.res(chips)!RES_0402-20.0K,1%,1/16W,CHIP,GA!!!F909!A!!!!
S!SPI_NIC_MOSI!R1R7!2!@baseboard_fab2_lib.baseboard_fab2(sch_1):page140_i12@mstr_discrete.res(chips)!RES_0402-20.0K,1%,1/16W,CHIP,GA!!!F909!B!!!!
S!VSENSE_PVPP_ABC!R7F13!1!@baseboard_fab2_lib.baseboard_fab2(sch_1):page231_i167@mstr_discrete.res(chips)!RES_0402-20.0K,1%,1/16W,CHIP,GA!!!F903!A!!!!
S!VR_FB_PVPP_ABC!R7F13!2!@baseboard_fab2_lib.baseboard_fab2(sch_1):page231_i167@mstr_discrete.res(chips)!RES_0402-20.0K,1%,1/16W,CHIP,GA!!!F903!B!!!!
S!VSENSE_PVPP_DEF!R7B15!1!@baseboard_fab2_lib.baseboard_fab2(sch_1):page232_i303@mstr_discrete.res(chips)!RES_0402-20.0K,1%,1/16W,CHIP,GA!!!F905!A!!!!
S!VR_FB_PVPP_DEF!R7B15!2!@baseboard_fab2_lib.baseboard_fab2(sch_1):page232_i303@mstr_discrete.res(chips)!RES_0402-20.0K,1%,1/16W,CHIP,GA!!!F905!B!!!!
S!VSENSE_PVPP_GHJ!R4G7!1!@baseboard_fab2_lib.baseboard_fab2(sch_1):page233_i270@mstr_discrete.res(chips)!RES_0402-20.0K,1%,1/16W,CHIP,GA!!!F906!A!!!!
S!VR_FB_PVPP_GHJ!R4G7!2!@baseboard_fab2_lib.baseboard_fab2(sch_1):page233_i270@mstr_discrete.res(chips)!RES_0402-20.0K,1%,1/16W,CHIP,GA!!!F906!B!!!!
S!VSENSE_PVPP_KLM!R4B5!1!@baseboard_fab2_lib.baseboard_fab2(sch_1):page234_i215@mstr_discrete.res(chips)!RES_0402-20.0K,1%,1/16W,CHIP,GA!!!F907!A!!!!
S!VR_FB_PVPP_KLM!R4B5!2!@baseboard_fab2_lib.baseboard_fab2(sch_1):page234_i215@mstr_discrete.res(chips)!RES_0402-20.0K,1%,1/16W,CHIP,GA!!!F907!B!!!!
S!P5V_STBY!R9A5!1!@baseboard_fab2_lib.baseboard_fab2(sch_1):page155_i136@mstr_discrete.res(chips)!RES_0402-20.0K,1%,1/16W,CHIP,GA!!!F902!A!!!!
S!FM_UART_SWITCH_N!R9A5!2!@baseboard_fab2_lib.baseboard_fab2(sch_1):page155_i136@mstr_discrete.res(chips)!RES_0402-20.0K,1%,1/16W,CHIP,GA!!!F902!B!!!!
S!P3V3_RTC_STBY!R3N4!1!@baseboard_fab2_lib.baseboard_fab2(sch_1):page137_i19@mstr_discrete.res(chips)!RES_0402-20.0K,1%,1/16W,CHIP,GA!!!F908!A!!!!
S!RST_SRTCRST_N!R3N4!2!@baseboard_fab2_lib.baseboard_fab2(sch_1):page137_i19@mstr_discrete.res(chips)!RES_0402-20.0K,1%,1/16W,CHIP,GA!!!F908!B!!!!
S!P3V3_RTC_STBY!R7C10!1!@baseboard_fab2_lib.baseboard_fab2(sch_1):page137_i13@mstr_discrete.res(chips)!RES_0402-20.0K,1%,1/16W,CHIP,GA!!!F904!A!!!!
S!RST_RTCRST_N!R7C10!2!@baseboard_fab2_lib.baseboard_fab2(sch_1):page137_i13@mstr_discrete.res(chips)!RES_0402-20.0K,1%,1/16W,CHIP,GA!!!F904!B!!!!
S!RMII_BMC_SPRNGVLLE_TXEN_R!R8F33!1!@baseboard_fab2_lib.baseboard_fab2(sch_1):page147_i116@mstr_discrete.res(chips)!RES_0402-22.1,1.0%,1/16W,CHIP,A!!!F860!A!!!!
S!RMII_BMC_PCH_SPRNGVLLE_TXEN!R8F33!2!@baseboard_fab2_lib.baseboard_fab2(sch_1):page147_i116@mstr_discrete.res(chips)!RES_0402-22.1,1.0%,1/16W,CHIP,A!!!F860!B!!!!
S!RMII_BMC_OCP_TXEN_R!R8F30!1!@baseboard_fab2_lib.baseboard_fab2(sch_1):page147_i154@mstr_discrete.res(chips)!RES_0402-22.1,1.0%,1/16W,CHIP,A!!!F862!A!!!!
S!RMII_BMC_OCP_TXEN!R8F30!2!@baseboard_fab2_lib.baseboard_fab2(sch_1):page147_i154@mstr_discrete.res(chips)!RES_0402-22.1,1.0%,1/16W,CHIP,A!!!F862!B!!!!
S!CLK_50M_CKMNG_BMC_1_R!R2T46!1!@baseboard_fab2_lib.baseboard_fab2(sch_1):page101_i125@mstr_discrete.res(chips)!RES_0402-22.1,1.0%,1/16W,CHIP,A!!!F878!A!!!!
S!CLK_50M_CKMNG_BMC_1!R2T46!2!@baseboard_fab2_lib.baseboard_fab2(sch_1):page101_i125@mstr_discrete.res(chips)!RES_0402-22.1,1.0%,1/16W,CHIP,A!!!F878!B!!!!
S!CLK_50M_CKMNG_OCP_R!R2T42!1!@baseboard_fab2_lib.baseboard_fab2(sch_1):page101_i124@mstr_discrete.res(chips)!RES_0402-22.1,1.0%,1/16W,CHIP,A!!!F880!A!!!!
S!CLK_50M_CKMNG_OCP!R2T42!2!@baseboard_fab2_lib.baseboard_fab2(sch_1):page101_i124@mstr_discrete.res(chips)!RES_0402-22.1,1.0%,1/16W,CHIP,A!!!F880!B!!!!
S!PWRGD_PVCCIO_CPU1_R!R4D46!1!@baseboard_fab2_lib.baseboard_fab2(sch_1):page213_i13@mstr_discrete.res(chips)!RES_0402-22.1,1.0%,1/16W,CHIP,A!!!F874!A!!!!
S!PWRGD_PVCCIO_CPU1!R4D46!2!@baseboard_fab2_lib.baseboard_fab2(sch_1):page213_i13@mstr_discrete.res(chips)!RES_0402-22.1,1.0%,1/16W,CHIP,A!!!F874!B!!!!
S!PWRGD_P1V26_BMC_STBY_R!R9F11!1!@baseboard_fab2_lib.baseboard_fab2(sch_1):page238_i41@mstr_discrete.res(chips)!RES_0402-22.1,1.0%,1/16W,CHIP,A!!!F856!A!!!!
S!PWRGD_P1V26_BMC_STBY!R9F11!2!@baseboard_fab2_lib.baseboard_fab2(sch_1):page238_i41@mstr_discrete.res(chips)!RES_0402-22.1,1.0%,1/16W,CHIP,A!!!F856!B!!!!
S!PWRGD_P1V538_BMC_STBY_R!R1T9!1!@baseboard_fab2_lib.baseboard_fab2(sch_1):page239_i72@mstr_discrete.res(chips)!RES_0402-22.1,1.0%,1/16W,CHIP,A!!!F885!A!!!!
S!PWRGD_P1V538_BMC_STBY!R1T9!2!@baseboard_fab2_lib.baseboard_fab2(sch_1):page239_i72@mstr_discrete.res(chips)!RES_0402-22.1,1.0%,1/16W,CHIP,A!!!F885!B!!!!
S!PWRGD_P1V8_PCH_STBY_R!R8A11!1!@baseboard_fab2_lib.baseboard_fab2(sch_1):page237_i90@mstr_discrete.res(chips)!RES_0402-22.1,1.0%,1/16W,CHIP,A!!!F867!A!!!!
S!PWRGD_P1V8_PCH_STBY!R8A11!2!@baseboard_fab2_lib.baseboard_fab2(sch_1):page237_i90@mstr_discrete.res(chips)!RES_0402-22.1,1.0%,1/16W,CHIP,A!!!F867!B!!!!
S!PWRGD_P3V3_STBY_R!R8F10!1!@baseboard_fab2_lib.baseboard_fab2(sch_1):page240_i171@mstr_discrete.res(chips)!RES_0402-22.1,1.0%,1/16W,CHIP,A!!!F865!A!!!!
S!PWRGD_P3V3_STBY!R8F10!2!@baseboard_fab2_lib.baseboard_fab2(sch_1):page240_i171@mstr_discrete.res(chips)!RES_0402-22.1,1.0%,1/16W,CHIP,A!!!F865!B!!!!
S!PWRGD_P5V_STBY_R!R7E15!1!@baseboard_fab2_lib.baseboard_fab2(sch_1):page241_i89@mstr_discrete.res(chips)!RES_0402-22.1,1.0%,1/16W,CHIP,A!!!F870!A!!!!
S!PWRGD_P5V_STBY!R7E15!2!@baseboard_fab2_lib.baseboard_fab2(sch_1):page241_i89@mstr_discrete.res(chips)!RES_0402-22.1,1.0%,1/16W,CHIP,A!!!F870!B!!!!
S!VR_VRRDY_PVCCIN_CPU1!R1C30!1!@baseboard_fab2_lib.baseboard_fab2(sch_1):page206_i113@mstr_discrete.res(chips)!RES_0402-22.1,1.0%,1/16W,CHIP,A!!!F887!A!!!!
S!PWRGD_PVCCIN_CPU1!R1C30!2!@baseboard_fab2_lib.baseboard_fab2(sch_1):page206_i113@mstr_discrete.res(chips)!RES_0402-22.1,1.0%,1/16W,CHIP,A!!!F887!B!!!!
S!PWRGD_PVPP_DEF_R!R7B12!1!@baseboard_fab2_lib.baseboard_fab2(sch_1):page232_i257@mstr_discrete.res(chips)!RES_0402-22.1,1.0%,1/16W,CHIP,A!!!F871!A!!!!
S!PWRGD_PVPP_DEF!R7B12!2!@baseboard_fab2_lib.baseboard_fab2(sch_1):page232_i257@mstr_discrete.res(chips)!RES_0402-22.1,1.0%,1/16W,CHIP,A!!!F871!B!!!!
S!PWRGD_PVPP_GHJ_R!R4G12!1!@baseboard_fab2_lib.baseboard_fab2(sch_1):page233_i247@mstr_discrete.res(chips)!RES_0402-22.1,1.0%,1/16W,CHIP,A!!!F872!A!!!!
S!PWRGD_PVPP_GHJ!R4G12!2!@baseboard_fab2_lib.baseboard_fab2(sch_1):page233_i247@mstr_discrete.res(chips)!RES_0402-22.1,1.0%,1/16W,CHIP,A!!!F872!B!!!!
S!PWRGD_PVPP_ABC_R!R7F16!1!@baseboard_fab2_lib.baseboard_fab2(sch_1):page231_i208@mstr_discrete.res(chips)!RES_0402-22.1,1.0%,1/16W,CHIP,A!!!F869!A!!!!
S!PWRGD_PVPP_ABC!R7F16!2!@baseboard_fab2_lib.baseboard_fab2(sch_1):page231_i208@mstr_discrete.res(chips)!RES_0402-22.1,1.0%,1/16W,CHIP,A!!!F869!B!!!!
S!PWRGD_PVPP_KLM_R!R4B7!1!@baseboard_fab2_lib.baseboard_fab2(sch_1):page234_i201@mstr_discrete.res(chips)!RES_0402-22.1,1.0%,1/16W,CHIP,A!!!F875!A!!!!
S!PWRGD_PVPP_KLM!R4B7!2!@baseboard_fab2_lib.baseboard_fab2(sch_1):page234_i201@mstr_discrete.res(chips)!RES_0402-22.1,1.0%,1/16W,CHIP,A!!!F875!B!!!!
S!VR_VRRDY_PVCCIN_CPU0!R4D63!1!@baseboard_fab2_lib.baseboard_fab2(sch_1):page201_i124@mstr_discrete.res(chips)!RES_0402-22.1,1.0%,1/16W,CHIP,A!!!F873!A!!!!
S!PWRGD_PVCCIN_CPU0!R4D63!2!@baseboard_fab2_lib.baseboard_fab2(sch_1):page201_i124@mstr_discrete.res(chips)!RES_0402-22.1,1.0%,1/16W,CHIP,A!!!F873!B!!!!
S!PWRGD_PVDDQ_ABC_R!R7F24!1!@baseboard_fab2_lib.baseboard_fab2(sch_1):page215_i296@mstr_discrete.res(chips)!RES_0402-22.1,1.0%,1/16W,CHIP,A!!!F868!A!!!!
S!PWRGD_PVDDQ_ABC!R7F24!2!@baseboard_fab2_lib.baseboard_fab2(sch_1):page215_i296@mstr_discrete.res(chips)!RES_0402-22.1,1.0%,1/16W,CHIP,A!!!F868!B!!!!
S!PWRGD_PVDDQ_DEF_R!R3M3!1!@baseboard_fab2_lib.baseboard_fab2(sch_1):page218_i11@mstr_discrete.res(chips)!RES_0402-22.1,1.0%,1/16W,CHIP,A!!!F877!A!!!!
S!PWRGD_PVDDQ_DEF!R3M3!2!@baseboard_fab2_lib.baseboard_fab2(sch_1):page218_i11@mstr_discrete.res(chips)!RES_0402-22.1,1.0%,1/16W,CHIP,A!!!F877!B!!!!
S!PWRGD_PVDDQ_GHJ_R!R1G12!1!@baseboard_fab2_lib.baseboard_fab2(sch_1):page223_i14@mstr_discrete.res(chips)!RES_0402-22.1,1.0%,1/16W,CHIP,A!!!F886!A!!!!
S!PWRGD_PVDDQ_GHJ!R1G12!2!@baseboard_fab2_lib.baseboard_fab2(sch_1):page223_i14@mstr_discrete.res(chips)!RES_0402-22.1,1.0%,1/16W,CHIP,A!!!F886!B!!!!
S!PWRGD_PVDDQ_KLM_R!R1B5!1!@baseboard_fab2_lib.baseboard_fab2(sch_1):page226_i14@mstr_discrete.res(chips)!RES_0402-22.1,1.0%,1/16W,CHIP,A!!!F888!A!!!!
S!PWRGD_PVDDQ_KLM!R1B5!2!@baseboard_fab2_lib.baseboard_fab2(sch_1):page226_i14@mstr_discrete.res(chips)!RES_0402-22.1,1.0%,1/16W,CHIP,A!!!F888!B!!!!
S!PWRGD_PVCCIO_CPU0_R!R3P20!1!@baseboard_fab2_lib.baseboard_fab2(sch_1):page211_i58@mstr_discrete.res(chips)!RES_0402-22.1,1.0%,1/16W,CHIP,A!!!F876!A!!!!
S!PWRGD_PVCCIO_CPU0!R3P20!2!@baseboard_fab2_lib.baseboard_fab2(sch_1):page211_i58@mstr_discrete.res(chips)!RES_0402-22.1,1.0%,1/16W,CHIP,A!!!F876!B!!!!
S!PWRGD_PVNN_PCH_R!R2L16!1!@baseboard_fab2_lib.baseboard_fab2(sch_1):page235_i147@mstr_discrete.res(chips)!RES_0402-22.1,1.0%,1/16W,CHIP,A!!!F882!A!!!!
S!PWRGD_PVNN_P1V05_PCH!R2L16!2!@baseboard_fab2_lib.baseboard_fab2(sch_1):page235_i147@mstr_discrete.res(chips)!RES_0402-22.1,1.0%,1/16W,CHIP,A!!!F882!B!!!!
S!IRQ_FORCE_NM_THROTTLE_N!R2T41!1!@baseboard_fab2_lib.baseboard_fab2(sch_1):page145_i203@mstr_discrete.res(chips)!RES_0402-22.1,1.0%,1/16W,CHIP,A!!!F881!A!!!!
S!FM_BMC_SYS_THROTTLE_R_N!R2T41!2!@baseboard_fab2_lib.baseboard_fab2(sch_1):page145_i203@mstr_discrete.res(chips)!RES_0402-22.1,1.0%,1/16W,CHIP,A!!!F881!B!!!!
S!SPI_BMC_BT_CS_N!R1T26!1!@baseboard_fab2_lib.baseboard_fab2(sch_1):page146_i35@mstr_discrete.res(chips)!RES_0402-22.1,1.0%,1/16W,CHIP,A!!!F884!A!!!!
S!SPI_BMC_BT_CS_R_N!R1T26!2!@baseboard_fab2_lib.baseboard_fab2(sch_1):page146_i35@mstr_discrete.res(chips)!RES_0402-22.1,1.0%,1/16W,CHIP,A!!!F884!B!!!!
S!RMII_BMC_PCH_SPRNGVLLE_TXD1_R!R2T45!1!@baseboard_fab2_lib.baseboard_fab2(sch_1):page147_i115@mstr_discrete.res(chips)!RES_0402-22.1,1.0%,1/16W,CHIP,A!!!F879!A!!!!
S!RMII_BMC_PCH_SPRNGVLLE_TXD1!R2T45!2!@baseboard_fab2_lib.baseboard_fab2(sch_1):page147_i115@mstr_discrete.res(chips)!RES_0402-22.1,1.0%,1/16W,CHIP,A!!!F879!B!!!!
S!RMII_BMC_OCP_TXD1_R!R8F28!1!@baseboard_fab2_lib.baseboard_fab2(sch_1):page147_i125@mstr_discrete.res(chips)!RES_0402-22.1,1.0%,1/16W,CHIP,A!!!F863!A!!!!
S!RMII_BMC_OCP_TXD1!R8F28!2!@baseboard_fab2_lib.baseboard_fab2(sch_1):page147_i125@mstr_discrete.res(chips)!RES_0402-22.1,1.0%,1/16W,CHIP,A!!!F863!B!!!!
S!RMII_BMC_OCP_TXD0_R!R8F31!1!@baseboard_fab2_lib.baseboard_fab2(sch_1):page147_i126@mstr_discrete.res(chips)!RES_0402-22.1,1.0%,1/16W,CHIP,A!!!F861!A!!!!
S!RMII_BMC_OCP_TXD0!R8F31!2!@baseboard_fab2_lib.baseboard_fab2(sch_1):page147_i126@mstr_discrete.res(chips)!RES_0402-22.1,1.0%,1/16W,CHIP,A!!!F861!B!!!!
S!RMII_SPRNGVLLE_BMC_PCH_RXD0_R!R9E17!1!@baseboard_fab2_lib.baseboard_fab2(sch_1):page139_i229@mstr_discrete.res(chips)!RES_0402-22.1,1.0%,1/16W,CHIP,A!!!F859!A!!!!
S!RMII_SPRNGVLLE_BMC_PCH_RXD0!R9E17!2!@baseboard_fab2_lib.baseboard_fab2(sch_1):page139_i229@mstr_discrete.res(chips)!RES_0402-22.1,1.0%,1/16W,CHIP,A!!!F859!B!!!!
S!RMII_SPRNGVLLE_BMC_PCH_RXD1_R!R9E19!1!@baseboard_fab2_lib.baseboard_fab2(sch_1):page139_i228@mstr_discrete.res(chips)!RES_0402-22.1,1.0%,1/16W,CHIP,A!!!F858!A!!!!
S!RMII_SPRNGVLLE_BMC_PCH_RXD1!R9E19!2!@baseboard_fab2_lib.baseboard_fab2(sch_1):page139_i228@mstr_discrete.res(chips)!RES_0402-22.1,1.0%,1/16W,CHIP,A!!!F858!B!!!!
S!RMII_BMC_PCH_SPRNGVLLE_TXD0_R!R1T28!1!@baseboard_fab2_lib.baseboard_fab2(sch_1):page147_i121@mstr_discrete.res(chips)!RES_0402-22.1,1.0%,1/16W,CHIP,A!!!F883!A!!!!
S!RMII_BMC_PCH_SPRNGVLLE_TXD0!R1T28!2!@baseboard_fab2_lib.baseboard_fab2(sch_1):page147_i121@mstr_discrete.res(chips)!RES_0402-22.1,1.0%,1/16W,CHIP,A!!!F883!B!!!!
S!RMII_BMC_PCH_SPRNGVLLE_CRSDV_R!R9F1!1!@baseboard_fab2_lib.baseboard_fab2(sch_1):page139_i225@mstr_discrete.res(chips)!RES_0402-22.1,1.0%,1/16W,CHIP,A!!!F857!A!!!!
S!RMII_BMC_PCH_SPRNGVLLE_CRSDV!R9F1!2!@baseboard_fab2_lib.baseboard_fab2(sch_1):page139_i225@mstr_discrete.res(chips)!RES_0402-22.1,1.0%,1/16W,CHIP,A!!!F857!B!!!!
S!PWRGD_P12V_HSC_DLY_R!R8E7!1!@baseboard_fab2_lib.baseboard_fab2(sch_1):page196_i90@mstr_discrete.res(chips)!RES_0402-22.1,1.0%,1/16W,CHIP,A!!!F866!A!!!!
S!PWRGD_P12V_HSC_DLY!R8E7!2!@baseboard_fab2_lib.baseboard_fab2(sch_1):page196_i90@mstr_discrete.res(chips)!RES_0402-22.1,1.0%,1/16W,CHIP,A!!!F866!B!!!!
S!CLK_32K_SUSCLK_PLD_R!R8F27!1!@baseboard_fab2_lib.baseboard_fab2(sch_1):page101_i129@mstr_discrete.res(chips)!RES_0402-22.1,1.0%,1/16W,CHIP,A!!!F864!A!!!!
S!CLK_32K_SUSCLK_PLD!R8F27!2!@baseboard_fab2_lib.baseboard_fab2(sch_1):page101_i129@mstr_discrete.res(chips)!RES_0402-22.1,1.0%,1/16W,CHIP,A!!!F864!B!!!!
S!P3V3_STBY!R9E7!1!@baseboard_fab2_lib.baseboard_fab2(sch_1):page139_i193@mstr_discrete.res(chips)!RES_0402-3.32K,1%,1/16W,CHIP,GA!!!F771!A!!!!
S!IRQ_LOM_ALERT_N!R9E7!2!@baseboard_fab2_lib.baseboard_fab2(sch_1):page139_i193@mstr_discrete.res(chips)!RES_0402-3.32K,1%,1/16W,CHIP,GA!!!F771!B!!!!
S!P3V3_STBY!R1R3!1!@baseboard_fab2_lib.baseboard_fab2(sch_1):page140_i11@mstr_discrete.res(chips)!RES_0402-3.32K,1%,1/16W,CHIP,GA!!!F773!A!!!!
S!PU_NV_WP_N!R1R3!2!@baseboard_fab2_lib.baseboard_fab2(sch_1):page140_i11@mstr_discrete.res(chips)!RES_0402-3.32K,1%,1/16W,CHIP,GA!!!F773!B!!!!
S!P3V3_STBY!R1R9!1!@baseboard_fab2_lib.baseboard_fab2(sch_1):page140_i10@mstr_discrete.res(chips)!RES_0402-3.32K,1%,1/16W,CHIP,GA!!!F772!A!!!!
S!PU_NV_HOLD_N!R1R9!2!@baseboard_fab2_lib.baseboard_fab2(sch_1):page140_i10@mstr_discrete.res(chips)!RES_0402-3.32K,1%,1/16W,CHIP,GA!!!F772!B!!!!
S!P3V3_STBY!R9F5!1!@baseboard_fab2_lib.baseboard_fab2(sch_1):page139_i173@mstr_discrete.res(chips)!RES_0402-3.32K,1%,1/16W,CHIP,GA!!!F770!A!!!!
S!PU_SPRV_LAN_PWR_GOOD!R9F5!2!@baseboard_fab2_lib.baseboard_fab2(sch_1):page139_i173@mstr_discrete.res(chips)!RES_0402-3.32K,1%,1/16W,CHIP,GA!!!F770!B!!!!
S!A_P5V_SCALED!R1U28!1!@baseboard_fab2_lib.baseboard_fab2(sch_1):page169_i142@mstr_discrete.res(chips)!RES_0402-3.48K,1.0%,1/16W,CHIPA!!!F762!A!!!!
S!GND!R1U28!2!@baseboard_fab2_lib.baseboard_fab2(sch_1):page169_i142@mstr_discrete.res(chips)!RES_0402-3.48K,1.0%,1/16W,CHIPA!!!F762!B!!!!
S!A_P5V_STBY_SCALED!R1U44!1!@baseboard_fab2_lib.baseboard_fab2(sch_1):page169_i116@mstr_discrete.res(chips)!RES_0402-3.48K,1.0%,1/16W,CHIPA!!!F761!A!!!!
S!GND!R1U44!2!@baseboard_fab2_lib.baseboard_fab2(sch_1):page169_i116@mstr_discrete.res(chips)!RES_0402-3.48K,1.0%,1/16W,CHIPA!!!F761!B!!!!
S!FM_ROMA<23>!R1T13!1!@baseboard_fab2_lib.baseboard_fab2(sch_1):page150_i43@mstr_discrete.res(chips)!RES_0402-4.75K,1%,1/16W,EMPTY,A!!!F525!A!!!!
S!P3V3_STBY!R1T13!2!@baseboard_fab2_lib.baseboard_fab2(sch_1):page150_i43@mstr_discrete.res(chips)!RES_0402-4.75K,1%,1/16W,EMPTY,A!!!F525!B!!!!
S!FM_ROMA<18>!R1T18!1!@baseboard_fab2_lib.baseboard_fab2(sch_1):page150_i48@mstr_discrete.res(chips)!RES_0402-4.75K,1%,1/16W,EMPTY,A!!!F522!A!!!!
S!P3V3_STBY!R1T18!2!@baseboard_fab2_lib.baseboard_fab2(sch_1):page150_i48@mstr_discrete.res(chips)!RES_0402-4.75K,1%,1/16W,EMPTY,A!!!F522!B!!!!
S!PVCCIO_CPU0!R7C22!1!@baseboard_fab2_lib.baseboard_fab2(sch_1):page166_i14@mstr_discrete.res(chips)!RES_0402-4.75K,1%,1/16W,EMPTY,A!!!F513!A!!!!
S!PECI_PCH!R7C22!2!@baseboard_fab2_lib.baseboard_fab2(sch_1):page166_i14@mstr_discrete.res(chips)!RES_0402-4.75K,1%,1/16W,EMPTY,A!!!F513!B!!!!
S!P3V3_STBY!R7E18!1!@baseboard_fab2_lib.baseboard_fab2(sch_1):page192_i55@mstr_discrete.res(chips)!RES_0402-4.75K,1%,1/16W,EMPTY,A!!!F497!A!!!!
S!RST_RSMRST_N!R7E18!2!@baseboard_fab2_lib.baseboard_fab2(sch_1):page192_i55@mstr_discrete.res(chips)!RES_0402-4.75K,1%,1/16W,EMPTY,A!!!F497!B!!!!
S!FM_ROMA<21>!R1T17!1!@baseboard_fab2_lib.baseboard_fab2(sch_1):page150_i112@mstr_discrete.res(chips)!RES_0402-4.75K,1%,1/16W,EMPTY,A!!!F523!A!!!!
S!P3V3_STBY!R1T17!2!@baseboard_fab2_lib.baseboard_fab2(sch_1):page150_i112@mstr_discrete.res(chips)!RES_0402-4.75K,1%,1/16W,EMPTY,A!!!F523!B!!!!
S!P3V3_STBY!R1L19!1!@baseboard_fab2_lib.baseboard_fab2(sch_1):page175_i24@mstr_discrete.res(chips)!RES_0402-4.75K,1%,1/16W,EMPTY,A!!!F526!A!!!!
S!FM_DEBUG_RST_BTN_N!R1L19!2!@baseboard_fab2_lib.baseboard_fab2(sch_1):page175_i24@mstr_discrete.res(chips)!RES_0402-4.75K,1%,1/16W,EMPTY,A!!!F526!B!!!!
S!P3V3_STBY!R8E12!1!@baseboard_fab2_lib.baseboard_fab2(sch_1):page198_i78@mstr_discrete.res(chips)!RES_0402-4.75K,1%,1/16W,EMPTY,A!!!F511!A!!!!
S!FM_CTNR_PS_ON!R8E12!2!@baseboard_fab2_lib.baseboard_fab2(sch_1):page198_i78@mstr_discrete.res(chips)!RES_0402-4.75K,1%,1/16W,EMPTY,A!!!F511!B!!!!
S!P3V3_STBY!R3N2!1!@baseboard_fab2_lib.baseboard_fab2(sch_1):page125_i72@mstr_discrete.res(chips)!RES_0402-4.75K,1%,1/16W,EMPTY,A!!!F517!A!!!!
S!FM_FLASH_DESC_OVERRIDE!R3N2!2!@baseboard_fab2_lib.baseboard_fab2(sch_1):page125_i72@mstr_discrete.res(chips)!RES_0402-4.75K,1%,1/16W,EMPTY,A!!!F517!B!!!!
S!FM_HBW_BYPASS_LOWBW_N!R6P22!1!@baseboard_fab2_lib.baseboard_fab2(sch_1):page102_i47@mstr_discrete.res(chips)!RES_0402-4.75K,1%,1/16W,EMPTY,A!!!F515!A!!!!
S!GND!R6P22!2!@baseboard_fab2_lib.baseboard_fab2(sch_1):page102_i47@mstr_discrete.res(chips)!RES_0402-4.75K,1%,1/16W,EMPTY,A!!!F515!B!!!!
S!P3V3_STBY!R9F49!1!@baseboard_fab2_lib.baseboard_fab2(sch_1):page183_i14@mstr_discrete.res(chips)!RES_0402-4.75K,1%,1/16W,EMPTY,A!!!F500!A!!!!
S!FM_PI7C9X1172_A0!R9F49!2!@baseboard_fab2_lib.baseboard_fab2(sch_1):page183_i14@mstr_discrete.res(chips)!RES_0402-4.75K,1%,1/16W,EMPTY,A!!!F500!B!!!!
S!P3V3_STBY!R9F48!1!@baseboard_fab2_lib.baseboard_fab2(sch_1):page183_i13@mstr_discrete.res(chips)!RES_0402-4.75K,1%,1/16W,EMPTY,A!!!F501!A!!!!
S!FM_PI7C9X1172_A1!R9F48!2!@baseboard_fab2_lib.baseboard_fab2(sch_1):page183_i13@mstr_discrete.res(chips)!RES_0402-4.75K,1%,1/16W,EMPTY,A!!!F501!B!!!!
S!FM_ROMA<22>!R9F36!1!@baseboard_fab2_lib.baseboard_fab2(sch_1):page150_i44@mstr_discrete.res(chips)!RES_0402-4.75K,1%,1/16W,EMPTY,A!!!F505!A!!!!
S!P3V3_STBY!R9F36!2!@baseboard_fab2_lib.baseboard_fab2(sch_1):page150_i44@mstr_discrete.res(chips)!RES_0402-4.75K,1%,1/16W,EMPTY,A!!!F505!B!!!!
S!FM_ROMA<20>!R9F17!1!@baseboard_fab2_lib.baseboard_fab2(sch_1):page150_i46@mstr_discrete.res(chips)!RES_0402-4.75K,1%,1/16W,EMPTY,A!!!F508!A!!!!
S!P3V3_STBY!R9F17!2!@baseboard_fab2_lib.baseboard_fab2(sch_1):page150_i46@mstr_discrete.res(chips)!RES_0402-4.75K,1%,1/16W,EMPTY,A!!!F508!B!!!!
S!FM_ROMA<17>!R1T20!1!@baseboard_fab2_lib.baseboard_fab2(sch_1):page150_i49@mstr_discrete.res(chips)!RES_0402-4.75K,1%,1/16W,EMPTY,A!!!F520!A!!!!
S!P3V3_STBY!R1T20!2!@baseboard_fab2_lib.baseboard_fab2(sch_1):page150_i49@mstr_discrete.res(chips)!RES_0402-4.75K,1%,1/16W,EMPTY,A!!!F520!B!!!!
S!FM_ROMA<16>!R1T22!1!@baseboard_fab2_lib.baseboard_fab2(sch_1):page150_i50@mstr_discrete.res(chips)!RES_0402-4.75K,1%,1/16W,EMPTY,A!!!F518!A!!!!
S!P3V3_STBY!R1T22!2!@baseboard_fab2_lib.baseboard_fab2(sch_1):page150_i50@mstr_discrete.res(chips)!RES_0402-4.75K,1%,1/16W,EMPTY,A!!!F518!B!!!!
S!FM_ROMA<13>!R1T21!1!@baseboard_fab2_lib.baseboard_fab2(sch_1):page150_i53@mstr_discrete.res(chips)!RES_0402-4.75K,1%,1/16W,EMPTY,A!!!F519!A!!!!
S!P3V3_STBY!R1T21!2!@baseboard_fab2_lib.baseboard_fab2(sch_1):page150_i53@mstr_discrete.res(chips)!RES_0402-4.75K,1%,1/16W,EMPTY,A!!!F519!B!!!!
S!FM_ROMA<11>!R9F37!1!@baseboard_fab2_lib.baseboard_fab2(sch_1):page150_i55@mstr_discrete.res(chips)!RES_0402-4.75K,1%,1/16W,EMPTY,A!!!F504!A!!!!
S!P3V3_STBY!R9F37!2!@baseboard_fab2_lib.baseboard_fab2(sch_1):page150_i55@mstr_discrete.res(chips)!RES_0402-4.75K,1%,1/16W,EMPTY,A!!!F504!B!!!!
S!FM_ROMA<9>!R1T19!1!@baseboard_fab2_lib.baseboard_fab2(sch_1):page150_i57@mstr_discrete.res(chips)!RES_0402-4.75K,1%,1/16W,EMPTY,A!!!F521!A!!!!
S!P3V3_STBY!R1T19!2!@baseboard_fab2_lib.baseboard_fab2(sch_1):page150_i57@mstr_discrete.res(chips)!RES_0402-4.75K,1%,1/16W,EMPTY,A!!!F521!B!!!!
S!FM_ROMA<7>!R9F38!1!@baseboard_fab2_lib.baseboard_fab2(sch_1):page150_i59@mstr_discrete.res(chips)!RES_0402-4.75K,1%,1/16W,EMPTY,A!!!F503!A!!!!
S!P3V3_STBY!R9F38!2!@baseboard_fab2_lib.baseboard_fab2(sch_1):page150_i59@mstr_discrete.res(chips)!RES_0402-4.75K,1%,1/16W,EMPTY,A!!!F503!B!!!!
S!FM_ROMA<6>!R9F10!1!@baseboard_fab2_lib.baseboard_fab2(sch_1):page150_i60@mstr_discrete.res(chips)!RES_0402-4.75K,1%,1/16W,EMPTY,A!!!F509!A!!!!
S!P3V3_STBY!R9F10!2!@baseboard_fab2_lib.baseboard_fab2(sch_1):page150_i60@mstr_discrete.res(chips)!RES_0402-4.75K,1%,1/16W,EMPTY,A!!!F509!B!!!!
S!FM_ROMA<5>!R1T16!1!@baseboard_fab2_lib.baseboard_fab2(sch_1):page150_i61@mstr_discrete.res(chips)!RES_0402-4.75K,1%,1/16W,EMPTY,A!!!F524!A!!!!
S!P3V3_STBY!R1T16!2!@baseboard_fab2_lib.baseboard_fab2(sch_1):page150_i61@mstr_discrete.res(chips)!RES_0402-4.75K,1%,1/16W,EMPTY,A!!!F524!B!!!!
S!FM_ROMA<4>!R9F18!1!@baseboard_fab2_lib.baseboard_fab2(sch_1):page150_i62@mstr_discrete.res(chips)!RES_0402-4.75K,1%,1/16W,EMPTY,A!!!F507!A!!!!
S!P3V3_STBY!R9F18!2!@baseboard_fab2_lib.baseboard_fab2(sch_1):page150_i62@mstr_discrete.res(chips)!RES_0402-4.75K,1%,1/16W,EMPTY,A!!!F507!B!!!!
S!FM_ROMA<3>!R9F19!1!@baseboard_fab2_lib.baseboard_fab2(sch_1):page150_i63@mstr_discrete.res(chips)!RES_0402-4.75K,1%,1/16W,EMPTY,A!!!F506!A!!!!
S!P3V3_STBY!R9F19!2!@baseboard_fab2_lib.baseboard_fab2(sch_1):page150_i63@mstr_discrete.res(chips)!RES_0402-4.75K,1%,1/16W,EMPTY,A!!!F506!B!!!!
S!FM_ROMA<2>!R9F39!1!@baseboard_fab2_lib.baseboard_fab2(sch_1):page150_i64@mstr_discrete.res(chips)!RES_0402-4.75K,1%,1/16W,EMPTY,A!!!F502!A!!!!
S!P3V3_STBY!R9F39!2!@baseboard_fab2_lib.baseboard_fab2(sch_1):page150_i64@mstr_discrete.res(chips)!RES_0402-4.75K,1%,1/16W,EMPTY,A!!!F502!B!!!!
S!A_HSC_VCAP!R1D29!1!@baseboard_fab2_lib.baseboard_fab2(sch_1):page199_i37@mstr_discrete.res(chips)!RES_0402-4.75K,1%,1/16W,EMPTY,A!!!F527!A!!!!
S!FM_P12V_HSC_ADR1!R1D29!2!@baseboard_fab2_lib.baseboard_fab2(sch_1):page199_i37@mstr_discrete.res(chips)!RES_0402-4.75K,1%,1/16W,EMPTY,A!!!F527!B!!!!
S!A_HSC_VCAP!R1D27!1!@baseboard_fab2_lib.baseboard_fab2(sch_1):page199_i38@mstr_discrete.res(chips)!RES_0402-4.75K,1%,1/16W,EMPTY,A!!!F528!A!!!!
S!FM_P12V_HSC_ADR2!R1D27!2!@baseboard_fab2_lib.baseboard_fab2(sch_1):page199_i38@mstr_discrete.res(chips)!RES_0402-4.75K,1%,1/16W,EMPTY,A!!!F528!B!!!!
S!FM_100M_N!R6P23!1!@baseboard_fab2_lib.baseboard_fab2(sch_1):page102_i46@mstr_discrete.res(chips)!RES_0402-4.75K,1%,1/16W,EMPTY,A!!!F514!A!!!!
S!GND!R6P23!2!@baseboard_fab2_lib.baseboard_fab2(sch_1):page102_i46@mstr_discrete.res(chips)!RES_0402-4.75K,1%,1/16W,EMPTY,A!!!F514!B!!!!
S!P3V3_STBY!R9G25!1!@baseboard_fab2_lib.baseboard_fab2(sch_1):page165_i58@mstr_discrete.res(chips)!RES_0402-4.75K,1%,1/16W,EMPTY,A!!!F498!A!!!!
S!FM_ADC128_A1!R9G25!2!@baseboard_fab2_lib.baseboard_fab2(sch_1):page165_i58@mstr_discrete.res(chips)!RES_0402-4.75K,1%,1/16W,EMPTY,A!!!F498!B!!!!
S!P3V3_STBY!R9G23!1!@baseboard_fab2_lib.baseboard_fab2(sch_1):page165_i57@mstr_discrete.res(chips)!RES_0402-4.75K,1%,1/16W,EMPTY,A!!!F499!A!!!!
S!FM_ADC128_A0!R9G23!2!@baseboard_fab2_lib.baseboard_fab2(sch_1):page165_i57@mstr_discrete.res(chips)!RES_0402-4.75K,1%,1/16W,EMPTY,A!!!F499!B!!!!
S!P3V3_STBY!R3T3!1!@baseboard_fab2_lib.baseboard_fab2(sch_1):page153_i150@mstr_discrete.res(chips)!RES_0402-4.75K,1%,1/16W,EMPTY,A!!!F516!A!!!!
S!PU_SPI1_RST!R3T3!2!@baseboard_fab2_lib.baseboard_fab2(sch_1):page153_i150@mstr_discrete.res(chips)!RES_0402-4.75K,1%,1/16W,EMPTY,A!!!F516!B!!!!
S!P3V3_STBY!R8F16!1!@baseboard_fab2_lib.baseboard_fab2(sch_1):page162_i8@mstr_discrete.res(chips)!RES_0402-4.75K,1%,1/16W,EMPTY,A!!!F510!A!!!!
S!PU_SPI_FLASH_RESET_2_N!R8F16!2!@baseboard_fab2_lib.baseboard_fab2(sch_1):page162_i8@mstr_discrete.res(chips)!RES_0402-4.75K,1%,1/16W,EMPTY,A!!!F510!B!!!!
S!P3V3_STBY!R7F6!1!@baseboard_fab2_lib.baseboard_fab2(sch_1):page153_i90@mstr_discrete.res(chips)!RES_0402-4.75K,1%,1/16W,EMPTY,A!!!F512!A!!!!
S!PU_SPI0_RST!R7F6!2!@baseboard_fab2_lib.baseboard_fab2(sch_1):page153_i90@mstr_discrete.res(chips)!RES_0402-4.75K,1%,1/16W,EMPTY,A!!!F512!B!!!!
S!A_COMP_CKMNG!R8F25!1!@baseboard_fab2_lib.baseboard_fab2(sch_1):page101_i28@mstr_discrete.res(chips)!RES_0402-475.0,1%,1/16W,CHIP,GA!!!F467!A!!!!
S!GND!R8F25!2!@baseboard_fab2_lib.baseboard_fab2(sch_1):page101_i28@mstr_discrete.res(chips)!RES_0402-475.0,1%,1/16W,CHIP,GA!!!F467!B!!!!
S!XDP_PRESENT_N!R9A4!1!@baseboard_fab2_lib.baseboard_fab2(sch_1):page111_i55@mstr_discrete.res(chips)!RES_0402-475.0,1%,1/16W,CHIP,GA!!!F466!A!!!!
S!PVCCIO_CPU0!R9A4!2!@baseboard_fab2_lib.baseboard_fab2(sch_1):page111_i55@mstr_discrete.res(chips)!RES_0402-475.0,1%,1/16W,CHIP,GA!!!F466!B!!!!
S!P3V3_STBY!R8A10!1!@baseboard_fab2_lib.baseboard_fab2(sch_1):page237_i3@mstr_discrete.res(chips)!RES_0402-5.11K,1%,1/16W,CHIP,GA!!!F390!A!!!!
S!PWRGD_P1V8_PCH_STBY_R!R8A10!2!@baseboard_fab2_lib.baseboard_fab2(sch_1):page237_i3@mstr_discrete.res(chips)!RES_0402-5.11K,1%,1/16W,CHIP,GA!!!F390!B!!!!
S!P5V!R1U29!1!@baseboard_fab2_lib.baseboard_fab2(sch_1):page169_i141@mstr_discrete.res(chips)!RES_0402-5.11K,1%,1/16W,CHIP,GA!!!F394!A!!!!
S!A_P5V_SCALED!R1U29!2!@baseboard_fab2_lib.baseboard_fab2(sch_1):page169_i141@mstr_discrete.res(chips)!RES_0402-5.11K,1%,1/16W,CHIP,GA!!!F394!B!!!!
S!P3V3!R1U26!1!@baseboard_fab2_lib.baseboard_fab2(sch_1):page169_i148@mstr_discrete.res(chips)!RES_0402-5.11K,1%,1/16W,CHIP,GA!!!F395!A!!!!
S!A_P3V3_SCALED!R1U26!2!@baseboard_fab2_lib.baseboard_fab2(sch_1):page169_i148@mstr_discrete.res(chips)!RES_0402-5.11K,1%,1/16W,CHIP,GA!!!F395!B!!!!
S!P5V_STBY!R1U47!1!@baseboard_fab2_lib.baseboard_fab2(sch_1):page169_i115@mstr_discrete.res(chips)!RES_0402-5.11K,1%,1/16W,CHIP,GA!!!F391!A!!!!
S!A_P5V_STBY_SCALED!R1U47!2!@baseboard_fab2_lib.baseboard_fab2(sch_1):page169_i115@mstr_discrete.res(chips)!RES_0402-5.11K,1%,1/16W,CHIP,GA!!!F391!B!!!!
S!P12V_STBY!R1U32!1!@baseboard_fab2_lib.baseboard_fab2(sch_1):page169_i82@mstr_discrete.res(chips)!RES_0402-5.11K,1%,1/16W,CHIP,GA!!!F393!A!!!!
S!A_P12V_STBY_SCALED!R1U32!2!@baseboard_fab2_lib.baseboard_fab2(sch_1):page169_i82@mstr_discrete.res(chips)!RES_0402-5.11K,1%,1/16W,CHIP,GA!!!F393!B!!!!
S!P3V3_STBY!R1U39!1!@baseboard_fab2_lib.baseboard_fab2(sch_1):page169_i88@mstr_discrete.res(chips)!RES_0402-5.11K,1%,1/16W,CHIP,GA!!!F392!A!!!!
S!A_P3V3_STBY_SCALED!R1U39!2!@baseboard_fab2_lib.baseboard_fab2(sch_1):page169_i88@mstr_discrete.res(chips)!RES_0402-5.11K,1%,1/16W,CHIP,GA!!!F392!B!!!!
S!GND!R6U16!1!@baseboard_fab2_lib.baseboard_fab2(sch_1):page221_i55@mstr_discrete.res(chips)!RES_0402-51.1,1.0%,1/16W,CHIP,A!!!F377!A!!!!
S!PVTT_ABC!R6U16!2!@baseboard_fab2_lib.baseboard_fab2(sch_1):page221_i55@mstr_discrete.res(chips)!RES_0402-51.1,1.0%,1/16W,CHIP,A!!!F377!B!!!!
S!GND!R4A1!1!@baseboard_fab2_lib.baseboard_fab2(sch_1):page222_i52@mstr_discrete.res(chips)!RES_0402-51.1,1.0%,1/16W,CHIP,A!!!F381!A!!!!
S!PVTT_DEF!R4A1!2!@baseboard_fab2_lib.baseboard_fab2(sch_1):page222_i52@mstr_discrete.res(chips)!RES_0402-51.1,1.0%,1/16W,CHIP,A!!!F381!B!!!!
S!GND!R6U8!1!@baseboard_fab2_lib.baseboard_fab2(sch_1):page229_i52@mstr_discrete.res(chips)!RES_0402-51.1,1.0%,1/16W,CHIP,A!!!F378!A!!!!
S!PVTT_GHJ!R6U8!2!@baseboard_fab2_lib.baseboard_fab2(sch_1):page229_i52@mstr_discrete.res(chips)!RES_0402-51.1,1.0%,1/16W,CHIP,A!!!F378!B!!!!
S!GND!R6L7!1!@baseboard_fab2_lib.baseboard_fab2(sch_1):page230_i52@mstr_discrete.res(chips)!RES_0402-51.1,1.0%,1/16W,CHIP,A!!!F380!A!!!!
S!PVTT_KLM!R6L7!2!@baseboard_fab2_lib.baseboard_fab2(sch_1):page230_i52@mstr_discrete.res(chips)!RES_0402-51.1,1.0%,1/16W,CHIP,A!!!F380!B!!!!
S!PVCCIO_CPU1!R7R1!1!@baseboard_fab2_lib.baseboard_fab2(sch_1):page214_i109@mstr_discrete.res(chips)!RES_0402-51.1,1.0%,1/16W,CHIP,A!!!F374!A!!!!
S!GND!R7R1!2!@baseboard_fab2_lib.baseboard_fab2(sch_1):page214_i109@mstr_discrete.res(chips)!RES_0402-51.1,1.0%,1/16W,CHIP,A!!!F374!B!!!!
S!PVSA_CPU0!R6N4!1!@baseboard_fab2_lib.baseboard_fab2(sch_1):page205_i45@mstr_discrete.res(chips)!RES_0402-51.1,1.0%,1/16W,CHIP,A!!!F379!A!!!!
S!GND!R6N4!2!@baseboard_fab2_lib.baseboard_fab2(sch_1):page205_i45@mstr_discrete.res(chips)!RES_0402-51.1,1.0%,1/16W,CHIP,A!!!F379!B!!!!
S!PVSA_CPU1!R9N4!1!@baseboard_fab2_lib.baseboard_fab2(sch_1):page210_i45@mstr_discrete.res(chips)!RES_0402-51.1,1.0%,1/16W,CHIP,A!!!F372!A!!!!
S!GND!R9N4!2!@baseboard_fab2_lib.baseboard_fab2(sch_1):page210_i45@mstr_discrete.res(chips)!RES_0402-51.1,1.0%,1/16W,CHIP,A!!!F372!B!!!!
S!PVCCIO_CPU0!R7C3!1!@baseboard_fab2_lib.baseboard_fab2(sch_1):page212_i78@mstr_discrete.res(chips)!RES_0402-51.1,1.0%,1/16W,CHIP,A!!!F376!A!!!!
S!GND!R7C3!2!@baseboard_fab2_lib.baseboard_fab2(sch_1):page212_i78@mstr_discrete.res(chips)!RES_0402-51.1,1.0%,1/16W,CHIP,A!!!F376!B!!!!
S!FM_NMI_EVENT_N!R2N25!1!@baseboard_fab2_lib.baseboard_fab2(sch_1):page157_i302@mstr_discrete.res(chips)!RES_0402-51.1,1.0%,1/16W,CHIP,A!!!F382!A!!!!
S!FM_BMC_NMI_N!R2N25!2!@baseboard_fab2_lib.baseboard_fab2(sch_1):page157_i302@mstr_discrete.res(chips)!RES_0402-51.1,1.0%,1/16W,CHIP,A!!!F382!B!!!!
S!XDP_CPU_TCK0!R7P29!1!@baseboard_fab2_lib.baseboard_fab2(sch_1):page112_i61@mstr_discrete.res(chips)!RES_0402-51.1,1.0%,1/16W,CHIP,A!!!F375!A!!!!
S!GND!R7P29!2!@baseboard_fab2_lib.baseboard_fab2(sch_1):page112_i61@mstr_discrete.res(chips)!RES_0402-51.1,1.0%,1/16W,CHIP,A!!!F375!B!!!!
S!XDP_PCH_TCK1!R8B1!1!@baseboard_fab2_lib.baseboard_fab2(sch_1):page112_i95@mstr_discrete.res(chips)!RES_0402-51.1,1.0%,1/16W,CHIP,A!!!F373!A!!!!
S!GND!R8B1!2!@baseboard_fab2_lib.baseboard_fab2(sch_1):page112_i95@mstr_discrete.res(chips)!RES_0402-51.1,1.0%,1/16W,CHIP,A!!!F373!B!!!!
S!FM_P12V_HOTSWAP0_EN!R9T3!1!@baseboard_fab2_lib.baseboard_fab2(sch_1):page181_i185@mstr_discrete.res(chips)!RES_0402-6.19K,1%,1/16W,CHIP,GA!!!F370!A!!!!
S!GND!R9T3!2!@baseboard_fab2_lib.baseboard_fab2(sch_1):page181_i185@mstr_discrete.res(chips)!RES_0402-6.19K,1%,1/16W,CHIP,GA!!!F370!B!!!!
S!PWRGD_P12V_R!R1D31!1!@baseboard_fab2_lib.baseboard_fab2(sch_1):page199_i43@mstr_discrete.res(chips)!RES_0402-6.19K,1%,1/16W,CHIP,GA!!!F371!A!!!!
S!GND!R1D31!2!@baseboard_fab2_lib.baseboard_fab2(sch_1):page199_i43@mstr_discrete.res(chips)!RES_0402-6.19K,1%,1/16W,CHIP,GA!!!F371!B!!!!
S!P3V3!R1L21!1!@baseboard_fab2_lib.baseboard_fab2(sch_1):page177_i43@mstr_discrete.res(chips)!RES_0402-64.9,1.0%,1/16W,CHIP,A!!!F363!A!!!!
S!FP_LED_HDD_ACTIVITY_AND_R_N!R1L21!2!@baseboard_fab2_lib.baseboard_fab2(sch_1):page177_i43@mstr_discrete.res(chips)!RES_0402-64.9,1.0%,1/16W,CHIP,A!!!F363!B!!!!
S!PVDDQ_KLM!R7M9!1!@baseboard_fab2_lib.baseboard_fab2(sch_1):page96_i28@mstr_discrete.res(chips)!RES_0402-64.9,1.0%,1/16W,CHIP,A!!!F359!A!!!!
S!PWRGD_CPU1_DRAMPWROK_KLM_G!R7M9!2!@baseboard_fab2_lib.baseboard_fab2(sch_1):page96_i28@mstr_discrete.res(chips)!RES_0402-64.9,1.0%,1/16W,CHIP,A!!!F359!B!!!!
S!PVDDQ_GHJ!R3D21!1!@baseboard_fab2_lib.baseboard_fab2(sch_1):page96_i30@mstr_discrete.res(chips)!RES_0402-64.9,1.0%,1/16W,CHIP,A!!!F362!A!!!!
S!PWRGD_CPU1_DRAMPWROK_GHJ_G!R3D21!2!@baseboard_fab2_lib.baseboard_fab2(sch_1):page96_i30@mstr_discrete.res(chips)!RES_0402-64.9,1.0%,1/16W,CHIP,A!!!F362!B!!!!
S!PVDDQ_ABC!R3P38!1!@baseboard_fab2_lib.baseboard_fab2(sch_1):page96_i7@mstr_discrete.res(chips)!RES_0402-64.9,1.0%,1/16W,CHIP,A!!!F360!A!!!!
S!PWRGD_CPU0_DRAMPWROK_ABC_G!R3P38!2!@baseboard_fab2_lib.baseboard_fab2(sch_1):page96_i7@mstr_discrete.res(chips)!RES_0402-64.9,1.0%,1/16W,CHIP,A!!!F360!B!!!!
S!PVDDQ_DEF!R3P29!1!@baseboard_fab2_lib.baseboard_fab2(sch_1):page96_i5@mstr_discrete.res(chips)!RES_0402-64.9,1.0%,1/16W,CHIP,A!!!F361!A!!!!
S!PWRGD_CPU0_DRAMPWROK_DEF_G!R3P29!2!@baseboard_fab2_lib.baseboard_fab2(sch_1):page96_i5@mstr_discrete.res(chips)!RES_0402-64.9,1.0%,1/16W,CHIP,A!!!F361!B!!!!
S!P3V3_STBY!R1T3!1!@baseboard_fab2_lib.baseboard_fab2(sch_1):page160_i46@mstr_discrete.res(chips)!RES_0402-665,1.0%,1/16W,CHIP,GA!!!F356!A!!!!
S!SMB_SLOTX24_STBY_LVC3_SDA_R!R1T3!2!@baseboard_fab2_lib.baseboard_fab2(sch_1):page160_i46@mstr_discrete.res(chips)!RES_0402-665,1.0%,1/16W,CHIP,GA!!!F356!B!!!!
S!P3V3_STBY!R1T2!1!@baseboard_fab2_lib.baseboard_fab2(sch_1):page160_i49@mstr_discrete.res(chips)!RES_0402-665,1.0%,1/16W,CHIP,GA!!!F357!A!!!!
S!SMB_SLOTX24_STBY_LVC3_SCL_R!R1T2!2!@baseboard_fab2_lib.baseboard_fab2(sch_1):page160_i49@mstr_discrete.res(chips)!RES_0402-665,1.0%,1/16W,CHIP,GA!!!F357!B!!!!
S!P3V3_STBY!R2T53!1!@baseboard_fab2_lib.baseboard_fab2(sch_1):page138_i83@mstr_discrete.res(chips)!RES_0402-665,1.0%,1/16W,CHIP,GA!!!F353!A!!!!
S!SMB_BMC_PMBUS_STBY_LVC3_SDA!R2T53!2!@baseboard_fab2_lib.baseboard_fab2(sch_1):page138_i83@mstr_discrete.res(chips)!RES_0402-665,1.0%,1/16W,CHIP,GA!!!F353!B!!!!
S!P3V3_STBY!R2U39!1!@baseboard_fab2_lib.baseboard_fab2(sch_1):page167_i83@mstr_discrete.res(chips)!RES_0402-665,1.0%,1/16W,CHIP,GA!!!F348!A!!!!
S!SMB_SENSOR_STBY_LVC3_SDA!R2U39!2!@baseboard_fab2_lib.baseboard_fab2(sch_1):page167_i83@mstr_discrete.res(chips)!RES_0402-665,1.0%,1/16W,CHIP,GA!!!F348!B!!!!
S!P3V3_STBY!R2T54!1!@baseboard_fab2_lib.baseboard_fab2(sch_1):page138_i84@mstr_discrete.res(chips)!RES_0402-665,1.0%,1/16W,CHIP,GA!!!F352!A!!!!
S!SMB_BMC_PMBUS_STBY_LVC3_SCL!R2T54!2!@baseboard_fab2_lib.baseboard_fab2(sch_1):page138_i84@mstr_discrete.res(chips)!RES_0402-665,1.0%,1/16W,CHIP,GA!!!F352!B!!!!
S!P3V3_STBY!R2U38!1!@baseboard_fab2_lib.baseboard_fab2(sch_1):page167_i80@mstr_discrete.res(chips)!RES_0402-665,1.0%,1/16W,CHIP,GA!!!F349!A!!!!
S!SMB_SENSOR_STBY_LVC3_SCL!R2U38!2!@baseboard_fab2_lib.baseboard_fab2(sch_1):page167_i80@mstr_discrete.res(chips)!RES_0402-665,1.0%,1/16W,CHIP,GA!!!F349!B!!!!
S!P3V3_STBY!R2U11!1!@baseboard_fab2_lib.baseboard_fab2(sch_1):page138_i97@mstr_discrete.res(chips)!RES_0402-665,1.0%,1/16W,CHIP,GA!!!F350!A!!!!
S!SMB_LAN_STBY_LVC3_SDA!R2U11!2!@baseboard_fab2_lib.baseboard_fab2(sch_1):page138_i97@mstr_discrete.res(chips)!RES_0402-665,1.0%,1/16W,CHIP,GA!!!F350!B!!!!
S!P3V3_STBY!R2U3!1!@baseboard_fab2_lib.baseboard_fab2(sch_1):page138_i98@mstr_discrete.res(chips)!RES_0402-665,1.0%,1/16W,CHIP,GA!!!F351!A!!!!
S!SMB_LAN_STBY_LVC3_SCL!R2U3!2!@baseboard_fab2_lib.baseboard_fab2(sch_1):page138_i98@mstr_discrete.res(chips)!RES_0402-665,1.0%,1/16W,CHIP,GA!!!F351!B!!!!
S!P3V3_STBY!R2N8!1!@baseboard_fab2_lib.baseboard_fab2(sch_1):page138_i89@mstr_discrete.res(chips)!RES_0402-665,1.0%,1/16W,CHIP,GA!!!F354!A!!!!
S!SMB_SMLINK0_STBY_LVC3_SDA!R2N8!2!@baseboard_fab2_lib.baseboard_fab2(sch_1):page138_i89@mstr_discrete.res(chips)!RES_0402-665,1.0%,1/16W,CHIP,GA!!!F354!B!!!!
S!P3V3_STBY!R2N5!1!@baseboard_fab2_lib.baseboard_fab2(sch_1):page138_i90@mstr_discrete.res(chips)!RES_0402-665,1.0%,1/16W,CHIP,GA!!!F355!A!!!!
S!SMB_SMLINK0_STBY_LVC3_SCL!R2N5!2!@baseboard_fab2_lib.baseboard_fab2(sch_1):page138_i90@mstr_discrete.res(chips)!RES_0402-665,1.0%,1/16W,CHIP,GA!!!F355!B!!!!
S!PVPP_ABC!R4T7!1!@baseboard_fab2_lib.baseboard_fab2(sch_1):page99_i13@mstr_discrete.res(chips)!RES_0402-665,1.0%,1/16W,CHIP,GA!!!F345!A!!!!
S!SMB_DDR_ABC_VPP_SCL_R!R4T7!2!@baseboard_fab2_lib.baseboard_fab2(sch_1):page99_i13@mstr_discrete.res(chips)!RES_0402-665,1.0%,1/16W,CHIP,GA!!!F345!B!!!!
S!PVPP_GHJ!R6U17!1!@baseboard_fab2_lib.baseboard_fab2(sch_1):page99_i106@mstr_discrete.res(chips)!RES_0402-665,1.0%,1/16W,CHIP,GA!!!F343!A!!!!
S!SMB_DDR_GHJ_VPP_SCL_R!R6U17!2!@baseboard_fab2_lib.baseboard_fab2(sch_1):page99_i106@mstr_discrete.res(chips)!RES_0402-665,1.0%,1/16W,CHIP,GA!!!F343!B!!!!
S!PVPP_KLM!R7M1!1!@baseboard_fab2_lib.baseboard_fab2(sch_1):page99_i109@mstr_discrete.res(chips)!RES_0402-665,1.0%,1/16W,CHIP,GA!!!F341!A!!!!
S!SMB_DDR_KLM_VPP_SCL_R!R7M1!2!@baseboard_fab2_lib.baseboard_fab2(sch_1):page99_i109@mstr_discrete.res(chips)!RES_0402-665,1.0%,1/16W,CHIP,GA!!!F341!B!!!!
S!PVPP_DEF!R3R5!1!@baseboard_fab2_lib.baseboard_fab2(sch_1):page99_i103@mstr_discrete.res(chips)!RES_0402-665,1.0%,1/16W,CHIP,GA!!!F347!A!!!!
S!SMB_DDR_DEF_VPP_SCL_R!R3R5!2!@baseboard_fab2_lib.baseboard_fab2(sch_1):page99_i103@mstr_discrete.res(chips)!RES_0402-665,1.0%,1/16W,CHIP,GA!!!F347!B!!!!
S!PVPP_ABC!R4T8!1!@baseboard_fab2_lib.baseboard_fab2(sch_1):page99_i11@mstr_discrete.res(chips)!RES_0402-665,1.0%,1/16W,CHIP,GA!!!F344!A!!!!
S!SMB_DDR_ABC_VPP_SDA_R!R4T8!2!@baseboard_fab2_lib.baseboard_fab2(sch_1):page99_i11@mstr_discrete.res(chips)!RES_0402-665,1.0%,1/16W,CHIP,GA!!!F344!B!!!!
S!PVPP_GHJ!R6U18!1!@baseboard_fab2_lib.baseboard_fab2(sch_1):page99_i104@mstr_discrete.res(chips)!RES_0402-665,1.0%,1/16W,CHIP,GA!!!F342!A!!!!
S!SMB_DDR_GHJ_VPP_SDA_R!R6U18!2!@baseboard_fab2_lib.baseboard_fab2(sch_1):page99_i104@mstr_discrete.res(chips)!RES_0402-665,1.0%,1/16W,CHIP,GA!!!F342!B!!!!
S!PVPP_KLM!R7M6!1!@baseboard_fab2_lib.baseboard_fab2(sch_1):page99_i107@mstr_discrete.res(chips)!RES_0402-665,1.0%,1/16W,CHIP,GA!!!F340!A!!!!
S!SMB_DDR_KLM_VPP_SDA_R!R7M6!2!@baseboard_fab2_lib.baseboard_fab2(sch_1):page99_i107@mstr_discrete.res(chips)!RES_0402-665,1.0%,1/16W,CHIP,GA!!!F340!B!!!!
S!PVPP_DEF!R3R12!1!@baseboard_fab2_lib.baseboard_fab2(sch_1):page99_i101@mstr_discrete.res(chips)!RES_0402-665,1.0%,1/16W,CHIP,GA!!!F346!A!!!!
S!SMB_DDR_DEF_VPP_SDA_R!R3R12!2!@baseboard_fab2_lib.baseboard_fab2(sch_1):page99_i101@mstr_discrete.res(chips)!RES_0402-665,1.0%,1/16W,CHIP,GA!!!F346!B!!!!
S!VSENSE_P1V05_PCH_STBY_AVSP!R2L8!1!@baseboard_fab2_lib.baseboard_fab2(sch_1):page235_i154@mstr_discrete.res(chips)!RES_0603-10.0,1%,1/10W,CHIP,G2A!!!F277!A!!!!
S!VR_P1V05_PCH_STBY_AVSP!R2L8!2!@baseboard_fab2_lib.baseboard_fab2(sch_1):page235_i154@mstr_discrete.res(chips)!RES_0603-10.0,1%,1/10W,CHIP,G2A!!!F277!B!!!!
S!P12V_PSU!R9P30!1!@baseboard_fab2_lib.baseboard_fab2(sch_1):page199_i2@mstr_discrete.res(chips)!RES_0603-10.0,1%,1/10W,CHIP,G2A!!!F276!A!!!!
S!P12V_HSC_VCC!R9P30!2!@baseboard_fab2_lib.baseboard_fab2(sch_1):page199_i2@mstr_discrete.res(chips)!RES_0603-10.0,1%,1/10W,CHIP,G2A!!!F276!B!!!!
S!PVCCIN_CPU0!R4E13!1!@baseboard_fab2_lib.baseboard_fab2(sch_1):page203_i67@mstr_discrete.res(chips)!RES_0603-100.0,1%,1/10W,CHIP,GA!!!F274!A!!!!
S!GND!R4E13!2!@baseboard_fab2_lib.baseboard_fab2(sch_1):page203_i67@mstr_discrete.res(chips)!RES_0603-100.0,1%,1/10W,CHIP,GA!!!F274!B!!!!
S!PVCCIN_CPU1!R1E3!1!@baseboard_fab2_lib.baseboard_fab2(sch_1):page208_i7@mstr_discrete.res(chips)!RES_0603-100.0,1%,1/10W,CHIP,GA!!!F275!A!!!!
S!GND!R1E3!2!@baseboard_fab2_lib.baseboard_fab2(sch_1):page208_i7@mstr_discrete.res(chips)!RES_0603-100.0,1%,1/10W,CHIP,GA!!!F275!B!!!!
S!XTAL_33K_RTC1!R7C6!1!@baseboard_fab2_lib.baseboard_fab2(sch_1):page114_i54@mstr_discrete.res(chips)!RES_0603-10M,1.0%,1/10W,CHIP,GA!!!F271!A!!!!
S!XTAL_33K_RTC2!R7C6!2!@baseboard_fab2_lib.baseboard_fab2(sch_1):page114_i54@mstr_discrete.res(chips)!RES_0603-10M,1.0%,1/10W,CHIP,GA!!!F271!B!!!!
S!PVPP_ABC!R7F10!1!@baseboard_fab2_lib.baseboard_fab2(sch_1):page231_i177@mstr_discrete.res(chips)!RES_0603-120.0,1%,1/10W,CHIP,GA!!!F263!A!!!!
S!GND!R7F10!2!@baseboard_fab2_lib.baseboard_fab2(sch_1):page231_i177@mstr_discrete.res(chips)!RES_0603-120.0,1%,1/10W,CHIP,GA!!!F263!B!!!!
S!PVPP_DEF!R7B10!1!@baseboard_fab2_lib.baseboard_fab2(sch_1):page232_i227@mstr_discrete.res(chips)!RES_0603-120.0,1%,1/10W,CHIP,GA!!!F264!A!!!!
S!GND!R7B10!2!@baseboard_fab2_lib.baseboard_fab2(sch_1):page232_i227@mstr_discrete.res(chips)!RES_0603-120.0,1%,1/10W,CHIP,GA!!!F264!B!!!!
S!PVPP_GHJ!R4G6!1!@baseboard_fab2_lib.baseboard_fab2(sch_1):page233_i211@mstr_discrete.res(chips)!RES_0603-120.0,1%,1/10W,CHIP,GA!!!F266!A!!!!
S!GND!R4G6!2!@baseboard_fab2_lib.baseboard_fab2(sch_1):page233_i211@mstr_discrete.res(chips)!RES_0603-120.0,1%,1/10W,CHIP,GA!!!F266!B!!!!
S!PVPP_KLM!R4B2!1!@baseboard_fab2_lib.baseboard_fab2(sch_1):page234_i183@mstr_discrete.res(chips)!RES_0603-120.0,1%,1/10W,CHIP,GA!!!F267!A!!!!
S!GND!R4B2!2!@baseboard_fab2_lib.baseboard_fab2(sch_1):page234_i183@mstr_discrete.res(chips)!RES_0603-120.0,1%,1/10W,CHIP,GA!!!F267!B!!!!
S!PVDDQ_ABC!R3U4!1!@baseboard_fab2_lib.baseboard_fab2(sch_1):page217_i58@mstr_discrete.res(chips)!RES_0603-120.0,1%,1/10W,CHIP,GA!!!F268!A!!!!
S!GND!R3U4!2!@baseboard_fab2_lib.baseboard_fab2(sch_1):page217_i58@mstr_discrete.res(chips)!RES_0603-120.0,1%,1/10W,CHIP,GA!!!F268!B!!!!
S!PVDDQ_GHJ!R1G20!1!@baseboard_fab2_lib.baseboard_fab2(sch_1):page225_i58@mstr_discrete.res(chips)!RES_0603-120.0,1%,1/10W,CHIP,GA!!!F269!A!!!!
S!GND!R1G20!2!@baseboard_fab2_lib.baseboard_fab2(sch_1):page225_i58@mstr_discrete.res(chips)!RES_0603-120.0,1%,1/10W,CHIP,GA!!!F269!B!!!!
S!PVDDQ_KLM!R1A1!1!@baseboard_fab2_lib.baseboard_fab2(sch_1):page228_i58@mstr_discrete.res(chips)!RES_0603-120.0,1%,1/10W,CHIP,GA!!!F270!A!!!!
S!GND!R1A1!2!@baseboard_fab2_lib.baseboard_fab2(sch_1):page228_i58@mstr_discrete.res(chips)!RES_0603-120.0,1%,1/10W,CHIP,GA!!!F270!B!!!!
S!PVDDQ_DEF!R4L4!1!@baseboard_fab2_lib.baseboard_fab2(sch_1):page220_i58@mstr_discrete.res(chips)!RES_0603-120.0,1%,1/10W,CHIP,GA!!!F265!A!!!!
S!GND!R4L4!2!@baseboard_fab2_lib.baseboard_fab2(sch_1):page220_i58@mstr_discrete.res(chips)!RES_0603-120.0,1%,1/10W,CHIP,GA!!!F265!B!!!!
S!PECI_PCH!R7C19!1!@baseboard_fab2_lib.baseboard_fab2(sch_1):page166_i15@mstr_discrete.res(chips)!RES_0402-0.0,5%,1/16W,CHIP,G21A!!!F1811!A!!!!
S!PECI_CPU_G!R7C19!2!@baseboard_fab2_lib.baseboard_fab2(sch_1):page166_i15@mstr_discrete.res(chips)!RES_0402-0.0,5%,1/16W,CHIP,G21A!!!F1811!B!!!!
S!PECI_BMC!R9F33!1!@baseboard_fab2_lib.baseboard_fab2(sch_1):page145_i132@mstr_discrete.res(chips)!RES_0402-0.0,5%,1/16W,CHIP,G21A!!!F1752!A!!!!
S!PECI_BMC_R!R9F33!2!@baseboard_fab2_lib.baseboard_fab2(sch_1):page145_i132@mstr_discrete.res(chips)!RES_0402-0.0,5%,1/16W,CHIP,G21A!!!F1752!B!!!!
S!H_CPU_BMCINIT_R!R6D16!1!@baseboard_fab2_lib.baseboard_fab2(sch_1):page156_i299@mstr_discrete.res(chips)!RES_0402-0.0,5%,1/16W,CHIP,G21A!!!F1688!A!!!!
S!H_CPU0_BMCINIT!R6D16!2!@baseboard_fab2_lib.baseboard_fab2(sch_1):page156_i299@mstr_discrete.res(chips)!RES_0402-0.0,5%,1/16W,CHIP,G21A!!!F1688!B!!!!
S!H_CPU_BMCINIT_R!R3D31!1!@baseboard_fab2_lib.baseboard_fab2(sch_1):page156_i300@mstr_discrete.res(chips)!RES_0402-0.0,5%,1/16W,CHIP,G21A!!!F1687!A!!!!
S!H_CPU1_BMCINIT!R3D31!2!@baseboard_fab2_lib.baseboard_fab2(sch_1):page156_i300@mstr_discrete.res(chips)!RES_0402-0.0,5%,1/16W,CHIP,G21A!!!F1687!B!!!!
S!SMB_LAN_STBY_LVC3_SDA!R4A8!1!@baseboard_fab2_lib.baseboard_fab2(sch_1):page156_i322@mstr_discrete.res(chips)!RES_0402-0.0,5%,1/16W,CHIP,G21A!!!F1686!A!!!!
S!SMB_PIROM_CPU0_SDA!R4A8!2!@baseboard_fab2_lib.baseboard_fab2(sch_1):page156_i322@mstr_discrete.res(chips)!RES_0402-0.0,5%,1/16W,CHIP,G21A!!!F1686!B!!!!
S!SMB_LAN_STBY_LVC3_SCL!R4A9!1!@baseboard_fab2_lib.baseboard_fab2(sch_1):page156_i324@mstr_discrete.res(chips)!RES_0402-0.0,5%,1/16W,CHIP,G21A!!!F1685!A!!!!
S!SMB_PIROM_CPU0_SCL!R4A9!2!@baseboard_fab2_lib.baseboard_fab2(sch_1):page156_i324@mstr_discrete.res(chips)!RES_0402-0.0,5%,1/16W,CHIP,G21A!!!F1685!B!!!!
S!SMB_LAN_STBY_LVC3_SDA!R9M21!1!@baseboard_fab2_lib.baseboard_fab2(sch_1):page156_i321@mstr_discrete.res(chips)!RES_0402-0.0,5%,1/16W,CHIP,G21A!!!F1684!A!!!!
S!SMB_PIROM_CPU1_SDA!R9M21!2!@baseboard_fab2_lib.baseboard_fab2(sch_1):page156_i321@mstr_discrete.res(chips)!RES_0402-0.0,5%,1/16W,CHIP,G21A!!!F1684!B!!!!
S!SMB_LAN_STBY_LVC3_SCL!R9M20!1!@baseboard_fab2_lib.baseboard_fab2(sch_1):page156_i323@mstr_discrete.res(chips)!RES_0402-0.0,5%,1/16W,CHIP,G21A!!!F1683!A!!!!
S!SMB_PIROM_CPU1_SCL!R9M20!2!@baseboard_fab2_lib.baseboard_fab2(sch_1):page156_i323@mstr_discrete.res(chips)!RES_0402-0.0,5%,1/16W,CHIP,G21A!!!F1683!B!!!!
S!JTAG_MCP_TCK!R9B11!1!@baseboard_fab2_lib.baseboard_fab2(sch_1):page113_i239@mstr_discrete.res(chips)!RES_0402-0.0,5%,1/16W,CHIP,G21A!!!F1682!A!!!!
S!JTAG_MCP_TCK_R!R9B11!2!@baseboard_fab2_lib.baseboard_fab2(sch_1):page113_i239@mstr_discrete.res(chips)!RES_0402-0.0,5%,1/16W,CHIP,G21A!!!F1682!B!!!!
S!JTAG_MCP_TMS!R9B13!1!@baseboard_fab2_lib.baseboard_fab2(sch_1):page113_i240@mstr_discrete.res(chips)!RES_0402-0.0,5%,1/16W,CHIP,G21A!!!F1681!A!!!!
S!JTAG_MCP_TMS_R!R9B13!2!@baseboard_fab2_lib.baseboard_fab2(sch_1):page113_i240@mstr_discrete.res(chips)!RES_0402-0.0,5%,1/16W,CHIP,G21A!!!F1681!B!!!!
S!CLK_24M_BMC_CLKIN_R!R9F62!1!@baseboard_fab2_lib.baseboard_fab2(sch_1):page145_i256@mstr_discrete.res(chips)!RES_0402-0.0,5%,1/16W,CHIP,G21A!!!F1690!A!!!!
S!CLK_24M_25M_BMC_CLKIN!R9F62!2!@baseboard_fab2_lib.baseboard_fab2(sch_1):page145_i256@mstr_discrete.res(chips)!RES_0402-0.0,5%,1/16W,CHIP,G21A!!!F1690!B!!!!
S!FM_PWRBRK_N!R7E22!1!@baseboard_fab2_lib.baseboard_fab2(sch_1):page108_i341@mstr_discrete.res(chips)!RES_0402-0.0,5%,1/16W,CHIP,G21A!!!F1689!A!!!!
S!FM_PWRBRK_SLOT_N!R7E22!2!@baseboard_fab2_lib.baseboard_fab2(sch_1):page108_i341@mstr_discrete.res(chips)!RES_0402-0.0,5%,1/16W,CHIP,G21A!!!F1689!B!!!!
S!FM_CPU_ERR0_LVT3_R_N!R2T65!1!@baseboard_fab2_lib.baseboard_fab2(sch_1):page93_i111@mstr_discrete.res(chips)!RES_0402-0.0,5%,1/16W,CHIP,G21A!!!F1706!A!!!!
S!FM_CPU_ERR0_LVT3_K_N!R2T65!2!@baseboard_fab2_lib.baseboard_fab2(sch_1):page93_i111@mstr_discrete.res(chips)!RES_0402-0.0,5%,1/16W,CHIP,G21A!!!F1706!B!!!!
S!FM_CPU_ERR1_LVT3_R_N!R2T66!1!@baseboard_fab2_lib.baseboard_fab2(sch_1):page93_i112@mstr_discrete.res(chips)!RES_0402-0.0,5%,1/16W,CHIP,G21A!!!F1705!A!!!!
S!FM_CPU_ERR0_LVT3_K_N!R2T66!2!@baseboard_fab2_lib.baseboard_fab2(sch_1):page93_i112@mstr_discrete.res(chips)!RES_0402-0.0,5%,1/16W,CHIP,G21A!!!F1705!B!!!!
S!FM_CPU0_PROCHOT_LVT3_R_N!R2T67!1!@baseboard_fab2_lib.baseboard_fab2(sch_1):page93_i113@mstr_discrete.res(chips)!RES_0402-0.0,5%,1/16W,CHIP,G21A!!!F1704!A!!!!
S!FM_CPU0_PROCHOT_LVT3_K_N!R2T67!2!@baseboard_fab2_lib.baseboard_fab2(sch_1):page93_i113@mstr_discrete.res(chips)!RES_0402-0.0,5%,1/16W,CHIP,G21A!!!F1704!B!!!!
S!FM_CPU1_PROCHOT_LVT3_R_N!R7D41!1!@baseboard_fab2_lib.baseboard_fab2(sch_1):page93_i114@mstr_discrete.res(chips)!RES_0402-0.0,5%,1/16W,CHIP,G21A!!!F1703!A!!!!
S!FM_CPU1_PROCHOT_LVT3_K_N!R7D41!2!@baseboard_fab2_lib.baseboard_fab2(sch_1):page93_i114@mstr_discrete.res(chips)!RES_0402-0.0,5%,1/16W,CHIP,G21A!!!F1703!B!!!!
S!FM_CPU_ERR0_LVT3_N!R8F38!1!@baseboard_fab2_lib.baseboard_fab2(sch_1):page93_i119@mstr_discrete.res(chips)!RES_0402-0.0,5%,1/16W,CHIP,G21A!!!F1702!A!!!!
S!FM_CPU_ERR0_LVT3_BMC_N!R8F38!2!@baseboard_fab2_lib.baseboard_fab2(sch_1):page93_i119@mstr_discrete.res(chips)!RES_0402-0.0,5%,1/16W,CHIP,G21A!!!F1702!B!!!!
S!FM_CPU_ERR1_LVT3_N!R2T64!1!@baseboard_fab2_lib.baseboard_fab2(sch_1):page93_i121@mstr_discrete.res(chips)!RES_0402-0.0,5%,1/16W,CHIP,G21A!!!F1701!A!!!!
S!FM_CPU_ERR1_LVT3_BMC_N!R2T64!2!@baseboard_fab2_lib.baseboard_fab2(sch_1):page93_i121@mstr_discrete.res(chips)!RES_0402-0.0,5%,1/16W,CHIP,G21A!!!F1701!B!!!!
S!FM_CPU0_PROCHOT_LVT3_N!R1T36!1!@baseboard_fab2_lib.baseboard_fab2(sch_1):page93_i122@mstr_discrete.res(chips)!RES_0402-0.0,5%,1/16W,CHIP,G21A!!!F1700!A!!!!
S!FM_CPU0_PROCHOT_LVT3_BMC_N!R1T36!2!@baseboard_fab2_lib.baseboard_fab2(sch_1):page93_i122@mstr_discrete.res(chips)!RES_0402-0.0,5%,1/16W,CHIP,G21A!!!F1700!B!!!!
S!FM_CPU1_PROCHOT_LVT3_N!R1T37!1!@baseboard_fab2_lib.baseboard_fab2(sch_1):page93_i123@mstr_discrete.res(chips)!RES_0402-0.0,5%,1/16W,CHIP,G21A!!!F1699!A!!!!
S!FM_CPU1_PROCHOT_LVT3_BMC_N!R1T37!2!@baseboard_fab2_lib.baseboard_fab2(sch_1):page93_i123@mstr_discrete.res(chips)!RES_0402-0.0,5%,1/16W,CHIP,G21A!!!F1699!B!!!!
S!H_CPU0_ABC_MEMHOT_LVT3_R_N!R1U59!1!@baseboard_fab2_lib.baseboard_fab2(sch_1):page152_i74@mstr_discrete.res(chips)!RES_0402-0.0,5%,1/16W,CHIP,G21A!!!F1698!A!!!!
S!H_CPU0_MEMABC_MEMHOT_LVT3_K_N!R1U59!2!@baseboard_fab2_lib.baseboard_fab2(sch_1):page152_i74@mstr_discrete.res(chips)!RES_0402-0.0,5%,1/16W,CHIP,G21A!!!F1698!B!!!!
S!H_CPU0_DEF_MEMHOT_LVT3_R_N!R9G33!1!@baseboard_fab2_lib.baseboard_fab2(sch_1):page152_i73@mstr_discrete.res(chips)!RES_0402-0.0,5%,1/16W,CHIP,G21A!!!F1697!A!!!!
S!H_CPU0_MEMDEF_MEMHOT_LVT3_K_N!R9G33!2!@baseboard_fab2_lib.baseboard_fab2(sch_1):page152_i73@mstr_discrete.res(chips)!RES_0402-0.0,5%,1/16W,CHIP,G21A!!!F1697!B!!!!
S!H_CPU1_GHJ_MEMHOT_LVT3_R_N!R9G32!1!@baseboard_fab2_lib.baseboard_fab2(sch_1):page152_i72@mstr_discrete.res(chips)!RES_0402-0.0,5%,1/16W,CHIP,G21A!!!F1696!A!!!!
S!H_CPU1_MEMGHJ_MEMHOT_LVT3_K_N!R9G32!2!@baseboard_fab2_lib.baseboard_fab2(sch_1):page152_i72@mstr_discrete.res(chips)!RES_0402-0.0,5%,1/16W,CHIP,G21A!!!F1696!B!!!!
S!H_CPU1_KLM_MEMHOT_LVT3_R_N!R9G28!1!@baseboard_fab2_lib.baseboard_fab2(sch_1):page152_i71@mstr_discrete.res(chips)!RES_0402-0.0,5%,1/16W,CHIP,G21A!!!F1695!A!!!!
S!H_CPU1_MEMKLM_MEMHOT_LVT3_K_N!R9G28!2!@baseboard_fab2_lib.baseboard_fab2(sch_1):page152_i71@mstr_discrete.res(chips)!RES_0402-0.0,5%,1/16W,CHIP,G21A!!!F1695!B!!!!
S!H_CPU0_MEMABC_MEMHOT_LVT3_N!R2U47!1!@baseboard_fab2_lib.baseboard_fab2(sch_1):page152_i79@mstr_discrete.res(chips)!RES_0402-0.0,5%,1/16W,CHIP,G21A!!!F1694!A!!!!
S!H_CPU0_MEMABC_MEMHOT_LVT3_BMC_N!R2U47!2!@baseboard_fab2_lib.baseboard_fab2(sch_1):page152_i79@mstr_discrete.res(chips)!RES_0402-0.0,5%,1/16W,CHIP,G21A!!!F1694!B!!!!
S!H_CPU0_MEMDEF_MEMHOT_LVT3_N!R9G29!1!@baseboard_fab2_lib.baseboard_fab2(sch_1):page152_i92@mstr_discrete.res(chips)!RES_0402-0.0,5%,1/16W,CHIP,G21A!!!F1693!A!!!!
S!H_CPU0_MEMDEF_MEMHOT_LVT3_BMC_N!R9G29!2!@baseboard_fab2_lib.baseboard_fab2(sch_1):page152_i92@mstr_discrete.res(chips)!RES_0402-0.0,5%,1/16W,CHIP,G21A!!!F1693!B!!!!
S!H_CPU1_MEMGHJ_MEMHOT_LVT3_N!R1U54!1!@baseboard_fab2_lib.baseboard_fab2(sch_1):page152_i93@mstr_discrete.res(chips)!RES_0402-0.0,5%,1/16W,CHIP,G21A!!!F1692!A!!!!
S!H_CPU1_MEMGHJ_MEMHOT_LVT3_BMC_N!R1U54!2!@baseboard_fab2_lib.baseboard_fab2(sch_1):page152_i93@mstr_discrete.res(chips)!RES_0402-0.0,5%,1/16W,CHIP,G21A!!!F1692!B!!!!
S!H_CPU1_MEMKLM_MEMHOT_LVT3_N!R2U46!1!@baseboard_fab2_lib.baseboard_fab2(sch_1):page152_i94@mstr_discrete.res(chips)!RES_0402-0.0,5%,1/16W,CHIP,G21A!!!F1691!A!!!!
S!H_CPU1_MEMKLM_MEMHOT_LVT3_BMC_N!R2U46!2!@baseboard_fab2_lib.baseboard_fab2(sch_1):page152_i94@mstr_discrete.res(chips)!RES_0402-0.0,5%,1/16W,CHIP,G21A!!!F1691!B!!!!
S!H_CPU0_PROCHOT_G_N!R2T60!1!@baseboard_fab2_lib.baseboard_fab2(sch_1):page93_i103@mstr_discrete.res(chips)!RES_0402-0.0,5%,1/16W,CHIP,G21A!!!F1712!A!!!!
S!H_CPU0_PROCHOT_G_R_N!R2T60!2!@baseboard_fab2_lib.baseboard_fab2(sch_1):page93_i103@mstr_discrete.res(chips)!RES_0402-0.0,5%,1/16W,CHIP,G21A!!!F1712!B!!!!
S!H_CPU1_PROCHOT_G_N!R2T68!1!@baseboard_fab2_lib.baseboard_fab2(sch_1):page93_i102@mstr_discrete.res(chips)!RES_0402-0.0,5%,1/16W,CHIP,G21A!!!F1711!A!!!!
S!H_CPU1_PROCHOT_G_R_N!R2T68!2!@baseboard_fab2_lib.baseboard_fab2(sch_1):page93_i102@mstr_discrete.res(chips)!RES_0402-0.0,5%,1/16W,CHIP,G21A!!!F1711!B!!!!
S!H_CPU0_MEMABC_MEMHOT_G_N!R9G34!1!@baseboard_fab2_lib.baseboard_fab2(sch_1):page152_i45@mstr_discrete.res(chips)!RES_0402-0.0,5%,1/16W,CHIP,G21A!!!F1710!A!!!!
S!H_CPU0_MEMABC_MEMHOT_G_R_N!R9G34!2!@baseboard_fab2_lib.baseboard_fab2(sch_1):page152_i45@mstr_discrete.res(chips)!RES_0402-0.0,5%,1/16W,CHIP,G21A!!!F1710!B!!!!
S!H_CPU0_MEMDEF_MEMHOT_G_N!R1U58!1!@baseboard_fab2_lib.baseboard_fab2(sch_1):page152_i49@mstr_discrete.res(chips)!RES_0402-0.0,5%,1/16W,CHIP,G21A!!!F1709!A!!!!
S!H_CPU0_MEMDEF_MEMHOT_G_R_N!R1U58!2!@baseboard_fab2_lib.baseboard_fab2(sch_1):page152_i49@mstr_discrete.res(chips)!RES_0402-0.0,5%,1/16W,CHIP,G21A!!!F1709!B!!!!
S!H_CPU1_MEMGHJ_MEMHOT_G_N!R1U53!1!@baseboard_fab2_lib.baseboard_fab2(sch_1):page152_i64@mstr_discrete.res(chips)!RES_0402-0.0,5%,1/16W,CHIP,G21A!!!F1708!A!!!!
S!H_CPU1_MEMGHJ_MEMHOT_G_R_N!R1U53!2!@baseboard_fab2_lib.baseboard_fab2(sch_1):page152_i64@mstr_discrete.res(chips)!RES_0402-0.0,5%,1/16W,CHIP,G21A!!!F1708!B!!!!
S!H_CPU1_MEMKLM_MEMHOT_G_N!R1U60!1!@baseboard_fab2_lib.baseboard_fab2(sch_1):page152_i65@mstr_discrete.res(chips)!RES_0402-0.0,5%,1/16W,CHIP,G21A!!!F1707!A!!!!
S!H_CPU1_MEMKLM_MEMHOT_G_R_N!R1U60!2!@baseboard_fab2_lib.baseboard_fab2(sch_1):page152_i65@mstr_discrete.res(chips)!RES_0402-0.0,5%,1/16W,CHIP,G21A!!!F1707!B!!!!
S!CLK_156M_OSC_BRD_CPU1_DN!R3F2!1!@baseboard_fab2_lib.baseboard_fab2(sch_1):page104_i69@mstr_discrete.res(chips)!RES_0402-0.0,5%,1/16W,CHIP,G21A!!!F1896!A!!!!
S!CLK_156M_OSC_CPU1_HFI_DN!R3F2!2!@baseboard_fab2_lib.baseboard_fab2(sch_1):page104_i69@mstr_discrete.res(chips)!RES_0402-0.0,5%,1/16W,CHIP,G21A!!!F1896!B!!!!
S!CLK_156M_OSC_BRD_CPU1_DP!R3F4!1!@baseboard_fab2_lib.baseboard_fab2(sch_1):page104_i70@mstr_discrete.res(chips)!RES_0402-0.0,5%,1/16W,CHIP,G21A!!!F1895!A!!!!
S!CLK_156M_OSC_CPU1_HFI_DP!R3F4!2!@baseboard_fab2_lib.baseboard_fab2(sch_1):page104_i70@mstr_discrete.res(chips)!RES_0402-0.0,5%,1/16W,CHIP,G21A!!!F1895!B!!!!
S!CLK_156M_OSC_BRD_CPU0_DN!R6F7!1!@baseboard_fab2_lib.baseboard_fab2(sch_1):page104_i67@mstr_discrete.res(chips)!RES_0402-0.0,5%,1/16W,CHIP,G21A!!!F1841!A!!!!
S!CLK_156M_OSC_CPU0_HFI_DN!R6F7!2!@baseboard_fab2_lib.baseboard_fab2(sch_1):page104_i67@mstr_discrete.res(chips)!RES_0402-0.0,5%,1/16W,CHIP,G21A!!!F1841!B!!!!
S!CLK_156M_OSC_BRD_CPU0_DP!R6F9!1!@baseboard_fab2_lib.baseboard_fab2(sch_1):page104_i68@mstr_discrete.res(chips)!RES_0402-0.0,5%,1/16W,CHIP,G21A!!!F1840!A!!!!
S!CLK_156M_OSC_CPU0_HFI_DP!R6F9!2!@baseboard_fab2_lib.baseboard_fab2(sch_1):page104_i68@mstr_discrete.res(chips)!RES_0402-0.0,5%,1/16W,CHIP,G21A!!!F1840!B!!!!
S!FM_156M_CPU0_BRD_OSC_EN!R8D43!1!@baseboard_fab2_lib.baseboard_fab2(sch_1):page104_i93@mstr_discrete.res(chips)!RES_0402-0.0,5%,1/16W,CHIP,G21A!!!F1714!A!!!!
S!FM_CPU0_STL_BRD_OSC_EN!R8D43!2!@baseboard_fab2_lib.baseboard_fab2(sch_1):page104_i93@mstr_discrete.res(chips)!RES_0402-0.0,5%,1/16W,CHIP,G21A!!!F1714!B!!!!
S!FM_156M_CPU1_BRD_OSC_EN!R7D36!1!@baseboard_fab2_lib.baseboard_fab2(sch_1):page104_i96@mstr_discrete.res(chips)!RES_0402-0.0,5%,1/16W,CHIP,G21A!!!F1713!A!!!!
S!FM_CPU1_STL_BRD_OSC_EN!R7D36!2!@baseboard_fab2_lib.baseboard_fab2(sch_1):page104_i96@mstr_discrete.res(chips)!RES_0402-0.0,5%,1/16W,CHIP,G21A!!!F1713!B!!!!
S!PVDDQ_KLM!R6L6!1!@baseboard_fab2_lib.baseboard_fab2(sch_1):page230_i34@mstr_discrete.res(chips)!RES_0402-0.0,5%,1/16W,CHIP,G21A!!!F1839!A!!!!
S!VSENSE_PVDDQ_KLM_VTT!R6L6!2!@baseboard_fab2_lib.baseboard_fab2(sch_1):page230_i34@mstr_discrete.res(chips)!RES_0402-0.0,5%,1/16W,CHIP,G21A!!!F1839!B!!!!
S!FAN_TACH0!R1F8!1!@baseboard_fab2_lib.baseboard_fab2(sch_1):page181_i268@mstr_discrete.res(chips)!RES_0402-0.0,5%,1/16W,CHIP,G21A!!!F1945!A!!!!
S!FAN_TACH0_R!R1F8!2!@baseboard_fab2_lib.baseboard_fab2(sch_1):page181_i268@mstr_discrete.res(chips)!RES_0402-0.0,5%,1/16W,CHIP,G21A!!!F1945!B!!!!
S!SMB_VR_STBY_LVC3_SDA_R!R1U8!1!@baseboard_fab2_lib.baseboard_fab2(sch_1):page159_i223@mstr_discrete.res(chips)!RES_0402-0.0,5%,1/16W,CHIP,G21A!!!F1923!A!!!!
S!SMB_VR_STBY_LVC3_SDA!R1U8!2!@baseboard_fab2_lib.baseboard_fab2(sch_1):page159_i223@mstr_discrete.res(chips)!RES_0402-0.0,5%,1/16W,CHIP,G21A!!!F1923!B!!!!
S!SMB_VR_STBY_LVC3_SCL_R!R1U11!1!@baseboard_fab2_lib.baseboard_fab2(sch_1):page159_i222@mstr_discrete.res(chips)!RES_0402-0.0,5%,1/16W,CHIP,G21A!!!F1922!A!!!!
S!SMB_VR_STBY_LVC3_SCL!R1U11!2!@baseboard_fab2_lib.baseboard_fab2(sch_1):page159_i222@mstr_discrete.res(chips)!RES_0402-0.0,5%,1/16W,CHIP,G21A!!!F1922!B!!!!
S!SMB_VR_SDA_VDDQ_GHJ!R1G21!1!@baseboard_fab2_lib.baseboard_fab2(sch_1):page223_i22@mstr_discrete.res(chips)!RES_0402-0.0,5%,1/16W,CHIP,G21A!!!F1941!A!!!!
S!SMB_VR_STBY_LVC3_SDA!R1G21!2!@baseboard_fab2_lib.baseboard_fab2(sch_1):page223_i22@mstr_discrete.res(chips)!RES_0402-0.0,5%,1/16W,CHIP,G21A!!!F1941!B!!!!
S!SMB_VR_SCL_VDDQ_GHJ!R1G19!1!@baseboard_fab2_lib.baseboard_fab2(sch_1):page223_i21@mstr_discrete.res(chips)!RES_0402-0.0,5%,1/16W,CHIP,G21A!!!F1942!A!!!!
S!SMB_VR_STBY_LVC3_SCL!R1G19!2!@baseboard_fab2_lib.baseboard_fab2(sch_1):page223_i21@mstr_discrete.res(chips)!RES_0402-0.0,5%,1/16W,CHIP,G21A!!!F1942!B!!!!
S!GND!R1U51!1!@baseboard_fab2_lib.baseboard_fab2(sch_1):page141_i112@mstr_discrete.res(chips)!RES_0402-0.0,5%,1/16W,CHIP,G21A!!!F1921!A!!!!
S!GND_NIC!R1U51!2!@baseboard_fab2_lib.baseboard_fab2(sch_1):page141_i112@mstr_discrete.res(chips)!RES_0402-0.0,5%,1/16W,CHIP,G21A!!!F1921!B!!!!
S!GND!R1U3!1!@baseboard_fab2_lib.baseboard_fab2(sch_1):page141_i114@mstr_discrete.res(chips)!RES_0402-0.0,5%,1/16W,CHIP,G21A!!!F1924!A!!!!
S!GND_NIC!R1U3!2!@baseboard_fab2_lib.baseboard_fab2(sch_1):page141_i114@mstr_discrete.res(chips)!RES_0402-0.0,5%,1/16W,CHIP,G21A!!!F1924!B!!!!
S!SPI_PCH_IO3!R2T2!1!@baseboard_fab2_lib.baseboard_fab2(sch_1):page154_i92@mstr_discrete.res(chips)!RES_0402-0.0,5%,1/16W,CHIP,G21A!!!F1911!A!!!!
S!SPI_PCH_IO3_R1!R2T2!2!@baseboard_fab2_lib.baseboard_fab2(sch_1):page154_i92@mstr_discrete.res(chips)!RES_0402-0.0,5%,1/16W,CHIP,G21A!!!F1911!B!!!!
S!JTAG_BMC_TDI!R8G8!1!@baseboard_fab2_lib.baseboard_fab2(sch_1):page189_i17@mstr_discrete.res(chips)!RES_0402-0.0,5%,1/16W,CHIP,G21A!!!F1770!A!!!!
S!JTAG_TDI!R8G8!2!@baseboard_fab2_lib.baseboard_fab2(sch_1):page189_i17@mstr_discrete.res(chips)!RES_0402-0.0,5%,1/16W,CHIP,G21A!!!F1770!B!!!!
S!JTAG_BMC_TMS!R8G14!1!@baseboard_fab2_lib.baseboard_fab2(sch_1):page189_i20@mstr_discrete.res(chips)!RES_0402-0.0,5%,1/16W,CHIP,G21A!!!F1767!A!!!!
S!JTAG_TMS!R8G14!2!@baseboard_fab2_lib.baseboard_fab2(sch_1):page189_i20@mstr_discrete.res(chips)!RES_0402-0.0,5%,1/16W,CHIP,G21A!!!F1767!B!!!!
S!JTAG_BMC_TCK!R8G17!1!@baseboard_fab2_lib.baseboard_fab2(sch_1):page189_i25@mstr_discrete.res(chips)!RES_0402-0.0,5%,1/16W,CHIP,G21A!!!F1766!A!!!!
S!JTAG_TCK!R8G17!2!@baseboard_fab2_lib.baseboard_fab2(sch_1):page189_i25@mstr_discrete.res(chips)!RES_0402-0.0,5%,1/16W,CHIP,G21A!!!F1766!B!!!!
S!JTAG_BMC_TDO!R7G17!1!@baseboard_fab2_lib.baseboard_fab2(sch_1):page189_i37@mstr_discrete.res(chips)!RES_0402-0.0,5%,1/16W,CHIP,G21A!!!F1797!A!!!!
S!JTAG_TDO!R7G17!2!@baseboard_fab2_lib.baseboard_fab2(sch_1):page189_i37@mstr_discrete.res(chips)!RES_0402-0.0,5%,1/16W,CHIP,G21A!!!F1797!B!!!!
S!JTAG_BMC_TRST_N!R8G10!1!@baseboard_fab2_lib.baseboard_fab2(sch_1):page189_i7@mstr_discrete.res(chips)!RES_0402-0.0,5%,1/16W,CHIP,G21A!!!F1769!A!!!!
S!JTAG_TRST_N!R8G10!2!@baseboard_fab2_lib.baseboard_fab2(sch_1):page189_i7@mstr_discrete.res(chips)!RES_0402-0.0,5%,1/16W,CHIP,G21A!!!F1769!B!!!!
S!RST_BMC_SRST_N!R7D23!1!@baseboard_fab2_lib.baseboard_fab2(sch_1):page118_i131@mstr_discrete.res(chips)!RES_0402-0.0,5%,1/16W,CHIP,G21A!!!F1810!A!!!!
S!RST_BMC_SRST_R_N!R7D23!2!@baseboard_fab2_lib.baseboard_fab2(sch_1):page118_i131@mstr_discrete.res(chips)!RES_0402-0.0,5%,1/16W,CHIP,G21A!!!F1810!B!!!!
S!SPI_PCH_MOSI_R!R7C15!1!@baseboard_fab2_lib.baseboard_fab2(sch_1):page121_i31@mstr_discrete.res(chips)!RES_0402-0.0,5%,1/16W,CHIP,G21A!!!F1812!A!!!!
S!SPI_PCH_MOSI!R7C15!2!@baseboard_fab2_lib.baseboard_fab2(sch_1):page121_i31@mstr_discrete.res(chips)!RES_0402-0.0,5%,1/16W,CHIP,G21A!!!F1812!B!!!!
S!SPI_PCH_MISO!R8F6!1!@baseboard_fab2_lib.baseboard_fab2(sch_1):page154_i119@mstr_discrete.res(chips)!RES_0402-0.0,5%,1/16W,CHIP,G21A!!!F1775!A!!!!
S!SPI_PCH_MISO_R!R8F6!2!@baseboard_fab2_lib.baseboard_fab2(sch_1):page154_i119@mstr_discrete.res(chips)!RES_0402-0.0,5%,1/16W,CHIP,G21A!!!F1775!B!!!!
S!SPI_PCH_IO2!R2R12!1!@baseboard_fab2_lib.baseboard_fab2(sch_1):page154_i93@mstr_discrete.res(chips)!RES_0402-0.0,5%,1/16W,CHIP,G21A!!!F1912!A!!!!
S!SPI_PCH_IO2_R1!R2R12!2!@baseboard_fab2_lib.baseboard_fab2(sch_1):page154_i93@mstr_discrete.res(chips)!RES_0402-0.0,5%,1/16W,CHIP,G21A!!!F1912!B!!!!
S!RMII_BMC_OCP_CRSDV!R1M15!1!@baseboard_fab2_lib.baseboard_fab2(sch_1):page186_i339@mstr_discrete.res(chips)!RES_0402-0.0,5%,1/16W,CHIP,G21A!!!F1930!A!!!!
S!RMII_BMC_OCP_CRSDV_R!R1M15!2!@baseboard_fab2_lib.baseboard_fab2(sch_1):page186_i339@mstr_discrete.res(chips)!RES_0402-0.0,5%,1/16W,CHIP,G21A!!!F1930!B!!!!
S!RMII_BMC_OCP_RXD0!R1M17!1!@baseboard_fab2_lib.baseboard_fab2(sch_1):page186_i338@mstr_discrete.res(chips)!RES_0402-0.0,5%,1/16W,CHIP,G21A!!!F1928!A!!!!
S!RMII_BMC_OCP_RXD0_R!R1M17!2!@baseboard_fab2_lib.baseboard_fab2(sch_1):page186_i338@mstr_discrete.res(chips)!RES_0402-0.0,5%,1/16W,CHIP,G21A!!!F1928!B!!!!
S!RMII_BMC_OCP_RXD1!R1M16!1!@baseboard_fab2_lib.baseboard_fab2(sch_1):page186_i337@mstr_discrete.res(chips)!RES_0402-0.0,5%,1/16W,CHIP,G21A!!!F1929!A!!!!
S!RMII_BMC_OCP_RXD1_R!R1M16!2!@baseboard_fab2_lib.baseboard_fab2(sch_1):page186_i337@mstr_discrete.res(chips)!RES_0402-0.0,5%,1/16W,CHIP,G21A!!!F1929!B!!!!
S!RMII_BMC_OCP_RXER_R!R1M18!1!@baseboard_fab2_lib.baseboard_fab2(sch_1):page186_i340@mstr_discrete.res(chips)!RES_0402-0.0,5%,1/16W,CHIP,G21A!!!F1927!A!!!!
S!RMII_BMC_OCP_RXER!R1M18!2!@baseboard_fab2_lib.baseboard_fab2(sch_1):page186_i340@mstr_discrete.res(chips)!RES_0402-0.0,5%,1/16W,CHIP,G21A!!!F1927!B!!!!
S!VR_PVCCIN_CPU1_VD12!R9N15!1!@baseboard_fab2_lib.baseboard_fab2(sch_1):page206_i122@mstr_discrete.res(chips)!RES_0402-0.0,5%,1/16W,CHIP,G21A!!!F1728!A!!!!
S!VR_PVCCIN_CPU1_AIREF1!R9N15!2!@baseboard_fab2_lib.baseboard_fab2(sch_1):page206_i122@mstr_discrete.res(chips)!RES_0402-0.0,5%,1/16W,CHIP,G21A!!!F1728!B!!!!
S!VR_PVCCIN_CPU1_VD12!R9N5!1!@baseboard_fab2_lib.baseboard_fab2(sch_1):page206_i128@mstr_discrete.res(chips)!RES_0402-0.0,5%,1/16W,CHIP,G21A!!!F1732!A!!!!
S!VR_PVSA_CPU1_BIREF1!R9N5!2!@baseboard_fab2_lib.baseboard_fab2(sch_1):page206_i128@mstr_discrete.res(chips)!RES_0402-0.0,5%,1/16W,CHIP,G21A!!!F1732!B!!!!
S!VR_PVCCIN_CPU1_VD12!R9N17!1!@baseboard_fab2_lib.baseboard_fab2(sch_1):page206_i123@mstr_discrete.res(chips)!RES_0402-0.0,5%,1/16W,CHIP,G21A!!!F1726!A!!!!
S!VR_PVCCIN_CPU1_AIREF2!R9N17!2!@baseboard_fab2_lib.baseboard_fab2(sch_1):page206_i123@mstr_discrete.res(chips)!RES_0402-0.0,5%,1/16W,CHIP,G21A!!!F1726!B!!!!
S!VR_PVCCIN_CPU1_VD12!R9N12!1!@baseboard_fab2_lib.baseboard_fab2(sch_1):page206_i124@mstr_discrete.res(chips)!RES_0402-0.0,5%,1/16W,CHIP,G21A!!!F1729!A!!!!
S!VR_PVCCIN_CPU1_AIREF3!R9N12!2!@baseboard_fab2_lib.baseboard_fab2(sch_1):page206_i124@mstr_discrete.res(chips)!RES_0402-0.0,5%,1/16W,CHIP,G21A!!!F1729!B!!!!
S!VR_PVCCIN_CPU1_VD12!R9N10!1!@baseboard_fab2_lib.baseboard_fab2(sch_1):page206_i125@mstr_discrete.res(chips)!RES_0402-0.0,5%,1/16W,CHIP,G21A!!!F1730!A!!!!
S!VR_PVCCIN_CPU1_AIREF4!R9N10!2!@baseboard_fab2_lib.baseboard_fab2(sch_1):page206_i125@mstr_discrete.res(chips)!RES_0402-0.0,5%,1/16W,CHIP,G21A!!!F1730!B!!!!
S!VR_PVCCIN_CPU1_VD12!R9N9!1!@baseboard_fab2_lib.baseboard_fab2(sch_1):page206_i126@mstr_discrete.res(chips)!RES_0402-0.0,5%,1/16W,CHIP,G21A!!!F1731!A!!!!
S!VR_PVCCIN_CPU1_AIREF5!R9N9!2!@baseboard_fab2_lib.baseboard_fab2(sch_1):page206_i126@mstr_discrete.res(chips)!RES_0402-0.0,5%,1/16W,CHIP,G21A!!!F1731!B!!!!
S!VR_PVCCIO_CPU0_VD12!R3P57!1!@baseboard_fab2_lib.baseboard_fab2(sch_1):page211_i91@mstr_discrete.res(chips)!RES_0402-0.0,5%,1/16W,CHIP,G21A!!!F1888!A!!!!
S!VR_PVCCIO_CPU0_AIREF1!R3P57!2!@baseboard_fab2_lib.baseboard_fab2(sch_1):page211_i91@mstr_discrete.res(chips)!RES_0402-0.0,5%,1/16W,CHIP,G21A!!!F1888!B!!!!
S!VR_PVCCIO_CPU1_VD12!R4D45!1!@baseboard_fab2_lib.baseboard_fab2(sch_1):page213_i94@mstr_discrete.res(chips)!RES_0402-0.0,5%,1/16W,CHIP,G21A!!!F1865!A!!!!
S!VR_PVCCIO_CPU1_AIREF1!R4D45!2!@baseboard_fab2_lib.baseboard_fab2(sch_1):page213_i94@mstr_discrete.res(chips)!RES_0402-0.0,5%,1/16W,CHIP,G21A!!!F1865!B!!!!
S!VR_PVDDQ_ABC_VD12!R3U10!1!@baseboard_fab2_lib.baseboard_fab2(sch_1):page215_i341@mstr_discrete.res(chips)!RES_0402-0.0,5%,1/16W,CHIP,G21A!!!F1876!A!!!!
S!VR_PVDDQ_ABC_AIREF1!R3U10!2!@baseboard_fab2_lib.baseboard_fab2(sch_1):page215_i341@mstr_discrete.res(chips)!RES_0402-0.0,5%,1/16W,CHIP,G21A!!!F1876!B!!!!
S!VR_PVDDQ_ABC_VD12!R3U3!1!@baseboard_fab2_lib.baseboard_fab2(sch_1):page215_i332@mstr_discrete.res(chips)!RES_0402-0.0,5%,1/16W,CHIP,G21A!!!F1874!A!!!!
S!VR_PVDDQ_ABC_AIREF2!R3U3!2!@baseboard_fab2_lib.baseboard_fab2(sch_1):page215_i332@mstr_discrete.res(chips)!RES_0402-0.0,5%,1/16W,CHIP,G21A!!!F1874!B!!!!
S!VR_PVDDQ_DEF_VD12!R3L9!1!@baseboard_fab2_lib.baseboard_fab2(sch_1):page218_i57@mstr_discrete.res(chips)!RES_0402-0.0,5%,1/16W,CHIP,G21A!!!F1894!A!!!!
S!VR_PVDDQ_DEF_AIREF1!R3L9!2!@baseboard_fab2_lib.baseboard_fab2(sch_1):page218_i57@mstr_discrete.res(chips)!RES_0402-0.0,5%,1/16W,CHIP,G21A!!!F1894!B!!!!
S!VR_PVDDQ_DEF_VD12!R3L10!1!@baseboard_fab2_lib.baseboard_fab2(sch_1):page218_i50@mstr_discrete.res(chips)!RES_0402-0.0,5%,1/16W,CHIP,G21A!!!F1893!A!!!!
S!VR_PVDDQ_DEF_AIREF2!R3L10!2!@baseboard_fab2_lib.baseboard_fab2(sch_1):page218_i50@mstr_discrete.res(chips)!RES_0402-0.0,5%,1/16W,CHIP,G21A!!!F1893!B!!!!
S!VR_PVDDQ_GHJ_VD12!R1G28!1!@baseboard_fab2_lib.baseboard_fab2(sch_1):page223_i87@mstr_discrete.res(chips)!RES_0402-0.0,5%,1/16W,CHIP,G21A!!!F1718!A!!!!
S!VR_PVDDQ_GHJ_AIREF1!R1G28!2!@baseboard_fab2_lib.baseboard_fab2(sch_1):page223_i87@mstr_discrete.res(chips)!RES_0402-0.0,5%,1/16W,CHIP,G21A!!!F1718!B!!!!
S!VR_PVDDQ_GHJ_VD12!R1G27!1!@baseboard_fab2_lib.baseboard_fab2(sch_1):page223_i88@mstr_discrete.res(chips)!RES_0402-0.0,5%,1/16W,CHIP,G21A!!!F1717!A!!!!
S!VR_PVDDQ_GHJ_AIREF2!R1G27!2!@baseboard_fab2_lib.baseboard_fab2(sch_1):page223_i88@mstr_discrete.res(chips)!RES_0402-0.0,5%,1/16W,CHIP,G21A!!!F1717!B!!!!
S!VR_PVDDQ_KLM_VD12!R9M11!1!@baseboard_fab2_lib.baseboard_fab2(sch_1):page226_i87@mstr_discrete.res(chips)!RES_0402-0.0,5%,1/16W,CHIP,G21A!!!F1733!A!!!!
S!VR_PVDDQ_KLM_AIREF1!R9M11!2!@baseboard_fab2_lib.baseboard_fab2(sch_1):page226_i87@mstr_discrete.res(chips)!RES_0402-0.0,5%,1/16W,CHIP,G21A!!!F1733!B!!!!
S!VR_PVDDQ_KLM_VD12!R9M10!1!@baseboard_fab2_lib.baseboard_fab2(sch_1):page226_i88@mstr_discrete.res(chips)!RES_0402-0.0,5%,1/16W,CHIP,G21A!!!F1734!A!!!!
S!VR_PVDDQ_KLM_AIREF2!R9M10!2!@baseboard_fab2_lib.baseboard_fab2(sch_1):page226_i88@mstr_discrete.res(chips)!RES_0402-0.0,5%,1/16W,CHIP,G21A!!!F1734!B!!!!
S!VR_PVNN_P1V05_PCH_VD12!R2L1!1!@baseboard_fab2_lib.baseboard_fab2(sch_1):page235_i224@mstr_discrete.res(chips)!RES_0402-0.0,5%,1/16W,CHIP,G21A!!!F1920!A!!!!
S!VR_PVNN_PCH_AIREF1!R2L1!2!@baseboard_fab2_lib.baseboard_fab2(sch_1):page235_i224@mstr_discrete.res(chips)!RES_0402-0.0,5%,1/16W,CHIP,G21A!!!F1920!B!!!!
S!VR_PVNN_P1V05_PCH_VD12!R2L7!1!@baseboard_fab2_lib.baseboard_fab2(sch_1):page235_i225@mstr_discrete.res(chips)!RES_0402-0.0,5%,1/16W,CHIP,G21A!!!F1919!A!!!!
S!VR_P1V05_PCH_BIREF1!R2L7!2!@baseboard_fab2_lib.baseboard_fab2(sch_1):page235_i225@mstr_discrete.res(chips)!RES_0402-0.0,5%,1/16W,CHIP,G21A!!!F1919!B!!!!
S!VR_PVCCIN_CPU0_VD12!R6P29!1!@baseboard_fab2_lib.baseboard_fab2(sch_1):page201_i154@mstr_discrete.res(chips)!RES_0402-0.0,5%,1/16W,CHIP,G21A!!!F1830!A!!!!
S!VR_PVSA_CPU0_BIREF1!R6P29!2!@baseboard_fab2_lib.baseboard_fab2(sch_1):page201_i154@mstr_discrete.res(chips)!RES_0402-0.0,5%,1/16W,CHIP,G21A!!!F1830!B!!!!
S!VR_PVCCIN_CPU0_VD12!R6P43!1!@baseboard_fab2_lib.baseboard_fab2(sch_1):page201_i150@mstr_discrete.res(chips)!RES_0402-0.0,5%,1/16W,CHIP,G21A!!!F1824!A!!!!
S!VR_PVCCIN_CPU0_AIREF1!R6P43!2!@baseboard_fab2_lib.baseboard_fab2(sch_1):page201_i150@mstr_discrete.res(chips)!RES_0402-0.0,5%,1/16W,CHIP,G21A!!!F1824!B!!!!
S!VR_PVCCIN_CPU0_VD12!R6P42!1!@baseboard_fab2_lib.baseboard_fab2(sch_1):page201_i139@mstr_discrete.res(chips)!RES_0402-0.0,5%,1/16W,CHIP,G21A!!!F1825!A!!!!
S!VR_PVCCIN_CPU0_AIREF2!R6P42!2!@baseboard_fab2_lib.baseboard_fab2(sch_1):page201_i139@mstr_discrete.res(chips)!RES_0402-0.0,5%,1/16W,CHIP,G21A!!!F1825!B!!!!
S!VR_PVCCIN_CPU0_VD12!R6P38!1!@baseboard_fab2_lib.baseboard_fab2(sch_1):page201_i147@mstr_discrete.res(chips)!RES_0402-0.0,5%,1/16W,CHIP,G21A!!!F1827!A!!!!
S!VR_PVCCIN_CPU0_AIREF3!R6P38!2!@baseboard_fab2_lib.baseboard_fab2(sch_1):page201_i147@mstr_discrete.res(chips)!RES_0402-0.0,5%,1/16W,CHIP,G21A!!!F1827!B!!!!
S!VR_PVCCIN_CPU0_VD12!R6P34!1!@baseboard_fab2_lib.baseboard_fab2(sch_1):page201_i148@mstr_discrete.res(chips)!RES_0402-0.0,5%,1/16W,CHIP,G21A!!!F1828!A!!!!
S!VR_PVCCIN_CPU0_AIREF4!R6P34!2!@baseboard_fab2_lib.baseboard_fab2(sch_1):page201_i148@mstr_discrete.res(chips)!RES_0402-0.0,5%,1/16W,CHIP,G21A!!!F1828!B!!!!
S!VR_PVCCIN_CPU0_VD12!R6P30!1!@baseboard_fab2_lib.baseboard_fab2(sch_1):page201_i149@mstr_discrete.res(chips)!RES_0402-0.0,5%,1/16W,CHIP,G21A!!!F1829!A!!!!
S!VR_PVCCIN_CPU0_AIREF5!R6P30!2!@baseboard_fab2_lib.baseboard_fab2(sch_1):page201_i149@mstr_discrete.res(chips)!RES_0402-0.0,5%,1/16W,CHIP,G21A!!!F1829!B!!!!
S!RMII_BMC_PCH_SPRNGVLLE_CRSDV!R3P2!1!@baseboard_fab2_lib.baseboard_fab2(sch_1):page121_i67@mstr_discrete.res(chips)!RES_0402-0.0,5%,1/16W,CHIP,G21A!!!F1886!A!!!!
S!RMII_BMC_PCH_SPRNGVLLE_CRSDV_R1!R3P2!2!@baseboard_fab2_lib.baseboard_fab2(sch_1):page121_i67@mstr_discrete.res(chips)!RES_0402-0.0,5%,1/16W,CHIP,G21A!!!F1886!B!!!!
S!RMII_SPRNGVLLE_BMC_PCH_RXD1!R2P1!1!@baseboard_fab2_lib.baseboard_fab2(sch_1):page121_i66@mstr_discrete.res(chips)!RES_0402-0.0,5%,1/16W,CHIP,G21A!!!F1914!A!!!!
S!RMII_SPRNGVLLE_BMC_PCH_RXD1_R1!R2P1!2!@baseboard_fab2_lib.baseboard_fab2(sch_1):page121_i66@mstr_discrete.res(chips)!RES_0402-0.0,5%,1/16W,CHIP,G21A!!!F1914!B!!!!
S!RMII_SPRNGVLLE_BMC_PCH_RXD0!R3P3!1!@baseboard_fab2_lib.baseboard_fab2(sch_1):page121_i65@mstr_discrete.res(chips)!RES_0402-0.0,5%,1/16W,CHIP,G21A!!!F1885!A!!!!
S!RMII_SPRNGVLLE_BMC_PCH_RXD0_R1!R3P3!2!@baseboard_fab2_lib.baseboard_fab2(sch_1):page121_i65@mstr_discrete.res(chips)!RES_0402-0.0,5%,1/16W,CHIP,G21A!!!F1885!B!!!!
S!SP1_BMC_HOST_UART_RX!R9F54!1!@baseboard_fab2_lib.baseboard_fab2(sch_1):page183_i52@mstr_discrete.res(chips)!RES_0402-0.0,5%,1/16W,CHIP,G21A!!!F1750!A!!!!
S!SP1_HOST_BRIDGE_UART_RX!R9F54!2!@baseboard_fab2_lib.baseboard_fab2(sch_1):page183_i52@mstr_discrete.res(chips)!RES_0402-0.0,5%,1/16W,CHIP,G21A!!!F1750!B!!!!
S!UART_BMC_RXD5!R9F53!1!@baseboard_fab2_lib.baseboard_fab2(sch_1):page183_i53@mstr_discrete.res(chips)!RES_0402-0.0,5%,1/16W,CHIP,G21A!!!F1751!A!!!!
S!UART_BRIDGE_RXD5!R9F53!2!@baseboard_fab2_lib.baseboard_fab2(sch_1):page183_i53@mstr_discrete.res(chips)!RES_0402-0.0,5%,1/16W,CHIP,G21A!!!F1751!B!!!!
S!SP1_HOST_BRIDGE_UART_TX!R9F56!1!@baseboard_fab2_lib.baseboard_fab2(sch_1):page183_i49@mstr_discrete.res(chips)!RES_0402-0.0,5%,1/16W,CHIP,G21A!!!F1749!A!!!!
S!SP1_BMC_HOST_UART_TX!R9F56!2!@baseboard_fab2_lib.baseboard_fab2(sch_1):page183_i49@mstr_discrete.res(chips)!RES_0402-0.0,5%,1/16W,CHIP,G21A!!!F1749!B!!!!
S!UART_BRIDGE_TXD5!R9F57!1!@baseboard_fab2_lib.baseboard_fab2(sch_1):page183_i48@mstr_discrete.res(chips)!RES_0402-0.0,5%,1/16W,CHIP,G21A!!!F1748!A!!!!
S!UART_BMC_TXD5!R9F57!2!@baseboard_fab2_lib.baseboard_fab2(sch_1):page183_i48@mstr_discrete.res(chips)!RES_0402-0.0,5%,1/16W,CHIP,G21A!!!F1748!B!!!!
S!LED_PCH_SATA_HDD_N!R1M10!1!@baseboard_fab2_lib.baseboard_fab2(sch_1):page177_i6@mstr_discrete.res(chips)!RES_0402-0.0,5%,1/16W,CHIP,G21A!!!F1932!A!!!!
S!LED_SATA_ACT_R_N!R1M10!2!@baseboard_fab2_lib.baseboard_fab2(sch_1):page177_i6@mstr_discrete.res(chips)!RES_0402-0.0,5%,1/16W,CHIP,G21A!!!F1932!B!!!!
S!LED_PCH_SSATA_HDD_N!R1M13!1!@baseboard_fab2_lib.baseboard_fab2(sch_1):page177_i3@mstr_discrete.res(chips)!RES_0402-0.0,5%,1/16W,CHIP,G21A!!!F1931!A!!!!
S!LED_SAS_ACT_R_N!R1M13!2!@baseboard_fab2_lib.baseboard_fab2(sch_1):page177_i3@mstr_discrete.res(chips)!RES_0402-0.0,5%,1/16W,CHIP,G21A!!!F1931!B!!!!
S!FAN_TACH2!R9T2!1!@baseboard_fab2_lib.baseboard_fab2(sch_1):page181_i255@mstr_discrete.res(chips)!RES_0402-0.0,5%,1/16W,CHIP,G21A!!!F1720!A!!!!
S!FAN_TACH2_R!R9T2!2!@baseboard_fab2_lib.baseboard_fab2(sch_1):page181_i255@mstr_discrete.res(chips)!RES_0402-0.0,5%,1/16W,CHIP,G21A!!!F1720!B!!!!
S!FAN_TACH3!R9R9!1!@baseboard_fab2_lib.baseboard_fab2(sch_1):page181_i254@mstr_discrete.res(chips)!RES_0402-0.0,5%,1/16W,CHIP,G21A!!!F1723!A!!!!
S!FAN_TACH3_R!R9R9!2!@baseboard_fab2_lib.baseboard_fab2(sch_1):page181_i254@mstr_discrete.res(chips)!RES_0402-0.0,5%,1/16W,CHIP,G21A!!!F1723!B!!!!
S!FAN_TACH1!R9R10!1!@baseboard_fab2_lib.baseboard_fab2(sch_1):page181_i256@mstr_discrete.res(chips)!RES_0402-0.0,5%,1/16W,CHIP,G21A!!!F1722!A!!!!
S!FAN_TACH1_R!R9R10!2!@baseboard_fab2_lib.baseboard_fab2(sch_1):page181_i256@mstr_discrete.res(chips)!RES_0402-0.0,5%,1/16W,CHIP,G21A!!!F1722!B!!!!
S!FAN_PWM_OUT_SYS0_R!R9T1!1!@baseboard_fab2_lib.baseboard_fab2(sch_1):page181_i261@mstr_discrete.res(chips)!RES_0402-0.0,5%,1/16W,CHIP,G21A!!!F1721!A!!!!
S!FAN_PWM_OUT_SYS0_R1!R9T1!2!@baseboard_fab2_lib.baseboard_fab2(sch_1):page181_i261@mstr_discrete.res(chips)!RES_0402-0.0,5%,1/16W,CHIP,G21A!!!F1721!B!!!!
S!FM_ADR_SMI_GPIO_R_N!R2R4!1!@baseboard_fab2_lib.baseboard_fab2(sch_1):page191_i184@mstr_discrete.res(chips)!RES_0402-0.0,5%,1/16W,CHIP,G21A!!!F1913!A!!!!
S!FM_ADR_SMI_GPIO_N!R2R4!2!@baseboard_fab2_lib.baseboard_fab2(sch_1):page191_i184@mstr_discrete.res(chips)!RES_0402-0.0,5%,1/16W,CHIP,G21A!!!F1913!B!!!!
S!JTAG_TDO!R7G21!1!@baseboard_fab2_lib.baseboard_fab2(sch_1):page189_i63@mstr_discrete.res(chips)!RES_0402-0.0,5%,1/16W,CHIP,G21A!!!F1796!A!!!!
S!JTAG_TDO_R!R7G21!2!@baseboard_fab2_lib.baseboard_fab2(sch_1):page189_i63@mstr_discrete.res(chips)!RES_0402-0.0,5%,1/16W,CHIP,G21A!!!F1796!B!!!!
S!JTAG_TMS!R8G21!1!@baseboard_fab2_lib.baseboard_fab2(sch_1):page189_i65@mstr_discrete.res(chips)!RES_0402-0.0,5%,1/16W,CHIP,G21A!!!F1763!A!!!!
S!JTAG_TMS_R!R8G21!2!@baseboard_fab2_lib.baseboard_fab2(sch_1):page189_i65@mstr_discrete.res(chips)!RES_0402-0.0,5%,1/16W,CHIP,G21A!!!F1763!B!!!!
S!JTAG_TDI!R8G19!1!@baseboard_fab2_lib.baseboard_fab2(sch_1):page189_i64@mstr_discrete.res(chips)!RES_0402-0.0,5%,1/16W,CHIP,G21A!!!F1764!A!!!!
S!JTAG_TDI_R!R8G19!2!@baseboard_fab2_lib.baseboard_fab2(sch_1):page189_i64@mstr_discrete.res(chips)!RES_0402-0.0,5%,1/16W,CHIP,G21A!!!F1764!B!!!!
S!JTAG_TCK!R8G22!1!@baseboard_fab2_lib.baseboard_fab2(sch_1):page189_i66@mstr_discrete.res(chips)!RES_0402-0.0,5%,1/16W,CHIP,G21A!!!F1762!A!!!!
S!JTAG_TCK_R!R8G22!2!@baseboard_fab2_lib.baseboard_fab2(sch_1):page189_i66@mstr_discrete.res(chips)!RES_0402-0.0,5%,1/16W,CHIP,G21A!!!F1762!B!!!!
S!RST_BMC_SRST_N!R9E14!1!@baseboard_fab2_lib.baseboard_fab2(sch_1):page157_i379@mstr_discrete.res(chips)!RES_0402-0.0,5%,1/16W,CHIP,G21A!!!F1757!A!!!!
S!FM_BMC_ENABLE_N!R9E14!2!@baseboard_fab2_lib.baseboard_fab2(sch_1):page157_i379@mstr_discrete.res(chips)!RES_0402-0.0,5%,1/16W,CHIP,G21A!!!F1757!B!!!!
S!FM_PVCCIN_PVCCSA_CPU0_EN_LVC1!R6P18!1!@baseboard_fab2_lib.baseboard_fab2(sch_1):page201_i131@mstr_discrete.res(chips)!RES_0402-0.0,5%,1/16W,CHIP,G21A!!!F1831!A!!!!
S!VR_PVCCIN_CPU0_VREN!R6P18!2!@baseboard_fab2_lib.baseboard_fab2(sch_1):page201_i131@mstr_discrete.res(chips)!RES_0402-0.0,5%,1/16W,CHIP,G21A!!!F1831!B!!!!
S!FM_PVCCIN_PVCCSA_CPU1_EN_LVC1!R9N16!1!@baseboard_fab2_lib.baseboard_fab2(sch_1):page206_i119@mstr_discrete.res(chips)!RES_0402-0.0,5%,1/16W,CHIP,G21A!!!F1727!A!!!!
S!VR_PVCCIN_CPU1_VREN!R9N16!2!@baseboard_fab2_lib.baseboard_fab2(sch_1):page206_i119@mstr_discrete.res(chips)!RES_0402-0.0,5%,1/16W,CHIP,G21A!!!F1727!B!!!!
S!FM_PVCCIO_CPU0_EN!R3P26!1!@baseboard_fab2_lib.baseboard_fab2(sch_1):page211_i87@mstr_discrete.res(chips)!RES_0402-0.0,5%,1/16W,CHIP,G21A!!!F1880!A!!!!
S!VR_PVCCIO_CPU0_EN!R3P26!2!@baseboard_fab2_lib.baseboard_fab2(sch_1):page211_i87@mstr_discrete.res(chips)!RES_0402-0.0,5%,1/16W,CHIP,G21A!!!F1880!B!!!!
S!FM_PVCCIO_CPU1_EN!R6P41!1!@baseboard_fab2_lib.baseboard_fab2(sch_1):page213_i90@mstr_discrete.res(chips)!RES_0402-0.0,5%,1/16W,CHIP,G21A!!!F1826!A!!!!
S!VR_PVCCIO_CPU1_EN!R6P41!2!@baseboard_fab2_lib.baseboard_fab2(sch_1):page213_i90@mstr_discrete.res(chips)!RES_0402-0.0,5%,1/16W,CHIP,G21A!!!F1826!B!!!!
S!FM_PVDDQ_ABC_EN!R7F21!1!@baseboard_fab2_lib.baseboard_fab2(sch_1):page215_i343@mstr_discrete.res(chips)!RES_0402-0.0,5%,1/16W,CHIP,G21A!!!F1801!A!!!!
S!VR_PVDDQ_ABC_VREN!R7F21!2!@baseboard_fab2_lib.baseboard_fab2(sch_1):page215_i343@mstr_discrete.res(chips)!RES_0402-0.0,5%,1/16W,CHIP,G21A!!!F1801!B!!!!
S!FM_PVDDQ_DEF_EN!R3M6!1!@baseboard_fab2_lib.baseboard_fab2(sch_1):page218_i59@mstr_discrete.res(chips)!RES_0402-0.0,5%,1/16W,CHIP,G21A!!!F1890!A!!!!
S!VR_PVDDQ_DEF_VREN!R3M6!2!@baseboard_fab2_lib.baseboard_fab2(sch_1):page218_i59@mstr_discrete.res(chips)!RES_0402-0.0,5%,1/16W,CHIP,G21A!!!F1890!B!!!!
S!FM_PVDDQ_GHJ_EN!R9U7!1!@baseboard_fab2_lib.baseboard_fab2(sch_1):page223_i84@mstr_discrete.res(chips)!RES_0402-0.0,5%,1/16W,CHIP,G21A!!!F1716!A!!!!
S!VR_PVDDQ_GHJ_VREN!R9U7!2!@baseboard_fab2_lib.baseboard_fab2(sch_1):page223_i84@mstr_discrete.res(chips)!RES_0402-0.0,5%,1/16W,CHIP,G21A!!!F1716!B!!!!
S!FM_PVDDQ_KLM_EN!R9M9!1!@baseboard_fab2_lib.baseboard_fab2(sch_1):page226_i84@mstr_discrete.res(chips)!RES_0402-0.0,5%,1/16W,CHIP,G21A!!!F1735!A!!!!
S!VR_PVDDQ_KLM_VREN!R9M9!2!@baseboard_fab2_lib.baseboard_fab2(sch_1):page226_i84@mstr_discrete.res(chips)!RES_0402-0.0,5%,1/16W,CHIP,G21A!!!F1735!B!!!!
S!FM_PVPP_CPU0_EN!R7F9!1!@baseboard_fab2_lib.baseboard_fab2(sch_1):page231_i220@mstr_discrete.res(chips)!RES_0402-0.0,5%,1/16W,CHIP,G21A!!!F1803!A!!!!
S!FM_PVPP_PVDDQ_CPU0_EN_ABC!R7F9!2!@baseboard_fab2_lib.baseboard_fab2(sch_1):page231_i220@mstr_discrete.res(chips)!RES_0402-0.0,5%,1/16W,CHIP,G21A!!!F1803!B!!!!
S!FM_PVPP_CPU0_EN!R7B9!1!@baseboard_fab2_lib.baseboard_fab2(sch_1):page232_i307@mstr_discrete.res(chips)!RES_0402-0.0,5%,1/16W,CHIP,G21A!!!F1814!A!!!!
S!FM_PVPP_PVDDQ_CPU0_EN_DEF!R7B9!2!@baseboard_fab2_lib.baseboard_fab2(sch_1):page232_i307@mstr_discrete.res(chips)!RES_0402-0.0,5%,1/16W,CHIP,G21A!!!F1814!B!!!!
S!FM_PVPP_CPU1_EN!R4G4!1!@baseboard_fab2_lib.baseboard_fab2(sch_1):page233_i275@mstr_discrete.res(chips)!RES_0402-0.0,5%,1/16W,CHIP,G21A!!!F1854!A!!!!
S!FM_PVPP_PVDDQ_CPU1_EN_GHJ!R4G4!2!@baseboard_fab2_lib.baseboard_fab2(sch_1):page233_i275@mstr_discrete.res(chips)!RES_0402-0.0,5%,1/16W,CHIP,G21A!!!F1854!B!!!!
S!FM_PVPP_CPU1_EN!R4B1!1!@baseboard_fab2_lib.baseboard_fab2(sch_1):page234_i220@mstr_discrete.res(chips)!RES_0402-0.0,5%,1/16W,CHIP,G21A!!!F1871!A!!!!
S!FM_PVPP_PVDDQ_CPU1_EN_KLM!R4B1!2!@baseboard_fab2_lib.baseboard_fab2(sch_1):page234_i220@mstr_discrete.res(chips)!RES_0402-0.0,5%,1/16W,CHIP,G21A!!!F1871!B!!!!
S!PWRGD_P1V8_PCH_STBY!R2L17!1!@baseboard_fab2_lib.baseboard_fab2(sch_1):page235_i221@mstr_discrete.res(chips)!RES_0402-0.0,5%,1/16W,CHIP,G21A!!!F1917!A!!!!
S!VR_PVNN_PCH_VREN!R2L17!2!@baseboard_fab2_lib.baseboard_fab2(sch_1):page235_i221@mstr_discrete.res(chips)!RES_0402-0.0,5%,1/16W,CHIP,G21A!!!F1917!B!!!!
S!PWRGD_P5V_STBY!R8F2!1!@baseboard_fab2_lib.baseboard_fab2(sch_1):page240_i176@mstr_discrete.res(chips)!RES_0402-0.0,5%,1/16W,CHIP,G21A!!!F1776!A!!!!
S!VR_P3V3_STBY_EN!R8F2!2!@baseboard_fab2_lib.baseboard_fab2(sch_1):page240_i176@mstr_discrete.res(chips)!RES_0402-0.0,5%,1/16W,CHIP,G21A!!!F1776!B!!!!
S!PWRGD_P12V_HSC_DLY!R8E33!1!@baseboard_fab2_lib.baseboard_fab2(sch_1):page241_i91@mstr_discrete.res(chips)!RES_0402-0.0,5%,1/16W,CHIP,G21A!!!F1780!A!!!!
S!VR_P5V_STBY_EN!R8E33!2!@baseboard_fab2_lib.baseboard_fab2(sch_1):page241_i91@mstr_discrete.res(chips)!RES_0402-0.0,5%,1/16W,CHIP,G21A!!!F1780!B!!!!
S!FM_GBE_LOM_DISABLE_N!R8C24!1!@baseboard_fab2_lib.baseboard_fab2(sch_1):page118_i120@mstr_discrete.res(chips)!RES_0402-0.0,5%,1/16W,CHIP,G21A!!!F1789!A!!!!
S!FM_1GB_LOM_DISABLE_N!R8C24!2!@baseboard_fab2_lib.baseboard_fab2(sch_1):page118_i120@mstr_discrete.res(chips)!RES_0402-0.0,5%,1/16W,CHIP,G21A!!!F1789!B!!!!
S!PVDDQ_ABC!R6U5!1!@baseboard_fab2_lib.baseboard_fab2(sch_1):page221_i32@mstr_discrete.res(chips)!RES_0402-0.0,5%,1/16W,CHIP,G21A!!!F1820!A!!!!
S!VSENSE_PVDDQ_ABC_VTT!R6U5!2!@baseboard_fab2_lib.baseboard_fab2(sch_1):page221_i32@mstr_discrete.res(chips)!RES_0402-0.0,5%,1/16W,CHIP,G21A!!!F1820!B!!!!
S!PVDDQ_DEF!R6L10!1!@baseboard_fab2_lib.baseboard_fab2(sch_1):page222_i34@mstr_discrete.res(chips)!RES_0402-0.0,5%,1/16W,CHIP,G21A!!!F1837!A!!!!
S!VSENSE_PVDDQ_DEF_VTT!R6L10!2!@baseboard_fab2_lib.baseboard_fab2(sch_1):page222_i34@mstr_discrete.res(chips)!RES_0402-0.0,5%,1/16W,CHIP,G21A!!!F1837!B!!!!
S!PVDDQ_GHJ!R6U6!1!@baseboard_fab2_lib.baseboard_fab2(sch_1):page229_i39@mstr_discrete.res(chips)!RES_0402-0.0,5%,1/16W,CHIP,G21A!!!F1819!A!!!!
S!VSENSE_PVDDQ_GHJ_VTT!R6U6!2!@baseboard_fab2_lib.baseboard_fab2(sch_1):page229_i39@mstr_discrete.res(chips)!RES_0402-0.0,5%,1/16W,CHIP,G21A!!!F1819!B!!!!
S!JTAG_PLD_TDI!R8G7!1!@baseboard_fab2_lib.baseboard_fab2(sch_1):page189_i18@mstr_discrete.res(chips)!RES_0402-0.0,5%,1/16W,CHIP,G21A!!!F1771!A!!!!
S!JTAG_TDI!R8G7!2!@baseboard_fab2_lib.baseboard_fab2(sch_1):page189_i18@mstr_discrete.res(chips)!RES_0402-0.0,5%,1/16W,CHIP,G21A!!!F1771!B!!!!
S!JTAG_PLD_TMS!R8G13!1!@baseboard_fab2_lib.baseboard_fab2(sch_1):page189_i23@mstr_discrete.res(chips)!RES_0402-0.0,5%,1/16W,CHIP,G21A!!!F1768!A!!!!
S!JTAG_TMS!R8G13!2!@baseboard_fab2_lib.baseboard_fab2(sch_1):page189_i23@mstr_discrete.res(chips)!RES_0402-0.0,5%,1/16W,CHIP,G21A!!!F1768!B!!!!
S!JTAG_PLD_TCK!R8G18!1!@baseboard_fab2_lib.baseboard_fab2(sch_1):page189_i26@mstr_discrete.res(chips)!RES_0402-0.0,5%,1/16W,CHIP,G21A!!!F1765!A!!!!
S!JTAG_TCK!R8G18!2!@baseboard_fab2_lib.baseboard_fab2(sch_1):page189_i26@mstr_discrete.res(chips)!RES_0402-0.0,5%,1/16W,CHIP,G21A!!!F1765!B!!!!
S!JTAG_PLD_TDO!R7G14!1!@baseboard_fab2_lib.baseboard_fab2(sch_1):page189_i38@mstr_discrete.res(chips)!RES_0402-0.0,5%,1/16W,CHIP,G21A!!!F1798!A!!!!
S!JTAG_TDO!R7G14!2!@baseboard_fab2_lib.baseboard_fab2(sch_1):page189_i38@mstr_discrete.res(chips)!RES_0402-0.0,5%,1/16W,CHIP,G21A!!!F1798!B!!!!
S!GND!R7A18!1!@baseboard_fab2_lib.baseboard_fab2(sch_1):page236_i92@mstr_discrete.res(chips)!RES_0402-0.0,5%,1/16W,CHIP,G21A!!!F1815!A!!!!
S!VSENSE_PVNN_PCH_STBY_AVSN!R7A18!2!@baseboard_fab2_lib.baseboard_fab2(sch_1):page236_i92@mstr_discrete.res(chips)!RES_0402-0.0,5%,1/16W,CHIP,G21A!!!F1815!B!!!!
S!FM_THROTTLE_N!R7E9!1!@baseboard_fab2_lib.baseboard_fab2(sch_1):page95_i108@mstr_discrete.res(chips)!RES_0402-0.0,5%,1/16W,CHIP,G21A!!!F1807!A!!!!
S!FM_THROTTLE_R_N!R7E9!2!@baseboard_fab2_lib.baseboard_fab2(sch_1):page95_i108@mstr_discrete.res(chips)!RES_0402-0.0,5%,1/16W,CHIP,G21A!!!F1807!B!!!!
S!FM_THROTTLE_R1_N!R1R8!1!@baseboard_fab2_lib.baseboard_fab2(sch_1):page170_i51@mstr_discrete.res(chips)!RES_0402-0.0,5%,1/16W,CHIP,G21A!!!F1925!A!!!!
S!FM_THROTTLE_N!R1R8!2!@baseboard_fab2_lib.baseboard_fab2(sch_1):page170_i51@mstr_discrete.res(chips)!RES_0402-0.0,5%,1/16W,CHIP,G21A!!!F1925!B!!!!
S!PVPP_DEF!R7B11!1!@baseboard_fab2_lib.baseboard_fab2(sch_1):page232_i299@mstr_discrete.res(chips)!RES_0402-0.0,5%,1/16W,CHIP,G21A!!!F1813!A!!!!
S!VSENSE_PVPP_DEF!R7B11!2!@baseboard_fab2_lib.baseboard_fab2(sch_1):page232_i299@mstr_discrete.res(chips)!RES_0402-0.0,5%,1/16W,CHIP,G21A!!!F1813!B!!!!
S!PVPP_GHJ!R4G8!1!@baseboard_fab2_lib.baseboard_fab2(sch_1):page233_i271@mstr_discrete.res(chips)!RES_0402-0.0,5%,1/16W,CHIP,G21A!!!F1853!A!!!!
S!VSENSE_PVPP_GHJ!R4G8!2!@baseboard_fab2_lib.baseboard_fab2(sch_1):page233_i271@mstr_discrete.res(chips)!RES_0402-0.0,5%,1/16W,CHIP,G21A!!!F1853!B!!!!
S!PVPP_KLM!R4B3!1!@baseboard_fab2_lib.baseboard_fab2(sch_1):page234_i214@mstr_discrete.res(chips)!RES_0402-0.0,5%,1/16W,CHIP,G21A!!!F1870!A!!!!
S!VSENSE_PVPP_KLM!R4B3!2!@baseboard_fab2_lib.baseboard_fab2(sch_1):page234_i214@mstr_discrete.res(chips)!RES_0402-0.0,5%,1/16W,CHIP,G21A!!!F1870!B!!!!
S!VR_PVPP_DEF_BOOT!R7B19!1!@baseboard_fab2_lib.baseboard_fab2(sch_1):page232_i240@mstr_discrete.res(chips)!RES_0402-0.0,5%,1/16W,CHIP,G21A!!!F1891!A!!!!
S!VR_PVPP_DEF_BOOT_R!R7B19!2!@baseboard_fab2_lib.baseboard_fab2(sch_1):page232_i240@mstr_discrete.res(chips)!RES_0402-0.0,5%,1/16W,CHIP,G21A!!!F1891!B!!!!
S!VR_PVPP_GHJ_BOOT!R4G24!1!@baseboard_fab2_lib.baseboard_fab2(sch_1):page233_i199@mstr_discrete.res(chips)!RES_0402-0.0,5%,1/16W,CHIP,G21A!!!F1823!A!!!!
S!VR_PVPP_GHJ_BOOT_R!R4G24!2!@baseboard_fab2_lib.baseboard_fab2(sch_1):page233_i199@mstr_discrete.res(chips)!RES_0402-0.0,5%,1/16W,CHIP,G21A!!!F1823!B!!!!
S!VR_PVPP_KLM_BOOT!R4B13!1!@baseboard_fab2_lib.baseboard_fab2(sch_1):page234_i155@mstr_discrete.res(chips)!RES_0402-0.0,5%,1/16W,CHIP,G21A!!!F1835!A!!!!
S!VR_PVPP_KLM_BOOT_R!R4B13!2!@baseboard_fab2_lib.baseboard_fab2(sch_1):page234_i155@mstr_discrete.res(chips)!RES_0402-0.0,5%,1/16W,CHIP,G21A!!!F1835!B!!!!
S!UART_MUX_OUT_R!R9F27!1!@baseboard_fab2_lib.baseboard_fab2(sch_1):page158_i91@mstr_discrete.res(chips)!RES_0402-0.0,5%,1/16W,CHIP,G21A!!!F1753!A!!!!
S!SPA_MID_DBG_TX!R9F27!2!@baseboard_fab2_lib.baseboard_fab2(sch_1):page158_i91@mstr_discrete.res(chips)!RES_0402-0.0,5%,1/16W,CHIP,G21A!!!F1753!B!!!!
S!XTAL_24MHZ_PI7C9X1172_IN!R9F58!1!@baseboard_fab2_lib.baseboard_fab2(sch_1):page183_i24@mstr_discrete.res(chips)!RES_0402-0.0,5%,1/16W,CHIP,G21A!!!F1747!A!!!!
S!XTAL_24MHZ_IN_R!R9F58!2!@baseboard_fab2_lib.baseboard_fab2(sch_1):page183_i24@mstr_discrete.res(chips)!RES_0402-0.0,5%,1/16W,CHIP,G21A!!!F1747!B!!!!
S!XTAL_24MHZ_PI7C9X1172_OUT!R9F59!1!@baseboard_fab2_lib.baseboard_fab2(sch_1):page183_i25@mstr_discrete.res(chips)!RES_0402-0.0,5%,1/16W,CHIP,G21A!!!F1746!A!!!!
S!XTAL_24MHZ_OUT_R!R9F59!2!@baseboard_fab2_lib.baseboard_fab2(sch_1):page183_i25@mstr_discrete.res(chips)!RES_0402-0.0,5%,1/16W,CHIP,G21A!!!F1746!B!!!!
S!PVPP_ABC!R7F12!1!@baseboard_fab2_lib.baseboard_fab2(sch_1):page231_i168@mstr_discrete.res(chips)!RES_0402-0.0,5%,1/16W,CHIP,G21A!!!F1802!A!!!!
S!VSENSE_PVPP_ABC!R7F12!2!@baseboard_fab2_lib.baseboard_fab2(sch_1):page231_i168@mstr_discrete.res(chips)!RES_0402-0.0,5%,1/16W,CHIP,G21A!!!F1802!B!!!!
S!P3V3_STBY!R8E25!1!@baseboard_fab2_lib.baseboard_fab2(sch_1):page240_i144@mstr_discrete.res(chips)!RES_0402-0.0,5%,1/16W,CHIP,G21A!!!F1784!A!!!!
S!VSENSE_P3V3_STBY!R8E25!2!@baseboard_fab2_lib.baseboard_fab2(sch_1):page240_i144@mstr_discrete.res(chips)!RES_0402-0.0,5%,1/16W,CHIP,G21A!!!F1784!B!!!!
S!SMB_LAN_STBY_LVC3_SDA_R2!R2N20!1!@baseboard_fab2_lib.baseboard_fab2(sch_1):page138_i171@mstr_discrete.res(chips)!RES_0402-0.0,5%,1/16W,CHIP,G21A!!!F1916!A!!!!
S!SMB_LAN_STBY_LVC3_SDA!R2N20!2!@baseboard_fab2_lib.baseboard_fab2(sch_1):page138_i171@mstr_discrete.res(chips)!RES_0402-0.0,5%,1/16W,CHIP,G21A!!!F1916!B!!!!
S!SMB_LAN_STBY_LVC3_SCL_R2!R2N21!1!@baseboard_fab2_lib.baseboard_fab2(sch_1):page138_i175@mstr_discrete.res(chips)!RES_0402-0.0,5%,1/16W,CHIP,G21A!!!F1915!A!!!!
S!SMB_LAN_STBY_LVC3_SCL!R2N21!2!@baseboard_fab2_lib.baseboard_fab2(sch_1):page138_i175@mstr_discrete.res(chips)!RES_0402-0.0,5%,1/16W,CHIP,G21A!!!F1915!B!!!!
S!VR_PVPP_ABC_BOOT!R7F8!1!@baseboard_fab2_lib.baseboard_fab2(sch_1):page231_i154@mstr_discrete.res(chips)!RES_0402-0.0,5%,1/16W,CHIP,G21A!!!F1804!A!!!!
S!VR_PVPP_ABC_BOOT_R!R7F8!2!@baseboard_fab2_lib.baseboard_fab2(sch_1):page231_i154@mstr_discrete.res(chips)!RES_0402-0.0,5%,1/16W,CHIP,G21A!!!F1804!B!!!!
S!GND!R7F35!1!@baseboard_fab2_lib.baseboard_fab2(sch_1):page231_i170@mstr_discrete.res(chips)!RES_0402-0.0,5%,1/16W,CHIP,G21A!!!F1877!A!!!!
S!AGND_PVPP_ABC!R7F35!2!@baseboard_fab2_lib.baseboard_fab2(sch_1):page231_i170@mstr_discrete.res(chips)!RES_0402-0.0,5%,1/16W,CHIP,G21A!!!F1877!B!!!!
S!GND!R7B20!1!@baseboard_fab2_lib.baseboard_fab2(sch_1):page232_i150@mstr_discrete.res(chips)!RES_0402-0.0,5%,1/16W,CHIP,G21A!!!F1889!A!!!!
S!AGND_PVPP_DEF!R7B20!2!@baseboard_fab2_lib.baseboard_fab2(sch_1):page232_i150@mstr_discrete.res(chips)!RES_0402-0.0,5%,1/16W,CHIP,G21A!!!F1889!B!!!!
S!GND!R4G25!1!@baseboard_fab2_lib.baseboard_fab2(sch_1):page233_i157@mstr_discrete.res(chips)!RES_0402-0.0,5%,1/16W,CHIP,G21A!!!F1822!A!!!!
S!AGND_PVPP_GHJ!R4G25!2!@baseboard_fab2_lib.baseboard_fab2(sch_1):page233_i157@mstr_discrete.res(chips)!RES_0402-0.0,5%,1/16W,CHIP,G21A!!!F1822!B!!!!
S!VR_P3V3_STBY_BOOT!R8E35!1!@baseboard_fab2_lib.baseboard_fab2(sch_1):page240_i127@mstr_discrete.res(chips)!RES_0402-0.0,5%,1/16W,CHIP,G21A!!!F1779!A!!!!
S!VR_P3V3_STBY_BOOT_R!R8E35!2!@baseboard_fab2_lib.baseboard_fab2(sch_1):page240_i127@mstr_discrete.res(chips)!RES_0402-0.0,5%,1/16W,CHIP,G21A!!!F1779!B!!!!
S!VSENSE_RGND_P3V3_STBY!R8E38!1!@baseboard_fab2_lib.baseboard_fab2(sch_1):page240_i140@mstr_discrete.res(chips)!RES_0402-0.0,5%,1/16W,CHIP,G21A!!!F1777!A!!!!
S!AGND_P3V3_STBY!R8E38!2!@baseboard_fab2_lib.baseboard_fab2(sch_1):page240_i140@mstr_discrete.res(chips)!RES_0402-0.0,5%,1/16W,CHIP,G21A!!!F1777!B!!!!
S!GND!R8F11!1!@baseboard_fab2_lib.baseboard_fab2(sch_1):page240_i146@mstr_discrete.res(chips)!RES_0402-0.0,5%,1/16W,CHIP,G21A!!!F1774!A!!!!
S!AGND_P3V3_STBY!R8F11!2!@baseboard_fab2_lib.baseboard_fab2(sch_1):page240_i146@mstr_discrete.res(chips)!RES_0402-0.0,5%,1/16W,CHIP,G21A!!!F1774!B!!!!
S!SPI_PCH_TPM_CS_N!R8D35!1!@baseboard_fab2_lib.baseboard_fab2(sch_1):page184_i92@mstr_discrete.res(chips)!RES_0402-0.0,5%,1/16W,CHIP,G21A!!!F1787!A!!!!
S!SPI_PCH_TPM_CS_R_N!R8D35!2!@baseboard_fab2_lib.baseboard_fab2(sch_1):page184_i92@mstr_discrete.res(chips)!RES_0402-0.0,5%,1/16W,CHIP,G21A!!!F1787!B!!!!
S!IRQ_SPI_TPM_N_R!R8E1!1!@baseboard_fab2_lib.baseboard_fab2(sch_1):page184_i99@mstr_discrete.res(chips)!RES_0402-0.0,5%,1/16W,CHIP,G21A!!!F1786!A!!!!
S!IRQ_PIRQA_SPI_TPM_N!R8E1!2!@baseboard_fab2_lib.baseboard_fab2(sch_1):page184_i99@mstr_discrete.res(chips)!RES_0402-0.0,5%,1/16W,CHIP,G21A!!!F1786!B!!!!
S!NIC_SER_P_MDI_3_DP!R9G9!1!@baseboard_fab2_lib.baseboard_fab2(sch_1):page141_i75@mstr_discrete.res(chips)!RES_0402-0.0,5%,1/16W,CHIP,G21A!!!F1744!A!!!!
S!NIC_MDI_SPRV_RJ45_3_R_DP!R9G9!2!@baseboard_fab2_lib.baseboard_fab2(sch_1):page141_i75@mstr_discrete.res(chips)!RES_0402-0.0,5%,1/16W,CHIP,G21A!!!F1744!B!!!!
S!NIC_SER_N_MDI_3_DN!R9G11!1!@baseboard_fab2_lib.baseboard_fab2(sch_1):page141_i76@mstr_discrete.res(chips)!RES_0402-0.0,5%,1/16W,CHIP,G21A!!!F1743!A!!!!
S!NIC_MDI_SPRV_RJ45_3_R_DN!R9G11!2!@baseboard_fab2_lib.baseboard_fab2(sch_1):page141_i76@mstr_discrete.res(chips)!RES_0402-0.0,5%,1/16W,CHIP,G21A!!!F1743!B!!!!
S!NIC_SET_P_MDI_2_DP!R9G18!1!@baseboard_fab2_lib.baseboard_fab2(sch_1):page141_i77@mstr_discrete.res(chips)!RES_0402-0.0,5%,1/16W,CHIP,G21A!!!F1741!A!!!!
S!NIC_MDI_SPRV_RJ45_2_R_DP!R9G18!2!@baseboard_fab2_lib.baseboard_fab2(sch_1):page141_i77@mstr_discrete.res(chips)!RES_0402-0.0,5%,1/16W,CHIP,G21A!!!F1741!B!!!!
S!NIC_SET_N_MDI_2_DN!R9G17!1!@baseboard_fab2_lib.baseboard_fab2(sch_1):page141_i78@mstr_discrete.res(chips)!RES_0402-0.0,5%,1/16W,CHIP,G21A!!!F1742!A!!!!
S!NIC_MDI_SPRV_RJ45_2_R_DN!R9G17!2!@baseboard_fab2_lib.baseboard_fab2(sch_1):page141_i78@mstr_discrete.res(chips)!RES_0402-0.0,5%,1/16W,CHIP,G21A!!!F1742!B!!!!
S!NIC_MDI_SPRV_RJ45_1_DP!R9G19!1!@baseboard_fab2_lib.baseboard_fab2(sch_1):page141_i79@mstr_discrete.res(chips)!RES_0402-0.0,5%,1/16W,CHIP,G21A!!!F1740!A!!!!
S!NIC_MDI_SPRV_RJ45_1_R_DP!R9G19!2!@baseboard_fab2_lib.baseboard_fab2(sch_1):page141_i79@mstr_discrete.res(chips)!RES_0402-0.0,5%,1/16W,CHIP,G21A!!!F1740!B!!!!
S!NIC_MDI_SPRV_RJ45_1_DN!R9G20!1!@baseboard_fab2_lib.baseboard_fab2(sch_1):page141_i80@mstr_discrete.res(chips)!RES_0402-0.0,5%,1/16W,CHIP,G21A!!!F1739!A!!!!
S!NIC_MDI_SPRV_RJ45_1_R_DN!R9G20!2!@baseboard_fab2_lib.baseboard_fab2(sch_1):page141_i80@mstr_discrete.res(chips)!RES_0402-0.0,5%,1/16W,CHIP,G21A!!!F1739!B!!!!
S!NIC_MDI_SPRV_RJ45_0_DP!R9G24!1!@baseboard_fab2_lib.baseboard_fab2(sch_1):page141_i81@mstr_discrete.res(chips)!RES_0402-0.0,5%,1/16W,CHIP,G21A!!!F1737!A!!!!
S!NIC_MDI_SPRV_RJ45_0_R_DP!R9G24!2!@baseboard_fab2_lib.baseboard_fab2(sch_1):page141_i81@mstr_discrete.res(chips)!RES_0402-0.0,5%,1/16W,CHIP,G21A!!!F1737!B!!!!
S!NIC_MDI_SPRV_RJ45_0_DN!R9G22!1!@baseboard_fab2_lib.baseboard_fab2(sch_1):page141_i82@mstr_discrete.res(chips)!RES_0402-0.0,5%,1/16W,CHIP,G21A!!!F1738!A!!!!
S!NIC_MDI_SPRV_RJ45_0_R_DN!R9G22!2!@baseboard_fab2_lib.baseboard_fab2(sch_1):page141_i82@mstr_discrete.res(chips)!RES_0402-0.0,5%,1/16W,CHIP,G21A!!!F1738!B!!!!
S!XDP_PCH_CPU_TCK0!R9A3!1!@baseboard_fab2_lib.baseboard_fab2(sch_1):page111_i74@mstr_discrete.res(chips)!RES_0402-0.0,5%,1/16W,CHIP,G21A!!!F1759!A!!!!
S!XDP_CPU_TCK0!R9A3!2!@baseboard_fab2_lib.baseboard_fab2(sch_1):page111_i74@mstr_discrete.res(chips)!RES_0402-0.0,5%,1/16W,CHIP,G21A!!!F1759!B!!!!
S!RST_PCIE_RISER1_PERST_N!R2U37!1!@baseboard_fab2_lib.baseboard_fab2(sch_1):page108_i173@mstr_discrete.res(chips)!RES_0402-0.0,5%,1/16W,CHIP,G21A!!!F1902!A!!!!
S!RST_PCIE_RISER1_PERST_R_N!R2U37!2!@baseboard_fab2_lib.baseboard_fab2(sch_1):page108_i173@mstr_discrete.res(chips)!RES_0402-0.0,5%,1/16W,CHIP,G21A!!!F1902!B!!!!
S!FM_PE_M2_WAKE_N!R8E27!1!@baseboard_fab2_lib.baseboard_fab2(sch_1):page142_i32@mstr_discrete.res(chips)!RES_0402-0.0,5%,1/16W,CHIP,G21A!!!F1782!A!!!!
S!FM_ALL_WAKE_N!R8E27!2!@baseboard_fab2_lib.baseboard_fab2(sch_1):page142_i32@mstr_discrete.res(chips)!RES_0402-0.0,5%,1/16W,CHIP,G21A!!!F1782!B!!!!
S!FM_PE_OCP_WAKE_N!R8E26!1!@baseboard_fab2_lib.baseboard_fab2(sch_1):page142_i30@mstr_discrete.res(chips)!RES_0402-0.0,5%,1/16W,CHIP,G21A!!!F1783!A!!!!
S!FM_ALL_WAKE_N!R8E26!2!@baseboard_fab2_lib.baseboard_fab2(sch_1):page142_i30@mstr_discrete.res(chips)!RES_0402-0.0,5%,1/16W,CHIP,G21A!!!F1783!B!!!!
S!FM_PE_SPRV_WAKE_N!R8E21!1!@baseboard_fab2_lib.baseboard_fab2(sch_1):page142_i33@mstr_discrete.res(chips)!RES_0402-0.0,5%,1/16W,CHIP,G21A!!!F1785!A!!!!
S!FM_ALL_WAKE_N!R8E21!2!@baseboard_fab2_lib.baseboard_fab2(sch_1):page142_i33@mstr_discrete.res(chips)!RES_0402-0.0,5%,1/16W,CHIP,G21A!!!F1785!B!!!!
S!FM_PE_SLOTX24_WAKE_N!R8E28!1!@baseboard_fab2_lib.baseboard_fab2(sch_1):page142_i31@mstr_discrete.res(chips)!RES_0402-0.0,5%,1/16W,CHIP,G21A!!!F1781!A!!!!
S!FM_ALL_WAKE_N!R8E28!2!@baseboard_fab2_lib.baseboard_fab2(sch_1):page142_i31@mstr_discrete.res(chips)!RES_0402-0.0,5%,1/16W,CHIP,G21A!!!F1781!B!!!!
S!USB2_P01_DN!R1M6!1!@baseboard_fab2_lib.baseboard_fab2(sch_1):page176_i31@mstr_discrete.res(chips)!RES_0402-0.0,5%,1/16W,CHIP,G21A!!!F1933!A!!!!
S!USB2_P01_ESD_DN!R1M6!2!@baseboard_fab2_lib.baseboard_fab2(sch_1):page176_i31@mstr_discrete.res(chips)!RES_0402-0.0,5%,1/16W,CHIP,G21A!!!F1933!B!!!!
S!USB2_P01_DP!R1M5!1!@baseboard_fab2_lib.baseboard_fab2(sch_1):page176_i16@mstr_discrete.res(chips)!RES_0402-0.0,5%,1/16W,CHIP,G21A!!!F1934!A!!!!
S!USB2_P01_ESD_DP!R1M5!2!@baseboard_fab2_lib.baseboard_fab2(sch_1):page176_i16@mstr_discrete.res(chips)!RES_0402-0.0,5%,1/16W,CHIP,G21A!!!F1934!B!!!!
S!USB3_P01_RXN!R1L42!1!@baseboard_fab2_lib.baseboard_fab2(sch_1):page176_i58@mstr_discrete.res(chips)!RES_0402-0.0,5%,1/16W,CHIP,G21A!!!F1937!A!!!!
S!USB3_P01_FB_RXN!R1L42!2!@baseboard_fab2_lib.baseboard_fab2(sch_1):page176_i58@mstr_discrete.res(chips)!RES_0402-0.0,5%,1/16W,CHIP,G21A!!!F1937!B!!!!
S!USB3_P01_RXP!R1L40!1!@baseboard_fab2_lib.baseboard_fab2(sch_1):page176_i59@mstr_discrete.res(chips)!RES_0402-0.0,5%,1/16W,CHIP,G21A!!!F1938!A!!!!
S!USB3_P01_FB_RXP!R1L40!2!@baseboard_fab2_lib.baseboard_fab2(sch_1):page176_i59@mstr_discrete.res(chips)!RES_0402-0.0,5%,1/16W,CHIP,G21A!!!F1938!B!!!!
S!USB3_P01_C_TXN!R1M2!1!@baseboard_fab2_lib.baseboard_fab2(sch_1):page176_i60@mstr_discrete.res(chips)!RES_0402-0.0,5%,1/16W,CHIP,G21A!!!F1935!A!!!!
S!USB3_P01_FB_TXN!R1M2!2!@baseboard_fab2_lib.baseboard_fab2(sch_1):page176_i60@mstr_discrete.res(chips)!RES_0402-0.0,5%,1/16W,CHIP,G21A!!!F1935!B!!!!
S!USB3_P01_C_TXP!R1M1!1!@baseboard_fab2_lib.baseboard_fab2(sch_1):page176_i61@mstr_discrete.res(chips)!RES_0402-0.0,5%,1/16W,CHIP,G21A!!!F1936!A!!!!
S!USB3_P01_FB_TXP!R1M1!2!@baseboard_fab2_lib.baseboard_fab2(sch_1):page176_i61@mstr_discrete.res(chips)!RES_0402-0.0,5%,1/16W,CHIP,G21A!!!F1936!B!!!!
S!PWRGD_PVDDQ_DEF!R4A2!1!@baseboard_fab2_lib.baseboard_fab2(sch_1):page222_i38@mstr_discrete.res(chips)!RES_0402-0.0,5%,1/16W,CHIP,G21A!!!F1873!A!!!!
S!FM_PVTT_DEF_EN_R!R4A2!2!@baseboard_fab2_lib.baseboard_fab2(sch_1):page222_i38@mstr_discrete.res(chips)!RES_0402-0.0,5%,1/16W,CHIP,G21A!!!F1873!B!!!!
S!PWRGD_PVDDQ_ABC!R4G23!1!@baseboard_fab2_lib.baseboard_fab2(sch_1):page221_i38@mstr_discrete.res(chips)!RES_0402-0.0,5%,1/16W,CHIP,G21A!!!F1851!A!!!!
S!FM_PVTT_ABC_EN_R!R4G23!2!@baseboard_fab2_lib.baseboard_fab2(sch_1):page221_i38@mstr_discrete.res(chips)!RES_0402-0.0,5%,1/16W,CHIP,G21A!!!F1851!B!!!!
S!PWRGD_PVDDQ_GHJ!R4G16!1!@baseboard_fab2_lib.baseboard_fab2(sch_1):page229_i35@mstr_discrete.res(chips)!RES_0402-0.0,5%,1/16W,CHIP,G21A!!!F1852!A!!!!
S!FM_PVTT_GHJ_EN_R!R4G16!2!@baseboard_fab2_lib.baseboard_fab2(sch_1):page229_i35@mstr_discrete.res(chips)!RES_0402-0.0,5%,1/16W,CHIP,G21A!!!F1852!B!!!!
S!PWRGD_PVDDQ_KLM!R4A3!1!@baseboard_fab2_lib.baseboard_fab2(sch_1):page230_i38@mstr_discrete.res(chips)!RES_0402-0.0,5%,1/16W,CHIP,G21A!!!F1872!A!!!!
S!FM_PVTT_KLM_EN_R!R4A3!2!@baseboard_fab2_lib.baseboard_fab2(sch_1):page230_i38@mstr_discrete.res(chips)!RES_0402-0.0,5%,1/16W,CHIP,G21A!!!F1872!B!!!!
S!XTAL_25MHZ_OUT_R!R9E18!1!@baseboard_fab2_lib.baseboard_fab2(sch_1):page139_i201@mstr_discrete.res(chips)!RES_0402-0.0,5%,1/16W,CHIP,G21A!!!F1756!A!!!!
S!XTAL_25MHZ_OUT!R9E18!2!@baseboard_fab2_lib.baseboard_fab2(sch_1):page139_i201@mstr_discrete.res(chips)!RES_0402-0.0,5%,1/16W,CHIP,G21A!!!F1756!B!!!!
S!RST_CPU0_LVC3_R1_N!R3P34!1!@baseboard_fab2_lib.baseboard_fab2(sch_1):page190_i116@mstr_discrete.res(chips)!RES_0402-0.0,5%,1/16W,CHIP,G21A!!!F1879!A!!!!
S!RST_CPU0_LVC3_N!R3P34!2!@baseboard_fab2_lib.baseboard_fab2(sch_1):page190_i116@mstr_discrete.res(chips)!RES_0402-0.0,5%,1/16W,CHIP,G21A!!!F1879!B!!!!
S!RST_CPU1_LVC3_R1_N!R3P35!1!@baseboard_fab2_lib.baseboard_fab2(sch_1):page190_i117@mstr_discrete.res(chips)!RES_0402-0.0,5%,1/16W,CHIP,G21A!!!F1878!A!!!!
S!RST_CPU1_LVC3_N!R3P35!2!@baseboard_fab2_lib.baseboard_fab2(sch_1):page190_i117@mstr_discrete.res(chips)!RES_0402-0.0,5%,1/16W,CHIP,G21A!!!F1878!B!!!!
S!A_HSC_TIMER!R9P21!1!@baseboard_fab2_lib.baseboard_fab2(sch_1):page200_i71@mstr_discrete.res(chips)!RES_0402-0.0,5%,1/16W,CHIP,G21A!!!F1724!A!!!!
S!A_HSC_TIMER_R!R9P21!2!@baseboard_fab2_lib.baseboard_fab2(sch_1):page200_i71@mstr_discrete.res(chips)!RES_0402-0.0,5%,1/16W,CHIP,G21A!!!F1724!B!!!!
S!P3V3_STBY!R2L14!1!@baseboard_fab2_lib.baseboard_fab2(sch_1):page235_i159@mstr_discrete.res(chips)!RES_0402-0.0,5%,1/16W,CHIP,G21A!!!F1918!A!!!!
S!VR_PVNN_PCH_VDD!R2L14!2!@baseboard_fab2_lib.baseboard_fab2(sch_1):page235_i159@mstr_discrete.res(chips)!RES_0402-0.0,5%,1/16W,CHIP,G21A!!!F1918!B!!!!
S!PWRGD_P3V3!R1L12!1!@baseboard_fab2_lib.baseboard_fab2(sch_1):page175_i63@mstr_discrete.res(chips)!RES_0402-0.0,5%,1/16W,CHIP,G21A!!!F1939!A!!!!
S!PWRGD_P3V3_R!R1L12!2!@baseboard_fab2_lib.baseboard_fab2(sch_1):page175_i63@mstr_discrete.res(chips)!RES_0402-0.0,5%,1/16W,CHIP,G21A!!!F1939!B!!!!
S!FM_M2_DET_LVC3!R2P14!1!@baseboard_fab2_lib.baseboard_fab2(sch_1):page185_i115@mstr_discrete.res(chips)!RES_0402-0.0,5%,1/16W,CHIP,G21A!!!F1788!A!!!!
S!FM_SSATA_PCIE_M2_SEL!R2P14!2!@baseboard_fab2_lib.baseboard_fab2(sch_1):page185_i115@mstr_discrete.res(chips)!RES_0402-0.0,5%,1/16W,CHIP,G21A!!!F1788!B!!!!
S!P3V3_STBY!R3P22!1!@baseboard_fab2_lib.baseboard_fab2(sch_1):page211_i24@mstr_discrete.res(chips)!RES_0402-0.0,5%,1/16W,CHIP,G21A!!!F1881!A!!!!
S!VR_PVCCIO_CPU0_VDD!R3P22!2!@baseboard_fab2_lib.baseboard_fab2(sch_1):page211_i24@mstr_discrete.res(chips)!RES_0402-0.0,5%,1/16W,CHIP,G21A!!!F1881!B!!!!
S!SVID_ALERT_PVCCIO_CPU0!R3P1!1!@baseboard_fab2_lib.baseboard_fab2(sch_1):page211_i61@mstr_discrete.res(chips)!RES_0402-0.0,5%,1/16W,CHIP,G21A!!!F1887!A!!!!
S!SVID_ALERT0_CPU0_R_N!R3P1!2!@baseboard_fab2_lib.baseboard_fab2(sch_1):page211_i61@mstr_discrete.res(chips)!RES_0402-0.0,5%,1/16W,CHIP,G21A!!!F1887!B!!!!
S!SVID_ALERT_PVCCIO_CPU1!R4D56!1!@baseboard_fab2_lib.baseboard_fab2(sch_1):page213_i16@mstr_discrete.res(chips)!RES_0402-0.0,5%,1/16W,CHIP,G21A!!!F1860!A!!!!
S!SVID_ALERT0_CPU1_R_N!R4D56!2!@baseboard_fab2_lib.baseboard_fab2(sch_1):page213_i16@mstr_discrete.res(chips)!RES_0402-0.0,5%,1/16W,CHIP,G21A!!!F1860!B!!!!
S!SVID_DIO0_CPU0_R!R3P11!1!@baseboard_fab2_lib.baseboard_fab2(sch_1):page211_i16@mstr_discrete.res(chips)!RES_0402-0.0,5%,1/16W,CHIP,G21A!!!F1882!A!!!!
S!SVID_VDIO_PVCCIO_CPU0!R3P11!2!@baseboard_fab2_lib.baseboard_fab2(sch_1):page211_i16@mstr_discrete.res(chips)!RES_0402-0.0,5%,1/16W,CHIP,G21A!!!F1882!B!!!!
S!SVID_DIO0_CPU1_R!R4D54!1!@baseboard_fab2_lib.baseboard_fab2(sch_1):page213_i37@mstr_discrete.res(chips)!RES_0402-0.0,5%,1/16W,CHIP,G21A!!!F1861!A!!!!
S!SVID_VDIO_PVCCIO_CPU1!R4D54!2!@baseboard_fab2_lib.baseboard_fab2(sch_1):page213_i37@mstr_discrete.res(chips)!RES_0402-0.0,5%,1/16W,CHIP,G21A!!!F1861!B!!!!
S!P3V3_STBY!R4D47!1!@baseboard_fab2_lib.baseboard_fab2(sch_1):page213_i25@mstr_discrete.res(chips)!RES_0402-0.0,5%,1/16W,CHIP,G21A!!!F1864!A!!!!
S!VR_PVCCIO_CPU1_VDD!R4D47!2!@baseboard_fab2_lib.baseboard_fab2(sch_1):page213_i25@mstr_discrete.res(chips)!RES_0402-0.0,5%,1/16W,CHIP,G21A!!!F1864!B!!!!
S!P3E_PCH_RX_0_DP!R8F18!1!@baseboard_fab2_lib.baseboard_fab2(sch_1):page185_i105@mstr_discrete.res(chips)!RES_0402-0.0,5%,1/16W,CHIP,G21A!!!F1773!A!!!!
S!P3E_PCH_M2_SATA6G_RX_R_DP!R8F18!2!@baseboard_fab2_lib.baseboard_fab2(sch_1):page185_i105@mstr_discrete.res(chips)!RES_0402-0.0,5%,1/16W,CHIP,G21A!!!F1773!B!!!!
S!P3E_PCH_RX_0_DN!R8F21!1!@baseboard_fab2_lib.baseboard_fab2(sch_1):page185_i106@mstr_discrete.res(chips)!RES_0402-0.0,5%,1/16W,CHIP,G21A!!!F1772!A!!!!
S!P3E_PCH_M2_SATA6G_RX_R_DN!R8F21!2!@baseboard_fab2_lib.baseboard_fab2(sch_1):page185_i106@mstr_discrete.res(chips)!RES_0402-0.0,5%,1/16W,CHIP,G21A!!!F1772!B!!!!
S!FM_UART_SWITCH_N!R1L6!1!@baseboard_fab2_lib.baseboard_fab2(sch_1):page168_i6@mstr_discrete.res(chips)!RES_0402-0.0,5%,1/16W,CHIP,G21A!!!F1940!A!!!!
S!FM_DB_UART_SEL0_N!R1L6!2!@baseboard_fab2_lib.baseboard_fab2(sch_1):page168_i6@mstr_discrete.res(chips)!RES_0402-0.0,5%,1/16W,CHIP,G21A!!!F1940!B!!!!
S!SPA_SIN_SW_R!R9A8!1!@baseboard_fab2_lib.baseboard_fab2(sch_1):page155_i53@mstr_discrete.res(chips)!RES_0402-0.0,5%,1/16W,CHIP,G21A!!!F1758!A!!!!
S!SPA_MID_DBG_RX!R9A8!2!@baseboard_fab2_lib.baseboard_fab2(sch_1):page155_i53@mstr_discrete.res(chips)!RES_0402-0.0,5%,1/16W,CHIP,G21A!!!F1758!B!!!!
S!FM_ADR_COMPLETE_DLY!R4T1!1!@baseboard_fab2_lib.baseboard_fab2(sch_1):page89_i2@mstr_discrete.res(chips)!RES_0402-0.0,5%,1/16W,CHIP,G21A!!!F1848!A!!!!
S!FM_ADR_COMPLETE_R!R4T1!2!@baseboard_fab2_lib.baseboard_fab2(sch_1):page89_i2@mstr_discrete.res(chips)!RES_0402-0.0,5%,1/16W,CHIP,G21A!!!F1848!B!!!!
S!VSENSE_P1V05_PCH_STBY_AVSN!R8B12!1!@baseboard_fab2_lib.baseboard_fab2(sch_1):page236_i59@mstr_discrete.res(chips)!RES_0402-0.0,5%,1/16W,CHIP,G21A!!!F1791!A!!!!
S!GND!R8B12!2!@baseboard_fab2_lib.baseboard_fab2(sch_1):page236_i59@mstr_discrete.res(chips)!RES_0402-0.0,5%,1/16W,CHIP,G21A!!!F1791!B!!!!
S!VSENSE_P1V05_PCH_STBY_AVSP!R8B14!1!@baseboard_fab2_lib.baseboard_fab2(sch_1):page236_i56@mstr_discrete.res(chips)!RES_0402-0.0,5%,1/16W,CHIP,G21A!!!F1790!A!!!!
S!P1V05_PCH_STBY!R8B14!2!@baseboard_fab2_lib.baseboard_fab2(sch_1):page236_i56@mstr_discrete.res(chips)!RES_0402-0.0,5%,1/16W,CHIP,G21A!!!F1790!B!!!!
S!VR_P5V_STBY_VSENSE_R!R8E37!1!@baseboard_fab2_lib.baseboard_fab2(sch_1):page241_i78@mstr_discrete.res(chips)!RES_0402-0.0,5%,1/16W,CHIP,G21A!!!F1778!A!!!!
S!P5V_STBY!R8E37!2!@baseboard_fab2_lib.baseboard_fab2(sch_1):page241_i78@mstr_discrete.res(chips)!RES_0402-0.0,5%,1/16W,CHIP,G21A!!!F1778!B!!!!
S!P3V3_STBY!R9U10!1!@baseboard_fab2_lib.baseboard_fab2(sch_1):page223_i30@mstr_discrete.res(chips)!RES_0402-0.0,5%,1/16W,CHIP,G21A!!!F1715!A!!!!
S!VR_PVDDQ_GHJ_VDD!R9U10!2!@baseboard_fab2_lib.baseboard_fab2(sch_1):page223_i30@mstr_discrete.res(chips)!RES_0402-0.0,5%,1/16W,CHIP,G21A!!!F1715!B!!!!
S!VR_PVDDQ_ABC_AIINSEN_R!R4F1!1!@baseboard_fab2_lib.baseboard_fab2(sch_1):page197_i110@mstr_discrete.res(chips)!RES_0402-0.0,5%,1/16W,CHIP,G21A!!!F1855!A!!!!
S!VR_PVDDQ_ABC_AIINSEN!R4F1!2!@baseboard_fab2_lib.baseboard_fab2(sch_1):page197_i110@mstr_discrete.res(chips)!RES_0402-0.0,5%,1/16W,CHIP,G21A!!!F1855!B!!!!
S!VR_PVDDQ_DEF_AIINSEN_R!R4B11!1!@baseboard_fab2_lib.baseboard_fab2(sch_1):page197_i113@mstr_discrete.res(chips)!RES_0402-0.0,5%,1/16W,CHIP,G21A!!!F1869!A!!!!
S!VR_PVDDQ_DEF_AIINSEN!R4B11!2!@baseboard_fab2_lib.baseboard_fab2(sch_1):page197_i113@mstr_discrete.res(chips)!RES_0402-0.0,5%,1/16W,CHIP,G21A!!!F1869!B!!!!
S!VR_PVDDQ_GHJ_AIINSEN_R!R9T4!1!@baseboard_fab2_lib.baseboard_fab2(sch_1):page197_i126@mstr_discrete.res(chips)!RES_0402-0.0,5%,1/16W,CHIP,G21A!!!F1719!A!!!!
S!VR_PVDDQ_GHJ_AIINSEN!R9T4!2!@baseboard_fab2_lib.baseboard_fab2(sch_1):page197_i126@mstr_discrete.res(chips)!RES_0402-0.0,5%,1/16W,CHIP,G21A!!!F1719!B!!!!
S!VR_PVDDQ_KLM_AIINSEN_R!R1B14!1!@baseboard_fab2_lib.baseboard_fab2(sch_1):page197_i137@mstr_discrete.res(chips)!RES_0402-0.0,5%,1/16W,CHIP,G21A!!!F1961!A!!!!
S!VR_PVDDQ_KLM_AIINSEN!R1B14!2!@baseboard_fab2_lib.baseboard_fab2(sch_1):page197_i137@mstr_discrete.res(chips)!RES_0402-0.0,5%,1/16W,CHIP,G21A!!!F1961!B!!!!
S!P3V3!R6U4!1!@baseboard_fab2_lib.baseboard_fab2(sch_1):page221_i28@mstr_discrete.res(chips)!RES_0402-0.0,5%,1/16W,CHIP,G21A!!!F1821!A!!!!
S!VR_PVTT_ABC_BIAS!R6U4!2!@baseboard_fab2_lib.baseboard_fab2(sch_1):page221_i28@mstr_discrete.res(chips)!RES_0402-0.0,5%,1/16W,CHIP,G21A!!!F1821!B!!!!
S!VR_PVTT_ABC_SNS!R5U1!1!@baseboard_fab2_lib.baseboard_fab2(sch_1):page221_i18@mstr_discrete.res(chips)!RES_0402-0.0,5%,1/16W,CHIP,G21A!!!F1844!A!!!!
S!PVTT_ABC!R5U1!2!@baseboard_fab2_lib.baseboard_fab2(sch_1):page221_i18@mstr_discrete.res(chips)!RES_0402-0.0,5%,1/16W,CHIP,G21A!!!F1844!B!!!!
S!NIC_LED_ACT_ANODE_R!R9G4!1!@baseboard_fab2_lib.baseboard_fab2(sch_1):page141_i56@mstr_discrete.res(chips)!RES_0402-0.0,5%,1/16W,CHIP,G21A!!!F1745!A!!!!
S!P3V3_STBY!R9G4!2!@baseboard_fab2_lib.baseboard_fab2(sch_1):page141_i56@mstr_discrete.res(chips)!RES_0402-0.0,5%,1/16W,CHIP,G21A!!!F1745!B!!!!
S!P3V3!R6L11!1!@baseboard_fab2_lib.baseboard_fab2(sch_1):page222_i30@mstr_discrete.res(chips)!RES_0402-0.0,5%,1/16W,CHIP,G21A!!!F1836!A!!!!
S!VR_PVTT_DEF_BIAS!R6L11!2!@baseboard_fab2_lib.baseboard_fab2(sch_1):page222_i30@mstr_discrete.res(chips)!RES_0402-0.0,5%,1/16W,CHIP,G21A!!!F1836!B!!!!
S!VR_PVTT_DEF_SNS!R5L1!1!@baseboard_fab2_lib.baseboard_fab2(sch_1):page222_i15@mstr_discrete.res(chips)!RES_0402-0.0,5%,1/16W,CHIP,G21A!!!F1845!A!!!!
S!PVTT_DEF!R5L1!2!@baseboard_fab2_lib.baseboard_fab2(sch_1):page222_i15@mstr_discrete.res(chips)!RES_0402-0.0,5%,1/16W,CHIP,G21A!!!F1845!B!!!!
S!VR_PVTT_GHJ_SNS!R8U1!1!@baseboard_fab2_lib.baseboard_fab2(sch_1):page229_i18@mstr_discrete.res(chips)!RES_0402-0.0,5%,1/16W,CHIP,G21A!!!F1760!A!!!!
S!PVTT_GHJ!R8U1!2!@baseboard_fab2_lib.baseboard_fab2(sch_1):page229_i18@mstr_discrete.res(chips)!RES_0402-0.0,5%,1/16W,CHIP,G21A!!!F1760!B!!!!
S!VR_PVTT_KLM_SNS!R8L1!1!@baseboard_fab2_lib.baseboard_fab2(sch_1):page230_i13@mstr_discrete.res(chips)!RES_0402-0.0,5%,1/16W,CHIP,G21A!!!F1761!A!!!!
S!PVTT_KLM!R8L1!2!@baseboard_fab2_lib.baseboard_fab2(sch_1):page230_i13@mstr_discrete.res(chips)!RES_0402-0.0,5%,1/16W,CHIP,G21A!!!F1761!B!!!!
S!P3V3!R6U7!1!@baseboard_fab2_lib.baseboard_fab2(sch_1):page229_i32@mstr_discrete.res(chips)!RES_0402-0.0,5%,1/16W,CHIP,G21A!!!F1818!A!!!!
S!VR_PVTT_GHJ_BIAS!R6U7!2!@baseboard_fab2_lib.baseboard_fab2(sch_1):page229_i32@mstr_discrete.res(chips)!RES_0402-0.0,5%,1/16W,CHIP,G21A!!!F1818!B!!!!
S!P3V3!R6L8!1!@baseboard_fab2_lib.baseboard_fab2(sch_1):page230_i30@mstr_discrete.res(chips)!RES_0402-0.0,5%,1/16W,CHIP,G21A!!!F1838!A!!!!
S!VR_PVTT_KLM_BIAS!R6L8!2!@baseboard_fab2_lib.baseboard_fab2(sch_1):page230_i30@mstr_discrete.res(chips)!RES_0402-0.0,5%,1/16W,CHIP,G21A!!!F1838!B!!!!
S!P3V3_STBY!R3M1!1!@baseboard_fab2_lib.baseboard_fab2(sch_1):page218_i34@mstr_discrete.res(chips)!RES_0402-0.0,5%,1/16W,CHIP,G21A!!!F1892!A!!!!
S!VR_PVDDQ_DEF_VDD!R3M1!2!@baseboard_fab2_lib.baseboard_fab2(sch_1):page218_i34@mstr_discrete.res(chips)!RES_0402-0.0,5%,1/16W,CHIP,G21A!!!F1892!B!!!!
S!SVID_ALERT_PVDDQ_DEF!R7A11!1!@baseboard_fab2_lib.baseboard_fab2(sch_1):page218_i15@mstr_discrete.res(chips)!RES_0402-0.0,5%,1/16W,CHIP,G21A!!!F1817!A!!!!
S!SVID_ALERT1_CPU0_R_N!R7A11!2!@baseboard_fab2_lib.baseboard_fab2(sch_1):page218_i15@mstr_discrete.res(chips)!RES_0402-0.0,5%,1/16W,CHIP,G21A!!!F1817!B!!!!
S!SVID_VDIO_PVDDQ_DEF!R7A12!1!@baseboard_fab2_lib.baseboard_fab2(sch_1):page218_i25@mstr_discrete.res(chips)!RES_0402-0.0,5%,1/16W,CHIP,G21A!!!F1816!A!!!!
S!SVID_DIO1_CPU0_R!R7A12!2!@baseboard_fab2_lib.baseboard_fab2(sch_1):page218_i25@mstr_discrete.res(chips)!RES_0402-0.0,5%,1/16W,CHIP,G21A!!!F1816!B!!!!
S!SVID_ALERT_PVDDQ_GHJ!R1G9!1!@baseboard_fab2_lib.baseboard_fab2(sch_1):page223_i16@mstr_discrete.res(chips)!RES_0402-0.0,5%,1/16W,CHIP,G21A!!!F1944!A!!!!
S!SVID_ALERT1_CPU1_R_N!R1G9!2!@baseboard_fab2_lib.baseboard_fab2(sch_1):page223_i16@mstr_discrete.res(chips)!RES_0402-0.0,5%,1/16W,CHIP,G21A!!!F1944!B!!!!
S!SVID_VDIO_PVDDQ_GHJ!R1G10!1!@baseboard_fab2_lib.baseboard_fab2(sch_1):page223_i23@mstr_discrete.res(chips)!RES_0402-0.0,5%,1/16W,CHIP,G21A!!!F1943!A!!!!
S!SVID_DIO1_CPU1_R!R1G10!2!@baseboard_fab2_lib.baseboard_fab2(sch_1):page223_i23@mstr_discrete.res(chips)!RES_0402-0.0,5%,1/16W,CHIP,G21A!!!F1943!B!!!!
S!P3V3_STBY!R9M3!1!@baseboard_fab2_lib.baseboard_fab2(sch_1):page226_i30@mstr_discrete.res(chips)!RES_0402-0.0,5%,1/16W,CHIP,G21A!!!F1736!A!!!!
S!VR_PVDDQ_KLM_VDD!R9M3!2!@baseboard_fab2_lib.baseboard_fab2(sch_1):page226_i30@mstr_discrete.res(chips)!RES_0402-0.0,5%,1/16W,CHIP,G21A!!!F1736!B!!!!
S!SVID_ALERT_PVDDQ_KLM!R1B11!1!@baseboard_fab2_lib.baseboard_fab2(sch_1):page226_i16@mstr_discrete.res(chips)!RES_0402-0.0,5%,1/16W,CHIP,G21A!!!F1962!A!!!!
S!SVID_ALERT1_CPU1_R_N!R1B11!2!@baseboard_fab2_lib.baseboard_fab2(sch_1):page226_i16@mstr_discrete.res(chips)!RES_0402-0.0,5%,1/16W,CHIP,G21A!!!F1962!B!!!!
S!SVID_VDIO_PVDDQ_KLM!R1B10!1!@baseboard_fab2_lib.baseboard_fab2(sch_1):page226_i23@mstr_discrete.res(chips)!RES_0402-0.0,5%,1/16W,CHIP,G21A!!!F1963!A!!!!
S!SVID_DIO1_CPU1_R!R1B10!2!@baseboard_fab2_lib.baseboard_fab2(sch_1):page226_i23@mstr_discrete.res(chips)!RES_0402-0.0,5%,1/16W,CHIP,G21A!!!F1963!B!!!!
S!GND!R4B14!1!@baseboard_fab2_lib.baseboard_fab2(sch_1):page234_i29@mstr_discrete.res(chips)!RES_0402-0.0,5%,1/16W,CHIP,G21A!!!F1834!A!!!!
S!AGND_PVPP_KLM!R4B14!2!@baseboard_fab2_lib.baseboard_fab2(sch_1):page234_i29@mstr_discrete.res(chips)!RES_0402-0.0,5%,1/16W,CHIP,G21A!!!F1834!B!!!!
S!VSENSE_PVCCIN_CPU1_P!R1E6!1!@baseboard_fab2_lib.baseboard_fab2(sch_1):page209_i11@mstr_discrete.res(chips)!RES_0402-0.0,5%,1/16W,CHIP,G21A!!!F1947!A!!!!
S!VSENSE_PVCCIN_CPU1_SKT_VSEN!R1E6!2!@baseboard_fab2_lib.baseboard_fab2(sch_1):page209_i11@mstr_discrete.res(chips)!RES_0402-0.0,5%,1/16W,CHIP,G21A!!!F1947!B!!!!
S!VSENSE_PVCCIN_CPU1_N!R1E7!1!@baseboard_fab2_lib.baseboard_fab2(sch_1):page209_i10@mstr_discrete.res(chips)!RES_0402-0.0,5%,1/16W,CHIP,G21A!!!F1946!A!!!!
S!VSENSE_PVCCIN_CPU1_SKT_VRTN!R1E7!2!@baseboard_fab2_lib.baseboard_fab2(sch_1):page209_i10@mstr_discrete.res(chips)!RES_0402-0.0,5%,1/16W,CHIP,G21A!!!F1946!B!!!!
S!VSENSE_PVCCIO_CPU1_SKT_VRTN!R3D29!1!@baseboard_fab2_lib.baseboard_fab2(sch_1):page214_i99@mstr_discrete.res(chips)!RES_0402-0.0,5%,1/16W,CHIP,G21A!!!F1898!A!!!!
S!VSENSE_PVCCIO_CPU1_AVSN!R3D29!2!@baseboard_fab2_lib.baseboard_fab2(sch_1):page214_i99@mstr_discrete.res(chips)!RES_0402-0.0,5%,1/16W,CHIP,G21A!!!F1898!B!!!!
S!VSENSE_PVCCIO_CPU1_SKT_VSEN!R3D30!1!@baseboard_fab2_lib.baseboard_fab2(sch_1):page214_i104@mstr_discrete.res(chips)!RES_0402-0.0,5%,1/16W,CHIP,G21A!!!F1897!A!!!!
S!VSENSE_PVCCIO_CPU1_AVSP!R3D30!2!@baseboard_fab2_lib.baseboard_fab2(sch_1):page214_i104@mstr_discrete.res(chips)!RES_0402-0.0,5%,1/16W,CHIP,G21A!!!F1897!B!!!!
S!VR_FET_SW_P5V_STBY_PVIN!R7E17!1!@baseboard_fab2_lib.baseboard_fab2(sch_1):page241_i37@mstr_discrete.res(chips)!RES_0402-0.0,5%,1/16W,CHIP,G21A!!!F1805!A!!!!
S!VR_P5V_STBY_VIN!R7E17!2!@baseboard_fab2_lib.baseboard_fab2(sch_1):page241_i37@mstr_discrete.res(chips)!RES_0402-0.0,5%,1/16W,CHIP,G21A!!!F1805!B!!!!
S!GND!R7E13!1!@baseboard_fab2_lib.baseboard_fab2(sch_1):page241_i58@mstr_discrete.res(chips)!RES_0402-0.0,5%,1/16W,CHIP,G21A!!!F1806!A!!!!
S!AGND_P5V_STBY!R7E13!2!@baseboard_fab2_lib.baseboard_fab2(sch_1):page241_i58@mstr_discrete.res(chips)!RES_0402-0.0,5%,1/16W,CHIP,G21A!!!F1806!B!!!!
S!H_CPU0_ERR1_G_N!R2T32!1!@baseboard_fab2_lib.baseboard_fab2(sch_1):page93_i15@mstr_discrete.res(chips)!RES_0402-0.0,5%,1/16W,CHIP,G21A!!!F1907!A!!!!
S!H_CPU_ERR1_GTL_R_N!R2T32!2!@baseboard_fab2_lib.baseboard_fab2(sch_1):page93_i15@mstr_discrete.res(chips)!RES_0402-0.0,5%,1/16W,CHIP,G21A!!!F1907!B!!!!
S!H_CPU0_ERR0_G_N!R2T17!1!@baseboard_fab2_lib.baseboard_fab2(sch_1):page93_i23@mstr_discrete.res(chips)!RES_0402-0.0,5%,1/16W,CHIP,G21A!!!F1910!A!!!!
S!H_CPU_ERR0_GTL_R_N!R2T17!2!@baseboard_fab2_lib.baseboard_fab2(sch_1):page93_i23@mstr_discrete.res(chips)!RES_0402-0.0,5%,1/16W,CHIP,G21A!!!F1910!B!!!!
S!H_CPU1_ERR0_G_N!R2T20!1!@baseboard_fab2_lib.baseboard_fab2(sch_1):page93_i16@mstr_discrete.res(chips)!RES_0402-0.0,5%,1/16W,CHIP,G21A!!!F1909!A!!!!
S!H_CPU_ERR0_GTL_R_N!R2T20!2!@baseboard_fab2_lib.baseboard_fab2(sch_1):page93_i16@mstr_discrete.res(chips)!RES_0402-0.0,5%,1/16W,CHIP,G21A!!!F1909!B!!!!
S!H_CPU1_ERR1_G_N!R2T27!1!@baseboard_fab2_lib.baseboard_fab2(sch_1):page93_i13@mstr_discrete.res(chips)!RES_0402-0.0,5%,1/16W,CHIP,G21A!!!F1908!A!!!!
S!H_CPU_ERR1_GTL_R_N!R2T27!2!@baseboard_fab2_lib.baseboard_fab2(sch_1):page93_i13@mstr_discrete.res(chips)!RES_0402-0.0,5%,1/16W,CHIP,G21A!!!F1908!B!!!!
S!XTAL_25MHZ_IN!R9E20!1!@baseboard_fab2_lib.baseboard_fab2(sch_1):page139_i110@mstr_discrete.res(chips)!RES_0402-0.0,5%,1/16W,CHIP,G21A!!!F1755!A!!!!
S!XTAL_25MHZ_IN_R!R9E20!2!@baseboard_fab2_lib.baseboard_fab2(sch_1):page139_i110@mstr_discrete.res(chips)!RES_0402-0.0,5%,1/16W,CHIP,G21A!!!F1755!B!!!!
S!RST_PLTRST_N!R1R1!1!@baseboard_fab2_lib.baseboard_fab2(sch_1):page139_i195@mstr_discrete.res(chips)!RES_0402-0.0,5%,1/16W,CHIP,G21A!!!F1926!A!!!!
S!RST_PLTRST_SPRV_R_N!R1R1!2!@baseboard_fab2_lib.baseboard_fab2(sch_1):page139_i195@mstr_discrete.res(chips)!RES_0402-0.0,5%,1/16W,CHIP,G21A!!!F1926!B!!!!
S!H_CPU0_CATERR_G_N!R3P59!1!@baseboard_fab2_lib.baseboard_fab2(sch_1):page92_i97@mstr_discrete.res(chips)!RES_0402-0.0,5%,1/16W,CHIP,G21A!!!F1903!A!!!!
S!H_CPU_CATERR_G_N!R3P59!2!@baseboard_fab2_lib.baseboard_fab2(sch_1):page92_i97@mstr_discrete.res(chips)!RES_0402-0.0,5%,1/16W,CHIP,G21A!!!F1903!B!!!!
S!H_CPU1_CATERR_G_N!R3P58!1!@baseboard_fab2_lib.baseboard_fab2(sch_1):page92_i98@mstr_discrete.res(chips)!RES_0402-0.0,5%,1/16W,CHIP,G21A!!!F1904!A!!!!
S!H_CPU_CATERR_G_N!R3P58!2!@baseboard_fab2_lib.baseboard_fab2(sch_1):page92_i98@mstr_discrete.res(chips)!RES_0402-0.0,5%,1/16W,CHIP,G21A!!!F1904!B!!!!
S!VSENSE_PVCCIO_CPU0_SKT_VSEN!R3P9!1!@baseboard_fab2_lib.baseboard_fab2(sch_1):page212_i71@mstr_discrete.res(chips)!RES_0402-0.0,5%,1/16W,CHIP,G21A!!!F1884!A!!!!
S!VSENSE_PVCCIO_CPU0_AVSP!R3P9!2!@baseboard_fab2_lib.baseboard_fab2(sch_1):page212_i71@mstr_discrete.res(chips)!RES_0402-0.0,5%,1/16W,CHIP,G21A!!!F1884!B!!!!
S!VSENSE_PVCCIO_CPU0_SKT_VRTN!R3P10!1!@baseboard_fab2_lib.baseboard_fab2(sch_1):page212_i66@mstr_discrete.res(chips)!RES_0402-0.0,5%,1/16W,CHIP,G21A!!!F1883!A!!!!
S!VSENSE_PVCCIO_CPU0_AVSN!R3P10!2!@baseboard_fab2_lib.baseboard_fab2(sch_1):page212_i66@mstr_discrete.res(chips)!RES_0402-0.0,5%,1/16W,CHIP,G21A!!!F1883!B!!!!
S!P3V3_STBY!R3T13!1!@baseboard_fab2_lib.baseboard_fab2(sch_1):page215_i313@mstr_discrete.res(chips)!RES_0402-0.0,5%,1/16W,CHIP,G21A!!!F1875!A!!!!
S!VR_PVDDQ_ABC_VDD!R3T13!2!@baseboard_fab2_lib.baseboard_fab2(sch_1):page215_i313@mstr_discrete.res(chips)!RES_0402-0.0,5%,1/16W,CHIP,G21A!!!F1875!B!!!!
S!SVID_ALERT_PVDDQ_ABC!R7G4!1!@baseboard_fab2_lib.baseboard_fab2(sch_1):page215_i302@mstr_discrete.res(chips)!RES_0402-0.0,5%,1/16W,CHIP,G21A!!!F1799!A!!!!
S!SVID_ALERT1_CPU0_R_N!R7G4!2!@baseboard_fab2_lib.baseboard_fab2(sch_1):page215_i302@mstr_discrete.res(chips)!RES_0402-0.0,5%,1/16W,CHIP,G21A!!!F1799!B!!!!
S!VSENSE_PVCCIN_CPU0_P!R4E16!1!@baseboard_fab2_lib.baseboard_fab2(sch_1):page204_i61@mstr_discrete.res(chips)!RES_0402-0.0,5%,1/16W,CHIP,G21A!!!F1857!A!!!!
S!VSENSE_PVCCIN_CPU0_SKT_VSEN!R4E16!2!@baseboard_fab2_lib.baseboard_fab2(sch_1):page204_i61@mstr_discrete.res(chips)!RES_0402-0.0,5%,1/16W,CHIP,G21A!!!F1857!B!!!!
S!VSENSE_PVCCIN_CPU0_N!R4E17!1!@baseboard_fab2_lib.baseboard_fab2(sch_1):page204_i62@mstr_discrete.res(chips)!RES_0402-0.0,5%,1/16W,CHIP,G21A!!!F1856!A!!!!
S!VSENSE_PVCCIN_CPU0_SKT_VRTN!R4E17!2!@baseboard_fab2_lib.baseboard_fab2(sch_1):page204_i62@mstr_discrete.res(chips)!RES_0402-0.0,5%,1/16W,CHIP,G21A!!!F1856!B!!!!
S!VSENSE_PVDDQ_ABC_N!R4U5!1!@baseboard_fab2_lib.baseboard_fab2(sch_1):page217_i67@mstr_discrete.res(chips)!RES_0402-0.0,5%,1/16W,CHIP,G21A!!!F1847!A!!!!
S!GND!R4U5!2!@baseboard_fab2_lib.baseboard_fab2(sch_1):page217_i67@mstr_discrete.res(chips)!RES_0402-0.0,5%,1/16W,CHIP,G21A!!!F1847!B!!!!
S!VSENSE_PVDDQ_ABC_P!R4U7!1!@baseboard_fab2_lib.baseboard_fab2(sch_1):page217_i71@mstr_discrete.res(chips)!RES_0402-0.0,5%,1/16W,CHIP,G21A!!!F1846!A!!!!
S!PVDDQ_ABC!R4U7!2!@baseboard_fab2_lib.baseboard_fab2(sch_1):page217_i71@mstr_discrete.res(chips)!RES_0402-0.0,5%,1/16W,CHIP,G21A!!!F1846!B!!!!
S!VSENSE_PVDDQ_GHJ_N!R7U3!1!@baseboard_fab2_lib.baseboard_fab2(sch_1):page225_i67@mstr_discrete.res(chips)!RES_0402-0.0,5%,1/16W,CHIP,G21A!!!F1792!A!!!!
S!GND!R7U3!2!@baseboard_fab2_lib.baseboard_fab2(sch_1):page225_i67@mstr_discrete.res(chips)!RES_0402-0.0,5%,1/16W,CHIP,G21A!!!F1792!B!!!!
S!VSENSE_PVDDQ_GHJ_P!R7U1!1!@baseboard_fab2_lib.baseboard_fab2(sch_1):page225_i71@mstr_discrete.res(chips)!RES_0402-0.0,5%,1/16W,CHIP,G21A!!!F1793!A!!!!
S!PVDDQ_GHJ!R7U1!2!@baseboard_fab2_lib.baseboard_fab2(sch_1):page225_i71@mstr_discrete.res(chips)!RES_0402-0.0,5%,1/16W,CHIP,G21A!!!F1793!B!!!!
S!VSENSE_PVDDQ_KLM_N!R7L1!1!@baseboard_fab2_lib.baseboard_fab2(sch_1):page228_i67@mstr_discrete.res(chips)!RES_0402-0.0,5%,1/16W,CHIP,G21A!!!F1795!A!!!!
S!GND!R7L1!2!@baseboard_fab2_lib.baseboard_fab2(sch_1):page228_i67@mstr_discrete.res(chips)!RES_0402-0.0,5%,1/16W,CHIP,G21A!!!F1795!B!!!!
S!VSENSE_PVDDQ_KLM_P!R7L3!1!@baseboard_fab2_lib.baseboard_fab2(sch_1):page228_i71@mstr_discrete.res(chips)!RES_0402-0.0,5%,1/16W,CHIP,G21A!!!F1794!A!!!!
S!PVDDQ_KLM!R7L3!2!@baseboard_fab2_lib.baseboard_fab2(sch_1):page228_i71@mstr_discrete.res(chips)!RES_0402-0.0,5%,1/16W,CHIP,G21A!!!F1794!B!!!!
S!VSENSE_PVDDQ_DEF_N!R4L1!1!@baseboard_fab2_lib.baseboard_fab2(sch_1):page220_i67@mstr_discrete.res(chips)!RES_0402-0.0,5%,1/16W,CHIP,G21A!!!F1850!A!!!!
S!GND!R4L1!2!@baseboard_fab2_lib.baseboard_fab2(sch_1):page220_i67@mstr_discrete.res(chips)!RES_0402-0.0,5%,1/16W,CHIP,G21A!!!F1850!B!!!!
S!VSENSE_PVDDQ_DEF_P!R4L3!1!@baseboard_fab2_lib.baseboard_fab2(sch_1):page220_i71@mstr_discrete.res(chips)!RES_0402-0.0,5%,1/16W,CHIP,G21A!!!F1849!A!!!!
S!PVDDQ_DEF!R4L3!2!@baseboard_fab2_lib.baseboard_fab2(sch_1):page220_i71@mstr_discrete.res(chips)!RES_0402-0.0,5%,1/16W,CHIP,G21A!!!F1849!B!!!!
S!SVID_DIO1_CPU0!R6B4!1!@baseboard_fab2_lib.baseboard_fab2(sch_1):page21_i154@mstr_discrete.res(chips)!RES_0402-0.0,5%,1/16W,CHIP,G21A!!!F1843!A!!!!
S!SVID_DIO1_CPU0_R!R6B4!2!@baseboard_fab2_lib.baseboard_fab2(sch_1):page21_i154@mstr_discrete.res(chips)!RES_0402-0.0,5%,1/16W,CHIP,G21A!!!F1843!B!!!!
S!SVID_CLK1_CPU0!R6B5!1!@baseboard_fab2_lib.baseboard_fab2(sch_1):page21_i153@mstr_discrete.res(chips)!RES_0402-0.0,5%,1/16W,CHIP,G21A!!!F1842!A!!!!
S!SVID_CLK1_CPU0_R!R6B5!2!@baseboard_fab2_lib.baseboard_fab2(sch_1):page21_i153@mstr_discrete.res(chips)!RES_0402-0.0,5%,1/16W,CHIP,G21A!!!F1842!B!!!!
S!SVID_DIO0_CPU0!R6N11!1!@baseboard_fab2_lib.baseboard_fab2(sch_1):page21_i151@mstr_discrete.res(chips)!RES_0402-0.0,5%,1/16W,CHIP,G21A!!!F1833!A!!!!
S!SVID_DIO0_CPU0_R!R6N11!2!@baseboard_fab2_lib.baseboard_fab2(sch_1):page21_i151@mstr_discrete.res(chips)!RES_0402-0.0,5%,1/16W,CHIP,G21A!!!F1833!B!!!!
S!SVID_CLK0_CPU0!R6N12!1!@baseboard_fab2_lib.baseboard_fab2(sch_1):page21_i150@mstr_discrete.res(chips)!RES_0402-0.0,5%,1/16W,CHIP,G21A!!!F1832!A!!!!
S!SVID_CLK0_CPU0_R!R6N12!2!@baseboard_fab2_lib.baseboard_fab2(sch_1):page21_i150@mstr_discrete.res(chips)!RES_0402-0.0,5%,1/16W,CHIP,G21A!!!F1832!B!!!!
S!SVID_CLK1_CPU1!R1C3!1!@baseboard_fab2_lib.baseboard_fab2(sch_1):page55_i25@mstr_discrete.res(chips)!RES_0402-0.0,5%,1/16W,CHIP,G21A!!!F1959!A!!!!
S!SVID_CLK1_CPU1_R!R1C3!2!@baseboard_fab2_lib.baseboard_fab2(sch_1):page55_i25@mstr_discrete.res(chips)!RES_0402-0.0,5%,1/16W,CHIP,G21A!!!F1959!B!!!!
S!SMB_BMC_PMBUS_STBY_LVC3_SCL!R1D24!1!@baseboard_fab2_lib.baseboard_fab2(sch_1):page199_i27@mstr_discrete.res(chips)!RES_0402-0.0,5%,1/16W,CHIP,G21A!!!F1951!A!!!!
S!SMB_3V3SB_HSC_SCL_R!R1D24!2!@baseboard_fab2_lib.baseboard_fab2(sch_1):page199_i27@mstr_discrete.res(chips)!RES_0402-0.0,5%,1/16W,CHIP,G21A!!!F1951!B!!!!
S!SMB_BMC_PMBUS_STBY_LVC3_SDA!R1D25!1!@baseboard_fab2_lib.baseboard_fab2(sch_1):page199_i28@mstr_discrete.res(chips)!RES_0402-0.0,5%,1/16W,CHIP,G21A!!!F1950!A!!!!
S!SMB_3V3SB_HSC_SDA_R!R1D25!2!@baseboard_fab2_lib.baseboard_fab2(sch_1):page199_i28@mstr_discrete.res(chips)!RES_0402-0.0,5%,1/16W,CHIP,G21A!!!F1950!B!!!!
S!FM_P12V_HSC_ADR2!R9P16!1!@baseboard_fab2_lib.baseboard_fab2(sch_1):page199_i36@mstr_discrete.res(chips)!RES_0402-0.0,5%,1/16W,CHIP,G21A!!!F1725!A!!!!
S!AGND_HSC!R9P16!2!@baseboard_fab2_lib.baseboard_fab2(sch_1):page199_i36@mstr_discrete.res(chips)!RES_0402-0.0,5%,1/16W,CHIP,G21A!!!F1725!B!!!!
S!P3V3_STBY!R4D26!1!@baseboard_fab2_lib.baseboard_fab2(sch_1):page201_i40@mstr_discrete.res(chips)!RES_0402-0.0,5%,1/16W,CHIP,G21A!!!F1866!A!!!!
S!VR_PVCCIN_CPU0_VDD!R4D26!2!@baseboard_fab2_lib.baseboard_fab2(sch_1):page201_i40@mstr_discrete.res(chips)!RES_0402-0.0,5%,1/16W,CHIP,G21A!!!F1866!B!!!!
S!SVID_VDIO_PVCCIN_CPU0!R4D66!1!@baseboard_fab2_lib.baseboard_fab2(sch_1):page201_i98@mstr_discrete.res(chips)!RES_0402-0.0,5%,1/16W,CHIP,G21A!!!F1859!A!!!!
S!SVID_DIO0_CPU0_R!R4D66!2!@baseboard_fab2_lib.baseboard_fab2(sch_1):page201_i98@mstr_discrete.res(chips)!RES_0402-0.0,5%,1/16W,CHIP,G21A!!!F1859!B!!!!
S!SVID_VALERT_VCCIN_CPU0!R4D67!1!@baseboard_fab2_lib.baseboard_fab2(sch_1):page201_i26@mstr_discrete.res(chips)!RES_0402-0.0,5%,1/16W,CHIP,G21A!!!F1858!A!!!!
S!SVID_ALERT0_CPU0_R_N!R4D67!2!@baseboard_fab2_lib.baseboard_fab2(sch_1):page201_i26@mstr_discrete.res(chips)!RES_0402-0.0,5%,1/16W,CHIP,G21A!!!F1858!B!!!!
S!SMB_VR_SDA_R!R4D50!1!@baseboard_fab2_lib.baseboard_fab2(sch_1):page201_i28@mstr_discrete.res(chips)!RES_0402-0.0,5%,1/16W,CHIP,G21A!!!F1863!A!!!!
S!SMB_VR_STBY_LVC3_SDA!R4D50!2!@baseboard_fab2_lib.baseboard_fab2(sch_1):page201_i28@mstr_discrete.res(chips)!RES_0402-0.0,5%,1/16W,CHIP,G21A!!!F1863!B!!!!
S!SMB_VR_SCL_R!R4D53!1!@baseboard_fab2_lib.baseboard_fab2(sch_1):page201_i31@mstr_discrete.res(chips)!RES_0402-0.0,5%,1/16W,CHIP,G21A!!!F1862!A!!!!
S!SMB_VR_STBY_LVC3_SCL!R4D53!2!@baseboard_fab2_lib.baseboard_fab2(sch_1):page201_i31@mstr_discrete.res(chips)!RES_0402-0.0,5%,1/16W,CHIP,G21A!!!F1862!B!!!!
S!P3V3_STBY!R1C14!1!@baseboard_fab2_lib.baseboard_fab2(sch_1):page206_i46@mstr_discrete.res(chips)!RES_0402-0.0,5%,1/16W,CHIP,G21A!!!F1956!A!!!!
S!VR_PVCCIN_CPU1_VDD!R1C14!2!@baseboard_fab2_lib.baseboard_fab2(sch_1):page206_i46@mstr_discrete.res(chips)!RES_0402-0.0,5%,1/16W,CHIP,G21A!!!F1956!B!!!!
S!SVID_VDIO_PVCCIN_CPU1!R1D2!1!@baseboard_fab2_lib.baseboard_fab2(sch_1):page206_i38@mstr_discrete.res(chips)!RES_0402-0.0,5%,1/16W,CHIP,G21A!!!F1953!A!!!!
S!SVID_DIO0_CPU1_R!R1D2!2!@baseboard_fab2_lib.baseboard_fab2(sch_1):page206_i38@mstr_discrete.res(chips)!RES_0402-0.0,5%,1/16W,CHIP,G21A!!!F1953!B!!!!
S!SMB_VR_SDA_R1!R1C23!1!@baseboard_fab2_lib.baseboard_fab2(sch_1):page206_i27@mstr_discrete.res(chips)!RES_0402-0.0,5%,1/16W,CHIP,G21A!!!F1955!A!!!!
S!SMB_VR_STBY_LVC3_SDA!R1C23!2!@baseboard_fab2_lib.baseboard_fab2(sch_1):page206_i27@mstr_discrete.res(chips)!RES_0402-0.0,5%,1/16W,CHIP,G21A!!!F1955!B!!!!
S!SVID_VALERT_VCCIN_CPU1!R1D3!1!@baseboard_fab2_lib.baseboard_fab2(sch_1):page206_i37@mstr_discrete.res(chips)!RES_0402-0.0,5%,1/16W,CHIP,G21A!!!F1952!A!!!!
S!SVID_ALERT0_CPU1_R_N!R1D3!2!@baseboard_fab2_lib.baseboard_fab2(sch_1):page206_i37@mstr_discrete.res(chips)!RES_0402-0.0,5%,1/16W,CHIP,G21A!!!F1952!B!!!!
S!SMB_VR_SCL_R1!R1C25!1!@baseboard_fab2_lib.baseboard_fab2(sch_1):page206_i28@mstr_discrete.res(chips)!RES_0402-0.0,5%,1/16W,CHIP,G21A!!!F1954!A!!!!
S!SMB_VR_STBY_LVC3_SCL!R1C25!2!@baseboard_fab2_lib.baseboard_fab2(sch_1):page206_i28@mstr_discrete.res(chips)!RES_0402-0.0,5%,1/16W,CHIP,G21A!!!F1954!B!!!!
S!VSENSE_PVSA_CPU1_P!R1C7!1!@baseboard_fab2_lib.baseboard_fab2(sch_1):page210_i31@mstr_discrete.res(chips)!RES_0402-0.0,5%,1/16W,CHIP,G21A!!!F1957!A!!!!
S!VSENSE_PVSA_CPU1_SKT_VSEN!R1C7!2!@baseboard_fab2_lib.baseboard_fab2(sch_1):page210_i31@mstr_discrete.res(chips)!RES_0402-0.0,5%,1/16W,CHIP,G21A!!!F1957!B!!!!
S!VSENSE_PVSA_CPU1_N!R1C5!1!@baseboard_fab2_lib.baseboard_fab2(sch_1):page210_i32@mstr_discrete.res(chips)!RES_0402-0.0,5%,1/16W,CHIP,G21A!!!F1958!A!!!!
S!VSENSE_PVSA_CPU1_SKT_VRTN!R1C5!2!@baseboard_fab2_lib.baseboard_fab2(sch_1):page210_i32@mstr_discrete.res(chips)!RES_0402-0.0,5%,1/16W,CHIP,G21A!!!F1958!B!!!!
S!VSENSE_PVSA_CPU0_P!R4C4!1!@baseboard_fab2_lib.baseboard_fab2(sch_1):page205_i26@mstr_discrete.res(chips)!RES_0402-0.0,5%,1/16W,CHIP,G21A!!!F1867!A!!!!
S!VSENSE_PVSA_CPU0_SKT_VSEN!R4C4!2!@baseboard_fab2_lib.baseboard_fab2(sch_1):page205_i26@mstr_discrete.res(chips)!RES_0402-0.0,5%,1/16W,CHIP,G21A!!!F1867!B!!!!
S!VSENSE_PVSA_CPU0_N!R4C2!1!@baseboard_fab2_lib.baseboard_fab2(sch_1):page205_i30@mstr_discrete.res(chips)!RES_0402-0.0,5%,1/16W,CHIP,G21A!!!F1868!A!!!!
S!VSENSE_PVSA_CPU0_SKT_VRTN!R4C2!2!@baseboard_fab2_lib.baseboard_fab2(sch_1):page205_i30@mstr_discrete.res(chips)!RES_0402-0.0,5%,1/16W,CHIP,G21A!!!F1868!B!!!!
S!SVID_DIO1_CPU1!R1C2!1!@baseboard_fab2_lib.baseboard_fab2(sch_1):page55_i24@mstr_discrete.res(chips)!RES_0402-0.0,5%,1/16W,CHIP,G21A!!!F1960!A!!!!
S!SVID_DIO1_CPU1_R!R1C2!2!@baseboard_fab2_lib.baseboard_fab2(sch_1):page55_i24@mstr_discrete.res(chips)!RES_0402-0.0,5%,1/16W,CHIP,G21A!!!F1960!B!!!!
S!SVID_DIO0_CPU1!R3B3!1!@baseboard_fab2_lib.baseboard_fab2(sch_1):page55_i29@mstr_discrete.res(chips)!RES_0402-0.0,5%,1/16W,CHIP,G21A!!!F1901!A!!!!
S!SVID_DIO0_CPU1_R!R3B3!2!@baseboard_fab2_lib.baseboard_fab2(sch_1):page55_i29@mstr_discrete.res(chips)!RES_0402-0.0,5%,1/16W,CHIP,G21A!!!F1901!B!!!!
S!SVID_CLK0_CPU1!R3B5!1!@baseboard_fab2_lib.baseboard_fab2(sch_1):page55_i28@mstr_discrete.res(chips)!RES_0402-0.0,5%,1/16W,CHIP,G21A!!!F1900!A!!!!
S!SVID_CLK0_CPU1_R!R3B5!2!@baseboard_fab2_lib.baseboard_fab2(sch_1):page55_i28@mstr_discrete.res(chips)!RES_0402-0.0,5%,1/16W,CHIP,G21A!!!F1900!B!!!!
S!H_CPU0_FAST_WAKE_N!R3D18!1!@baseboard_fab2_lib.baseboard_fab2(sch_1):page97_i33@mstr_discrete.res(chips)!RES_0402-0.0,5%,1/16W,CHIP,G21A!!!F1899!A!!!!
S!H_CPU1_FAST_WAKE_N!R3D18!2!@baseboard_fab2_lib.baseboard_fab2(sch_1):page97_i33@mstr_discrete.res(chips)!RES_0402-0.0,5%,1/16W,CHIP,G21A!!!F1899!B!!!!
S!A_HSC_MOP!R1D44!1!@baseboard_fab2_lib.baseboard_fab2(sch_1):page200_i44@mstr_discrete.res(chips)!RES_0402-0.0,5%,1/16W,CHIP,G21A!!!F1949!A!!!!
S!A_HSC_HSP!R1D44!2!@baseboard_fab2_lib.baseboard_fab2(sch_1):page200_i44@mstr_discrete.res(chips)!RES_0402-0.0,5%,1/16W,CHIP,G21A!!!F1949!B!!!!
S!A_HSC_MON!R1D45!1!@baseboard_fab2_lib.baseboard_fab2(sch_1):page200_i43@mstr_discrete.res(chips)!RES_0402-0.0,5%,1/16W,CHIP,G21A!!!F1948!A!!!!
S!A_HSC_HSN!R1D45!2!@baseboard_fab2_lib.baseboard_fab2(sch_1):page200_i43@mstr_discrete.res(chips)!RES_0402-0.0,5%,1/16W,CHIP,G21A!!!F1948!B!!!!
S!H_CPU0_MSMI_G_N!R7D27!1!@baseboard_fab2_lib.baseboard_fab2(sch_1):page92_i68@mstr_discrete.res(chips)!RES_0402-0.0,5%,1/16W,CHIP,G21A!!!F1809!A!!!!
S!H_CPU_MSMI_G_N!R7D27!2!@baseboard_fab2_lib.baseboard_fab2(sch_1):page92_i68@mstr_discrete.res(chips)!RES_0402-0.0,5%,1/16W,CHIP,G21A!!!F1809!B!!!!
S!H_CPU1_MSMI_G_N!R7D28!1!@baseboard_fab2_lib.baseboard_fab2(sch_1):page92_i67@mstr_discrete.res(chips)!RES_0402-0.0,5%,1/16W,CHIP,G21A!!!F1808!A!!!!
S!H_CPU_MSMI_G_N!R7D28!2!@baseboard_fab2_lib.baseboard_fab2(sch_1):page92_i67@mstr_discrete.res(chips)!RES_0402-0.0,5%,1/16W,CHIP,G21A!!!F1808!B!!!!
S!H_CPU0_ERR2_G_N!R2T40!1!@baseboard_fab2_lib.baseboard_fab2(sch_1):page92_i93@mstr_discrete.res(chips)!RES_0402-0.0,5%,1/16W,CHIP,G21A!!!F1906!A!!!!
S!H_CPU_ERR2_G_R_N!R2T40!2!@baseboard_fab2_lib.baseboard_fab2(sch_1):page92_i93@mstr_discrete.res(chips)!RES_0402-0.0,5%,1/16W,CHIP,G21A!!!F1906!B!!!!
S!H_CPU1_ERR2_G_N!R2T44!1!@baseboard_fab2_lib.baseboard_fab2(sch_1):page92_i92@mstr_discrete.res(chips)!RES_0402-0.0,5%,1/16W,CHIP,G21A!!!F1905!A!!!!
S!H_CPU_ERR2_G_R_N!R2T44!2!@baseboard_fab2_lib.baseboard_fab2(sch_1):page92_i92@mstr_discrete.res(chips)!RES_0402-0.0,5%,1/16W,CHIP,G21A!!!F1905!B!!!!
S!SVID_VDIO_PVDDQ_ABC!R7G2!1!@baseboard_fab2_lib.baseboard_fab2(sch_1):page215_i307@mstr_discrete.res(chips)!RES_0402-0.0,5%,1/16W,CHIP,G21A!!!F1800!A!!!!
S!SVID_DIO1_CPU0_R!R7G2!2!@baseboard_fab2_lib.baseboard_fab2(sch_1):page215_i307@mstr_discrete.res(chips)!RES_0402-0.0,5%,1/16W,CHIP,G21A!!!F1800!B!!!!
S!RST_PLTRST_BUF_N!R9F7!1!@baseboard_fab2_lib.baseboard_fab2(sch_1):page144_i405@mstr_discrete.res(chips)!RES_0402-0.0,5%,1/16W,CHIP,G21A!!!F1754!A!!!!
S!RST_BMC_LVC3_N!R9F7!2!@baseboard_fab2_lib.baseboard_fab2(sch_1):page144_i405@mstr_discrete.res(chips)!RES_0402-0.0,5%,1/16W,CHIP,G21A!!!F1754!B!!!!
S!FM_SLT_CFG2_R!R2U50!1!@baseboard_fab2_lib.baseboard_fab2(sch_1):page119_i215@mstr_discrete.res(chips)!RES_0402-0.0,5%,1/16W,EMPTY,G2A!!!F1595!A!!!!
S!FM_PWRBRK_SLOT_N!R2U50!2!@baseboard_fab2_lib.baseboard_fab2(sch_1):page119_i215@mstr_discrete.res(chips)!RES_0402-0.0,5%,1/16W,EMPTY,G2A!!!F1595!B!!!!
S!PECI_BMC!R7C18!1!@baseboard_fab2_lib.baseboard_fab2(sch_1):page166_i11@mstr_discrete.res(chips)!RES_0402-0.0,5%,1/16W,EMPTY,G2A!!!F1648!A!!!!
S!PECI_CPU_G!R7C18!2!@baseboard_fab2_lib.baseboard_fab2(sch_1):page166_i11@mstr_discrete.res(chips)!RES_0402-0.0,5%,1/16W,EMPTY,G2A!!!F1648!B!!!!
S!FM_CPU_ERR0_LVT3_N!R8F37!1!@baseboard_fab2_lib.baseboard_fab2(sch_1):page93_i131@mstr_discrete.res(chips)!RES_0402-0.0,5%,1/16W,EMPTY,G2A!!!F1603!A!!!!
S!FM_CPU_ERR0_PCH_N!R8F37!2!@baseboard_fab2_lib.baseboard_fab2(sch_1):page93_i131@mstr_discrete.res(chips)!RES_0402-0.0,5%,1/16W,EMPTY,G2A!!!F1603!B!!!!
S!FM_CPU_ERR1_LVT3_N!R2T63!1!@baseboard_fab2_lib.baseboard_fab2(sch_1):page93_i133@mstr_discrete.res(chips)!RES_0402-0.0,5%,1/16W,EMPTY,G2A!!!F1602!A!!!!
S!FM_CPU_ERR1_PCH_N!R2T63!2!@baseboard_fab2_lib.baseboard_fab2(sch_1):page93_i133@mstr_discrete.res(chips)!RES_0402-0.0,5%,1/16W,EMPTY,G2A!!!F1602!B!!!!
S!FM_CPU0_PROCHOT_LVT3_N!R1T35!1!@baseboard_fab2_lib.baseboard_fab2(sch_1):page93_i135@mstr_discrete.res(chips)!RES_0402-0.0,5%,1/16W,EMPTY,G2A!!!F1601!A!!!!
S!FM_CPU0_PROCHOT_PCH_N!R1T35!2!@baseboard_fab2_lib.baseboard_fab2(sch_1):page93_i135@mstr_discrete.res(chips)!RES_0402-0.0,5%,1/16W,EMPTY,G2A!!!F1601!B!!!!
S!FM_CPU1_PROCHOT_LVT3_N!R1T38!1!@baseboard_fab2_lib.baseboard_fab2(sch_1):page93_i137@mstr_discrete.res(chips)!RES_0402-0.0,5%,1/16W,EMPTY,G2A!!!F1600!A!!!!
S!FM_CPU1_PROCHOT_PCH_N!R1T38!2!@baseboard_fab2_lib.baseboard_fab2(sch_1):page93_i137@mstr_discrete.res(chips)!RES_0402-0.0,5%,1/16W,EMPTY,G2A!!!F1600!B!!!!
S!H_CPU0_MEMABC_MEMHOT_LVT3_N!R3N30!1!@baseboard_fab2_lib.baseboard_fab2(sch_1):page152_i95@mstr_discrete.res(chips)!RES_0402-0.0,5%,1/16W,EMPTY,G2A!!!F1599!A!!!!
S!H_CPU0_MEMABC_MEMHOT_PCH_N!R3N30!2!@baseboard_fab2_lib.baseboard_fab2(sch_1):page152_i95@mstr_discrete.res(chips)!RES_0402-0.0,5%,1/16W,EMPTY,G2A!!!F1599!B!!!!
S!H_CPU0_MEMDEF_MEMHOT_LVT3_N!R9G30!1!@baseboard_fab2_lib.baseboard_fab2(sch_1):page152_i98@mstr_discrete.res(chips)!RES_0402-0.0,5%,1/16W,EMPTY,G2A!!!F1598!A!!!!
S!H_CPU0_MEMDEF_MEMHOT_PCH_N!R9G30!2!@baseboard_fab2_lib.baseboard_fab2(sch_1):page152_i98@mstr_discrete.res(chips)!RES_0402-0.0,5%,1/16W,EMPTY,G2A!!!F1598!B!!!!
S!H_CPU1_MEMGHJ_MEMHOT_LVT3_N!R7D35!1!@baseboard_fab2_lib.baseboard_fab2(sch_1):page152_i100@mstr_discrete.res(chips)!RES_0402-0.0,5%,1/16W,EMPTY,G2A!!!F1597!A!!!!
S!H_CPU1_MEMGHJ_MEMHOT_PCH_N!R7D35!2!@baseboard_fab2_lib.baseboard_fab2(sch_1):page152_i100@mstr_discrete.res(chips)!RES_0402-0.0,5%,1/16W,EMPTY,G2A!!!F1597!B!!!!
S!H_CPU1_MEMKLM_MEMHOT_LVT3_N!R2U45!1!@baseboard_fab2_lib.baseboard_fab2(sch_1):page152_i102@mstr_discrete.res(chips)!RES_0402-0.0,5%,1/16W,EMPTY,G2A!!!F1596!A!!!!
S!H_CPU1_MEMKLM_MEMHOT_PCH_N!R2U45!2!@baseboard_fab2_lib.baseboard_fab2(sch_1):page152_i102@mstr_discrete.res(chips)!RES_0402-0.0,5%,1/16W,EMPTY,G2A!!!F1596!B!!!!
S!P3E_CPU0_PE1_SS_R_RXP<0>!R2U14!1!@baseboard_fab2_lib.baseboard_fab2(sch_1):page107_i466@mstr_discrete.res(chips)!RES_0402-0.0,5%,1/16W,EMPTY,G2A!!!F1671!A!!!!
S!P3E_CPU0_PE1_SS_RXP<0>!R2U14!2!@baseboard_fab2_lib.baseboard_fab2(sch_1):page107_i466@mstr_discrete.res(chips)!RES_0402-0.0,5%,1/16W,EMPTY,G2A!!!F1671!B!!!!
S!P3E_CPU0_PE1_SS_R_RXN<0>!R2U15!1!@baseboard_fab2_lib.baseboard_fab2(sch_1):page107_i465@mstr_discrete.res(chips)!RES_0402-0.0,5%,1/16W,EMPTY,G2A!!!F1670!A!!!!
S!P3E_CPU0_PE1_SS_RXN<0>!R2U15!2!@baseboard_fab2_lib.baseboard_fab2(sch_1):page107_i465@mstr_discrete.res(chips)!RES_0402-0.0,5%,1/16W,EMPTY,G2A!!!F1670!B!!!!
S!P3E_CPU0_PE1_SS_R_RXP<1>!R2U16!1!@baseboard_fab2_lib.baseboard_fab2(sch_1):page107_i467@mstr_discrete.res(chips)!RES_0402-0.0,5%,1/16W,EMPTY,G2A!!!F1669!A!!!!
S!P3E_CPU0_PE1_SS_RXP<1>!R2U16!2!@baseboard_fab2_lib.baseboard_fab2(sch_1):page107_i467@mstr_discrete.res(chips)!RES_0402-0.0,5%,1/16W,EMPTY,G2A!!!F1669!B!!!!
S!P3E_CPU0_PE1_SS_R_RXN<1>!R2U17!1!@baseboard_fab2_lib.baseboard_fab2(sch_1):page107_i464@mstr_discrete.res(chips)!RES_0402-0.0,5%,1/16W,EMPTY,G2A!!!F1668!A!!!!
S!P3E_CPU0_PE1_SS_RXN<1>!R2U17!2!@baseboard_fab2_lib.baseboard_fab2(sch_1):page107_i464@mstr_discrete.res(chips)!RES_0402-0.0,5%,1/16W,EMPTY,G2A!!!F1668!B!!!!
S!P3E_CPU0_PE1_SS_R_RXP<2>!R2U18!1!@baseboard_fab2_lib.baseboard_fab2(sch_1):page107_i468@mstr_discrete.res(chips)!RES_0402-0.0,5%,1/16W,EMPTY,G2A!!!F1667!A!!!!
S!P3E_CPU0_PE1_SS_RXP<2>!R2U18!2!@baseboard_fab2_lib.baseboard_fab2(sch_1):page107_i468@mstr_discrete.res(chips)!RES_0402-0.0,5%,1/16W,EMPTY,G2A!!!F1667!B!!!!
S!P3E_CPU0_PE1_SS_R_RXN<2>!R2U19!1!@baseboard_fab2_lib.baseboard_fab2(sch_1):page107_i463@mstr_discrete.res(chips)!RES_0402-0.0,5%,1/16W,EMPTY,G2A!!!F1666!A!!!!
S!P3E_CPU0_PE1_SS_RXN<2>!R2U19!2!@baseboard_fab2_lib.baseboard_fab2(sch_1):page107_i463@mstr_discrete.res(chips)!RES_0402-0.0,5%,1/16W,EMPTY,G2A!!!F1666!B!!!!
S!P3E_CPU0_PE1_SS_R_RXP<3>!R2U20!1!@baseboard_fab2_lib.baseboard_fab2(sch_1):page107_i469@mstr_discrete.res(chips)!RES_0402-0.0,5%,1/16W,EMPTY,G2A!!!F1665!A!!!!
S!P3E_CPU0_PE1_SS_RXP<3>!R2U20!2!@baseboard_fab2_lib.baseboard_fab2(sch_1):page107_i469@mstr_discrete.res(chips)!RES_0402-0.0,5%,1/16W,EMPTY,G2A!!!F1665!B!!!!
S!P3E_CPU0_PE1_SS_R_RXN<3>!R2U21!1!@baseboard_fab2_lib.baseboard_fab2(sch_1):page107_i462@mstr_discrete.res(chips)!RES_0402-0.0,5%,1/16W,EMPTY,G2A!!!F1664!A!!!!
S!P3E_CPU0_PE1_SS_RXN<3>!R2U21!2!@baseboard_fab2_lib.baseboard_fab2(sch_1):page107_i462@mstr_discrete.res(chips)!RES_0402-0.0,5%,1/16W,EMPTY,G2A!!!F1664!B!!!!
S!P3E_CPU0_PE1_SS_R_RXP<4>!R2U22!1!@baseboard_fab2_lib.baseboard_fab2(sch_1):page107_i470@mstr_discrete.res(chips)!RES_0402-0.0,5%,1/16W,EMPTY,G2A!!!F1663!A!!!!
S!P3E_CPU0_PE1_SS_RXP<4>!R2U22!2!@baseboard_fab2_lib.baseboard_fab2(sch_1):page107_i470@mstr_discrete.res(chips)!RES_0402-0.0,5%,1/16W,EMPTY,G2A!!!F1663!B!!!!
S!P3E_CPU0_PE1_SS_R_RXN<4>!R2U23!1!@baseboard_fab2_lib.baseboard_fab2(sch_1):page107_i461@mstr_discrete.res(chips)!RES_0402-0.0,5%,1/16W,EMPTY,G2A!!!F1662!A!!!!
S!P3E_CPU0_PE1_SS_RXN<4>!R2U23!2!@baseboard_fab2_lib.baseboard_fab2(sch_1):page107_i461@mstr_discrete.res(chips)!RES_0402-0.0,5%,1/16W,EMPTY,G2A!!!F1662!B!!!!
S!P3E_CPU0_PE1_SS_R_RXP<5>!R2U24!1!@baseboard_fab2_lib.baseboard_fab2(sch_1):page107_i471@mstr_discrete.res(chips)!RES_0402-0.0,5%,1/16W,EMPTY,G2A!!!F1661!A!!!!
S!P3E_CPU0_PE1_SS_RXP<5>!R2U24!2!@baseboard_fab2_lib.baseboard_fab2(sch_1):page107_i471@mstr_discrete.res(chips)!RES_0402-0.0,5%,1/16W,EMPTY,G2A!!!F1661!B!!!!
S!P3E_CPU0_PE1_SS_R_RXN<5>!R2U25!1!@baseboard_fab2_lib.baseboard_fab2(sch_1):page107_i460@mstr_discrete.res(chips)!RES_0402-0.0,5%,1/16W,EMPTY,G2A!!!F1660!A!!!!
S!P3E_CPU0_PE1_SS_RXN<5>!R2U25!2!@baseboard_fab2_lib.baseboard_fab2(sch_1):page107_i460@mstr_discrete.res(chips)!RES_0402-0.0,5%,1/16W,EMPTY,G2A!!!F1660!B!!!!
S!P3E_CPU0_PE1_SS_R_RXP<6>!R2U26!1!@baseboard_fab2_lib.baseboard_fab2(sch_1):page107_i472@mstr_discrete.res(chips)!RES_0402-0.0,5%,1/16W,EMPTY,G2A!!!F1659!A!!!!
S!P3E_CPU0_PE1_SS_RXP<6>!R2U26!2!@baseboard_fab2_lib.baseboard_fab2(sch_1):page107_i472@mstr_discrete.res(chips)!RES_0402-0.0,5%,1/16W,EMPTY,G2A!!!F1659!B!!!!
S!P3E_CPU0_PE1_SS_R_RXN<6>!R2U27!1!@baseboard_fab2_lib.baseboard_fab2(sch_1):page107_i459@mstr_discrete.res(chips)!RES_0402-0.0,5%,1/16W,EMPTY,G2A!!!F1658!A!!!!
S!P3E_CPU0_PE1_SS_RXN<6>!R2U27!2!@baseboard_fab2_lib.baseboard_fab2(sch_1):page107_i459@mstr_discrete.res(chips)!RES_0402-0.0,5%,1/16W,EMPTY,G2A!!!F1658!B!!!!
S!P3E_CPU0_PE1_SS_R_RXP<7>!R2U28!1!@baseboard_fab2_lib.baseboard_fab2(sch_1):page107_i473@mstr_discrete.res(chips)!RES_0402-0.0,5%,1/16W,EMPTY,G2A!!!F1657!A!!!!
S!P3E_CPU0_PE1_SS_RXP<7>!R2U28!2!@baseboard_fab2_lib.baseboard_fab2(sch_1):page107_i473@mstr_discrete.res(chips)!RES_0402-0.0,5%,1/16W,EMPTY,G2A!!!F1657!B!!!!
S!P3E_CPU0_PE1_SS_R_RXN<7>!R2U29!1!@baseboard_fab2_lib.baseboard_fab2(sch_1):page107_i458@mstr_discrete.res(chips)!RES_0402-0.0,5%,1/16W,EMPTY,G2A!!!F1656!A!!!!
S!P3E_CPU0_PE1_SS_RXN<7>!R2U29!2!@baseboard_fab2_lib.baseboard_fab2(sch_1):page107_i458@mstr_discrete.res(chips)!RES_0402-0.0,5%,1/16W,EMPTY,G2A!!!F1656!B!!!!
S!CLK_25M_BMC!R9F60!1!@baseboard_fab2_lib.baseboard_fab2(sch_1):page145_i257@mstr_discrete.res(chips)!RES_0402-0.0,5%,1/16W,EMPTY,G2A!!!F1604!A!!!!
S!CLK_24M_25M_BMC_CLKIN!R9F60!2!@baseboard_fab2_lib.baseboard_fab2(sch_1):page145_i257@mstr_discrete.res(chips)!RES_0402-0.0,5%,1/16W,EMPTY,G2A!!!F1604!B!!!!
S!H_CPU_ERR0_PCH_N!R2T57!1!@baseboard_fab2_lib.baseboard_fab2(sch_1):page93_i88@mstr_discrete.res(chips)!RES_0402-0.0,5%,1/16W,EMPTY,G2A!!!F1620!A!!!!
S!H_CPU_ERR0_GTL_R_N!R2T57!2!@baseboard_fab2_lib.baseboard_fab2(sch_1):page93_i88@mstr_discrete.res(chips)!RES_0402-0.0,5%,1/16W,EMPTY,G2A!!!F1620!B!!!!
S!H_CPU1_PROCHOT_G_N!R2T69!1!@baseboard_fab2_lib.baseboard_fab2(sch_1):page93_i108@mstr_discrete.res(chips)!RES_0402-0.0,5%,1/16W,EMPTY,G2A!!!F1619!A!!!!
S!H_CPU1_PROCHOT_G_PCH_N!R2T69!2!@baseboard_fab2_lib.baseboard_fab2(sch_1):page93_i108@mstr_discrete.res(chips)!RES_0402-0.0,5%,1/16W,EMPTY,G2A!!!F1619!B!!!!
S!H_CPU_ERR1_PCH_N!R2T61!1!@baseboard_fab2_lib.baseboard_fab2(sch_1):page93_i89@mstr_discrete.res(chips)!RES_0402-0.0,5%,1/16W,EMPTY,G2A!!!F1618!A!!!!
S!H_CPU_ERR1_GTL_R_N!R2T61!2!@baseboard_fab2_lib.baseboard_fab2(sch_1):page93_i89@mstr_discrete.res(chips)!RES_0402-0.0,5%,1/16W,EMPTY,G2A!!!F1618!B!!!!
S!H_CPU0_PROCHOT_G_N!R2T59!1!@baseboard_fab2_lib.baseboard_fab2(sch_1):page93_i107@mstr_discrete.res(chips)!RES_0402-0.0,5%,1/16W,EMPTY,G2A!!!F1617!A!!!!
S!H_CPU0_PROCHOT_G_PCH_N!R2T59!2!@baseboard_fab2_lib.baseboard_fab2(sch_1):page93_i107@mstr_discrete.res(chips)!RES_0402-0.0,5%,1/16W,EMPTY,G2A!!!F1617!B!!!!
S!H_CPU_ERR1_PCH_N!R2T62!1!@baseboard_fab2_lib.baseboard_fab2(sch_1):page93_i93@mstr_discrete.res(chips)!RES_0402-0.0,5%,1/16W,EMPTY,G2A!!!F1616!A!!!!
S!FM_CPU_ERR0_LVT3_K_N!R2T62!2!@baseboard_fab2_lib.baseboard_fab2(sch_1):page93_i93@mstr_discrete.res(chips)!RES_0402-0.0,5%,1/16W,EMPTY,G2A!!!F1616!B!!!!
S!FM_CPU0_PROCHOT_LVT3_K_N!R2T71!1!@baseboard_fab2_lib.baseboard_fab2(sch_1):page93_i109@mstr_discrete.res(chips)!RES_0402-0.0,5%,1/16W,EMPTY,G2A!!!F1615!A!!!!
S!H_CPU0_PROCHOT_G_PCH_N!R2T71!2!@baseboard_fab2_lib.baseboard_fab2(sch_1):page93_i109@mstr_discrete.res(chips)!RES_0402-0.0,5%,1/16W,EMPTY,G2A!!!F1615!B!!!!
S!FM_CPU1_PROCHOT_LVT3_K_N!R2T70!1!@baseboard_fab2_lib.baseboard_fab2(sch_1):page93_i110@mstr_discrete.res(chips)!RES_0402-0.0,5%,1/16W,EMPTY,G2A!!!F1614!A!!!!
S!H_CPU1_PROCHOT_G_PCH_N!R2T70!2!@baseboard_fab2_lib.baseboard_fab2(sch_1):page93_i110@mstr_discrete.res(chips)!RES_0402-0.0,5%,1/16W,EMPTY,G2A!!!F1614!B!!!!
S!H_CPU_ERR0_PCH_N!R2T58!1!@baseboard_fab2_lib.baseboard_fab2(sch_1):page93_i94@mstr_discrete.res(chips)!RES_0402-0.0,5%,1/16W,EMPTY,G2A!!!F1613!A!!!!
S!FM_CPU_ERR0_LVT3_K_N!R2T58!2!@baseboard_fab2_lib.baseboard_fab2(sch_1):page93_i94@mstr_discrete.res(chips)!RES_0402-0.0,5%,1/16W,EMPTY,G2A!!!F1613!B!!!!
S!H_CPU0_MEMABC_MEMHOT_G_PCH_N!R2U51!1!@baseboard_fab2_lib.baseboard_fab2(sch_1):page152_i51@mstr_discrete.res(chips)!RES_0402-0.0,5%,1/16W,EMPTY,G2A!!!F1612!A!!!!
S!H_CPU0_MEMABC_MEMHOT_G_N!R2U51!2!@baseboard_fab2_lib.baseboard_fab2(sch_1):page152_i51@mstr_discrete.res(chips)!RES_0402-0.0,5%,1/16W,EMPTY,G2A!!!F1612!B!!!!
S!H_CPU1_MEMKLM_MEMHOT_G_N!R1U62!1!@baseboard_fab2_lib.baseboard_fab2(sch_1):page152_i68@mstr_discrete.res(chips)!RES_0402-0.0,5%,1/16W,EMPTY,G2A!!!F1611!A!!!!
S!H_CPU1_MEMKLM_MEMHOT_G_PCH_N!R1U62!2!@baseboard_fab2_lib.baseboard_fab2(sch_1):page152_i68@mstr_discrete.res(chips)!RES_0402-0.0,5%,1/16W,EMPTY,G2A!!!F1611!B!!!!
S!H_CPU0_MEMDEF_MEMHOT_G_PCH_N!R1U56!1!@baseboard_fab2_lib.baseboard_fab2(sch_1):page152_i50@mstr_discrete.res(chips)!RES_0402-0.0,5%,1/16W,EMPTY,G2A!!!F1610!A!!!!
S!H_CPU0_MEMDEF_MEMHOT_G_N!R1U56!2!@baseboard_fab2_lib.baseboard_fab2(sch_1):page152_i50@mstr_discrete.res(chips)!RES_0402-0.0,5%,1/16W,EMPTY,G2A!!!F1610!B!!!!
S!H_CPU1_MEMGHJ_MEMHOT_G_N!R1U55!1!@baseboard_fab2_lib.baseboard_fab2(sch_1):page152_i67@mstr_discrete.res(chips)!RES_0402-0.0,5%,1/16W,EMPTY,G2A!!!F1609!A!!!!
S!H_CPU1_MEMGHJ_MEMHOT_G_PCH_N!R1U55!2!@baseboard_fab2_lib.baseboard_fab2(sch_1):page152_i67@mstr_discrete.res(chips)!RES_0402-0.0,5%,1/16W,EMPTY,G2A!!!F1609!B!!!!
S!H_CPU0_MEMDEF_MEMHOT_G_PCH_N!R9G27!1!@baseboard_fab2_lib.baseboard_fab2(sch_1):page152_i47@mstr_discrete.res(chips)!RES_0402-0.0,5%,1/16W,EMPTY,G2A!!!F1608!A!!!!
S!H_CPU0_MEMDEF_MEMHOT_LVT3_K_N!R9G27!2!@baseboard_fab2_lib.baseboard_fab2(sch_1):page152_i47@mstr_discrete.res(chips)!RES_0402-0.0,5%,1/16W,EMPTY,G2A!!!F1608!B!!!!
S!H_CPU1_MEMGHJ_MEMHOT_LVT3_K_N!R1U57!1!@baseboard_fab2_lib.baseboard_fab2(sch_1):page152_i69@mstr_discrete.res(chips)!RES_0402-0.0,5%,1/16W,EMPTY,G2A!!!F1607!A!!!!
S!H_CPU1_MEMGHJ_MEMHOT_G_PCH_N!R1U57!2!@baseboard_fab2_lib.baseboard_fab2(sch_1):page152_i69@mstr_discrete.res(chips)!RES_0402-0.0,5%,1/16W,EMPTY,G2A!!!F1607!B!!!!
S!H_CPU0_MEMABC_MEMHOT_G_PCH_N!R2U49!1!@baseboard_fab2_lib.baseboard_fab2(sch_1):page152_i66@mstr_discrete.res(chips)!RES_0402-0.0,5%,1/16W,EMPTY,G2A!!!F1606!A!!!!
S!H_CPU0_MEMABC_MEMHOT_LVT3_K_N!R2U49!2!@baseboard_fab2_lib.baseboard_fab2(sch_1):page152_i66@mstr_discrete.res(chips)!RES_0402-0.0,5%,1/16W,EMPTY,G2A!!!F1606!B!!!!
S!H_CPU1_MEMKLM_MEMHOT_LVT3_K_N!R1U61!1!@baseboard_fab2_lib.baseboard_fab2(sch_1):page152_i70@mstr_discrete.res(chips)!RES_0402-0.0,5%,1/16W,EMPTY,G2A!!!F1605!A!!!!
S!H_CPU1_MEMKLM_MEMHOT_G_PCH_N!R1U61!2!@baseboard_fab2_lib.baseboard_fab2(sch_1):page152_i70@mstr_discrete.res(chips)!RES_0402-0.0,5%,1/16W,EMPTY,G2A!!!F1605!B!!!!
S!FM_CPU0_VRM_OSC_EN!R7D40!1!@baseboard_fab2_lib.baseboard_fab2(sch_1):page104_i94@mstr_discrete.res(chips)!RES_0402-0.0,5%,1/16W,EMPTY,G2A!!!F1628!A!!!!
S!FM_CPU0_STL_BRD_OSC_EN!R7D40!2!@baseboard_fab2_lib.baseboard_fab2(sch_1):page104_i94@mstr_discrete.res(chips)!RES_0402-0.0,5%,1/16W,EMPTY,G2A!!!F1628!B!!!!
S!FM_CPU1_VRM_OSC_EN!R7D38!1!@baseboard_fab2_lib.baseboard_fab2(sch_1):page104_i97@mstr_discrete.res(chips)!RES_0402-0.0,5%,1/16W,EMPTY,G2A!!!F1627!A!!!!
S!FM_CPU1_STL_BRD_OSC_EN!R7D38!2!@baseboard_fab2_lib.baseboard_fab2(sch_1):page104_i97@mstr_discrete.res(chips)!RES_0402-0.0,5%,1/16W,EMPTY,G2A!!!F1627!B!!!!
S!CLK_322M_156M_CPU0_OSC_VRM_DN!R6F10!1!@baseboard_fab2_lib.baseboard_fab2(sch_1):page104_i78@mstr_discrete.res(chips)!RES_0402-0.0,5%,1/16W,EMPTY,G2A!!!F1626!A!!!!
S!CLK_322M_OSC_CPU0_RC_DN!R6F10!2!@baseboard_fab2_lib.baseboard_fab2(sch_1):page104_i78@mstr_discrete.res(chips)!RES_0402-0.0,5%,1/16W,EMPTY,G2A!!!F1626!B!!!!
S!CLK_322M_156M_CPU0_OSC_VRM_DP!R6F11!1!@baseboard_fab2_lib.baseboard_fab2(sch_1):page104_i79@mstr_discrete.res(chips)!RES_0402-0.0,5%,1/16W,EMPTY,G2A!!!F1625!A!!!!
S!CLK_322M_OSC_CPU0_RC_DP!R6F11!2!@baseboard_fab2_lib.baseboard_fab2(sch_1):page104_i79@mstr_discrete.res(chips)!RES_0402-0.0,5%,1/16W,EMPTY,G2A!!!F1625!B!!!!
S!CLK_322M_156M_CPU1_OSC_VRM_DN!R3F5!1!@baseboard_fab2_lib.baseboard_fab2(sch_1):page104_i84@mstr_discrete.res(chips)!RES_0402-0.0,5%,1/16W,EMPTY,G2A!!!F1624!A!!!!
S!CLK_322M_OSC_CPU1_RC_DN!R3F5!2!@baseboard_fab2_lib.baseboard_fab2(sch_1):page104_i84@mstr_discrete.res(chips)!RES_0402-0.0,5%,1/16W,EMPTY,G2A!!!F1624!B!!!!
S!CLK_322M_156M_CPU1_OSC_VRM_DP!R3F6!1!@baseboard_fab2_lib.baseboard_fab2(sch_1):page104_i88@mstr_discrete.res(chips)!RES_0402-0.0,5%,1/16W,EMPTY,G2A!!!F1623!A!!!!
S!CLK_322M_OSC_CPU1_RC_DP!R3F6!2!@baseboard_fab2_lib.baseboard_fab2(sch_1):page104_i88@mstr_discrete.res(chips)!RES_0402-0.0,5%,1/16W,EMPTY,G2A!!!F1623!B!!!!
S!FM_CPU0_VRM_OSC_EN!R7D39!1!@baseboard_fab2_lib.baseboard_fab2(sch_1):page104_i95@mstr_discrete.res(chips)!RES_0402-0.0,5%,1/16W,EMPTY,G2A!!!F1622!A!!!!
S!FM_CPU0_VRM_322M_156M_OSC_EN!R7D39!2!@baseboard_fab2_lib.baseboard_fab2(sch_1):page104_i95@mstr_discrete.res(chips)!RES_0402-0.0,5%,1/16W,EMPTY,G2A!!!F1622!B!!!!
S!FM_CPU1_VRM_OSC_EN!R7D37!1!@baseboard_fab2_lib.baseboard_fab2(sch_1):page104_i98@mstr_discrete.res(chips)!RES_0402-0.0,5%,1/16W,EMPTY,G2A!!!F1621!A!!!!
S!FM_CPU1_VRM_322M_156M_OSC_EN!R7D37!2!@baseboard_fab2_lib.baseboard_fab2(sch_1):page104_i98@mstr_discrete.res(chips)!RES_0402-0.0,5%,1/16W,EMPTY,G2A!!!F1621!B!!!!
S!FM_XRC_READY_N!R1C31!1!@baseboard_fab2_lib.baseboard_fab2(sch_1):page182_i110@mstr_discrete.res(chips)!RES_0402-0.0,5%,1/16W,EMPTY,G2A!!!F1677!A!!!!
S!FAN_TACH0_R!R1C31!2!@baseboard_fab2_lib.baseboard_fab2(sch_1):page182_i110@mstr_discrete.res(chips)!RES_0402-0.0,5%,1/16W,EMPTY,G2A!!!F1677!B!!!!
S!SMB_LAN_STBY_LVC3_SCL!R1C11!1!@baseboard_fab2_lib.baseboard_fab2(sch_1):page182_i97@mstr_discrete.res(chips)!RES_0402-0.0,5%,1/16W,EMPTY,G2A!!!F1678!A!!!!
S!FAN_TACH1_R!R1C11!2!@baseboard_fab2_lib.baseboard_fab2(sch_1):page182_i97@mstr_discrete.res(chips)!RES_0402-0.0,5%,1/16W,EMPTY,G2A!!!F1678!B!!!!
S!SMB_LAN_STBY_LVC3_SDA!R1C10!1!@baseboard_fab2_lib.baseboard_fab2(sch_1):page182_i101@mstr_discrete.res(chips)!RES_0402-0.0,5%,1/16W,EMPTY,G2A!!!F1679!A!!!!
S!FAN_TACH3_R!R1C10!2!@baseboard_fab2_lib.baseboard_fab2(sch_1):page182_i101@mstr_discrete.res(chips)!RES_0402-0.0,5%,1/16W,EMPTY,G2A!!!F1679!B!!!!
S!IRQ_BOARD_BMC_ALERT_N!R1C9!1!@baseboard_fab2_lib.baseboard_fab2(sch_1):page182_i104@mstr_discrete.res(chips)!RES_0402-0.0,5%,1/16W,EMPTY,G2A!!!F1680!A!!!!
S!FAN_TACH2_R!R1C9!2!@baseboard_fab2_lib.baseboard_fab2(sch_1):page182_i104@mstr_discrete.res(chips)!RES_0402-0.0,5%,1/16W,EMPTY,G2A!!!F1680!B!!!!
S!FM_BMC_READY_N!R1F9!1!@baseboard_fab2_lib.baseboard_fab2(sch_1):page182_i107@mstr_discrete.res(chips)!RES_0402-0.0,5%,1/16W,EMPTY,G2A!!!F1676!A!!!!
S!FAN_PWM_OUT_SYS0_R1!R1F9!2!@baseboard_fab2_lib.baseboard_fab2(sch_1):page182_i107@mstr_discrete.res(chips)!RES_0402-0.0,5%,1/16W,EMPTY,G2A!!!F1676!B!!!!
S!FM_GBE_LOM_DISABLE_N!R8C23!1!@baseboard_fab2_lib.baseboard_fab2(sch_1):page118_i125@mstr_discrete.res(chips)!RES_0402-0.0,5%,1/16W,EMPTY,G2A!!!F1643!A!!!!
S!FM_10GBE_LOM_DISABLE_N!R8C23!2!@baseboard_fab2_lib.baseboard_fab2(sch_1):page118_i125@mstr_discrete.res(chips)!RES_0402-0.0,5%,1/16W,EMPTY,G2A!!!F1643!B!!!!
S!FM_ROMA<0>!R9E15!1!@baseboard_fab2_lib.baseboard_fab2(sch_1):page150_i114@mstr_discrete.res(chips)!RES_0402-0.0,5%,1/16W,EMPTY,G2A!!!F1635!A!!!!
S!FM_BMC_ENABLE_N!R9E15!2!@baseboard_fab2_lib.baseboard_fab2(sch_1):page150_i114@mstr_discrete.res(chips)!RES_0402-0.0,5%,1/16W,EMPTY,G2A!!!F1635!B!!!!
S!FM_FLASH_DESC_OVERRIDE_R!R1T24!1!@baseboard_fab2_lib.baseboard_fab2(sch_1):page146_i127@mstr_discrete.res(chips)!RES_0402-0.0,5%,1/16W,EMPTY,G2A!!!F1673!A!!!!
S!FM_FLASH_DESC_OVERRIDE!R1T24!2!@baseboard_fab2_lib.baseboard_fab2(sch_1):page146_i127@mstr_discrete.res(chips)!RES_0402-0.0,5%,1/16W,EMPTY,G2A!!!F1673!B!!!!
S!CLK_100M_BMC_PE_R_DP!R7C4!1!@baseboard_fab2_lib.baseboard_fab2(sch_1):page114_i142@mstr_discrete.res(chips)!RES_0402-0.0,5%,1/16W,EMPTY,G2A!!!F1649!A!!!!
S!CLK_100M_BMC_PE_DP!R7C4!2!@baseboard_fab2_lib.baseboard_fab2(sch_1):page114_i142@mstr_discrete.res(chips)!RES_0402-0.0,5%,1/16W,EMPTY,G2A!!!F1649!B!!!!
S!CLK_100M_BMC_PE_R_DN!R7C2!1!@baseboard_fab2_lib.baseboard_fab2(sch_1):page114_i141@mstr_discrete.res(chips)!RES_0402-0.0,5%,1/16W,EMPTY,G2A!!!F1650!A!!!!
S!CLK_100M_BMC_PE_DN!R7C2!2!@baseboard_fab2_lib.baseboard_fab2(sch_1):page114_i141@mstr_discrete.res(chips)!RES_0402-0.0,5%,1/16W,EMPTY,G2A!!!F1650!B!!!!
S!FM_MEM_THERM_EVENT_LVT3_N!R8E11!1!@baseboard_fab2_lib.baseboard_fab2(sch_1):page156_i279@mstr_discrete.res(chips)!RES_0402-0.0,5%,1/16W,EMPTY,G2A!!!F1642!A!!!!
S!FM_ADR_SMI_GPIO_N!R8E11!2!@baseboard_fab2_lib.baseboard_fab2(sch_1):page156_i279@mstr_discrete.res(chips)!RES_0402-0.0,5%,1/16W,EMPTY,G2A!!!F1642!B!!!!
S!JTAG_PCH_GBE_TRST_N!R8G9!1!@baseboard_fab2_lib.baseboard_fab2(sch_1):page189_i9@mstr_discrete.res(chips)!RES_0402-0.0,5%,1/16W,EMPTY,G2A!!!F1640!A!!!!
S!JTAG_TRST_N!R8G9!2!@baseboard_fab2_lib.baseboard_fab2(sch_1):page189_i9@mstr_discrete.res(chips)!RES_0402-0.0,5%,1/16W,EMPTY,G2A!!!F1640!B!!!!
S!A_HSC_LOW_DRAIN!R9P15!1!@baseboard_fab2_lib.baseboard_fab2(sch_1):page200_i198@mstr_discrete.res(chips)!RES_0402-0.0,5%,1/16W,EMPTY,G2A!!!F1630!A!!!!
S!IRQ_OC_DETECT_N!R9P15!2!@baseboard_fab2_lib.baseboard_fab2(sch_1):page200_i198@mstr_discrete.res(chips)!RES_0402-0.0,5%,1/16W,EMPTY,G2A!!!F1630!B!!!!
S!CLK_322M_156M_CPU0_OSC_VRM_DN!R6F6!1!@baseboard_fab2_lib.baseboard_fab2(sch_1):page104_i41@mstr_discrete.res(chips)!RES_0402-0.0,5%,1/16W,EMPTY,G2A!!!F1652!A!!!!
S!CLK_156M_OSC_CPU0_HFI_DN!R6F6!2!@baseboard_fab2_lib.baseboard_fab2(sch_1):page104_i41@mstr_discrete.res(chips)!RES_0402-0.0,5%,1/16W,EMPTY,G2A!!!F1652!B!!!!
S!CLK_322M_156M_CPU1_OSC_VRM_DN!R3F1!1!@baseboard_fab2_lib.baseboard_fab2(sch_1):page104_i51@mstr_discrete.res(chips)!RES_0402-0.0,5%,1/16W,EMPTY,G2A!!!F1655!A!!!!
S!CLK_156M_OSC_CPU1_HFI_DN!R3F1!2!@baseboard_fab2_lib.baseboard_fab2(sch_1):page104_i51@mstr_discrete.res(chips)!RES_0402-0.0,5%,1/16W,EMPTY,G2A!!!F1655!B!!!!
S!CLK_322M_156M_CPU0_OSC_VRM_DP!R6F8!1!@baseboard_fab2_lib.baseboard_fab2(sch_1):page104_i37@mstr_discrete.res(chips)!RES_0402-0.0,5%,1/16W,EMPTY,G2A!!!F1651!A!!!!
S!CLK_156M_OSC_CPU0_HFI_DP!R6F8!2!@baseboard_fab2_lib.baseboard_fab2(sch_1):page104_i37@mstr_discrete.res(chips)!RES_0402-0.0,5%,1/16W,EMPTY,G2A!!!F1651!B!!!!
S!CLK_322M_156M_CPU1_OSC_VRM_DP!R3F3!1!@baseboard_fab2_lib.baseboard_fab2(sch_1):page104_i53@mstr_discrete.res(chips)!RES_0402-0.0,5%,1/16W,EMPTY,G2A!!!F1654!A!!!!
S!CLK_156M_OSC_CPU1_HFI_DP!R3F3!2!@baseboard_fab2_lib.baseboard_fab2(sch_1):page104_i53@mstr_discrete.res(chips)!RES_0402-0.0,5%,1/16W,EMPTY,G2A!!!F1654!B!!!!
S!FM_MATED_IN_N!R9T8!1!@baseboard_fab2_lib.baseboard_fab2(sch_1):page181_i249@mstr_discrete.res(chips)!RES_0402-0.0,5%,1/16W,EMPTY,G2A!!!F1629!A!!!!
S!GND!R9T8!2!@baseboard_fab2_lib.baseboard_fab2(sch_1):page181_i249@mstr_discrete.res(chips)!RES_0402-0.0,5%,1/16W,EMPTY,G2A!!!F1629!B!!!!
S!JTAG_PCH_PLD_TDI!R7G18!1!@baseboard_fab2_lib.baseboard_fab2(sch_1):page189_i13@mstr_discrete.res(chips)!RES_0402-0.0,5%,1/16W,EMPTY,G2A!!!F1645!A!!!!
S!JTAG_TDI!R7G18!2!@baseboard_fab2_lib.baseboard_fab2(sch_1):page189_i13@mstr_discrete.res(chips)!RES_0402-0.0,5%,1/16W,EMPTY,G2A!!!F1645!B!!!!
S!JTAG_PCH_PLD_TMS!R8G11!1!@baseboard_fab2_lib.baseboard_fab2(sch_1):page189_i19@mstr_discrete.res(chips)!RES_0402-0.0,5%,1/16W,EMPTY,G2A!!!F1639!A!!!!
S!JTAG_TMS!R8G11!2!@baseboard_fab2_lib.baseboard_fab2(sch_1):page189_i19@mstr_discrete.res(chips)!RES_0402-0.0,5%,1/16W,EMPTY,G2A!!!F1639!B!!!!
S!JTAG_PCH_PLD_TCK!R8G16!1!@baseboard_fab2_lib.baseboard_fab2(sch_1):page189_i22@mstr_discrete.res(chips)!RES_0402-0.0,5%,1/16W,EMPTY,G2A!!!F1636!A!!!!
S!JTAG_TCK!R8G16!2!@baseboard_fab2_lib.baseboard_fab2(sch_1):page189_i22@mstr_discrete.res(chips)!RES_0402-0.0,5%,1/16W,EMPTY,G2A!!!F1636!B!!!!
S!JTAG_PCH_PLD_TDO!R7G15!1!@baseboard_fab2_lib.baseboard_fab2(sch_1):page189_i36@mstr_discrete.res(chips)!RES_0402-0.0,5%,1/16W,EMPTY,G2A!!!F1647!A!!!!
S!JTAG_TDO!R7G15!2!@baseboard_fab2_lib.baseboard_fab2(sch_1):page189_i36@mstr_discrete.res(chips)!RES_0402-0.0,5%,1/16W,EMPTY,G2A!!!F1647!B!!!!
S!IRQ_DIMM_SAVE_LVT3_N!R2P12!1!@baseboard_fab2_lib.baseboard_fab2(sch_1):page89_i23@mstr_discrete.res(chips)!RES_0402-0.0,5%,1/16W,EMPTY,G2A!!!F1672!A!!!!
S!FM_ADR_SMI_GPIO_N!R2P12!2!@baseboard_fab2_lib.baseboard_fab2(sch_1):page89_i23@mstr_discrete.res(chips)!RES_0402-0.0,5%,1/16W,EMPTY,G2A!!!F1672!B!!!!
S!JTAG_PCH_GBE_TDI!R7G19!1!@baseboard_fab2_lib.baseboard_fab2(sch_1):page189_i8@mstr_discrete.res(chips)!RES_0402-0.0,5%,1/16W,EMPTY,G2A!!!F1644!A!!!!
S!JTAG_TDI!R7G19!2!@baseboard_fab2_lib.baseboard_fab2(sch_1):page189_i8@mstr_discrete.res(chips)!RES_0402-0.0,5%,1/16W,EMPTY,G2A!!!F1644!B!!!!
S!JTAG_PCH_GBE_TMS!R8G12!1!@baseboard_fab2_lib.baseboard_fab2(sch_1):page189_i21@mstr_discrete.res(chips)!RES_0402-0.0,5%,1/16W,EMPTY,G2A!!!F1638!A!!!!
S!JTAG_TMS!R8G12!2!@baseboard_fab2_lib.baseboard_fab2(sch_1):page189_i21@mstr_discrete.res(chips)!RES_0402-0.0,5%,1/16W,EMPTY,G2A!!!F1638!B!!!!
S!JTAG_PCH_GBE_CLK!R8G15!1!@baseboard_fab2_lib.baseboard_fab2(sch_1):page189_i24@mstr_discrete.res(chips)!RES_0402-0.0,5%,1/16W,EMPTY,G2A!!!F1637!A!!!!
S!JTAG_TCK!R8G15!2!@baseboard_fab2_lib.baseboard_fab2(sch_1):page189_i24@mstr_discrete.res(chips)!RES_0402-0.0,5%,1/16W,EMPTY,G2A!!!F1637!B!!!!
S!JTAG_PCH_GBE_TDO!R7G16!1!@baseboard_fab2_lib.baseboard_fab2(sch_1):page189_i27@mstr_discrete.res(chips)!RES_0402-0.0,5%,1/16W,EMPTY,G2A!!!F1646!A!!!!
S!JTAG_TDO!R7G16!2!@baseboard_fab2_lib.baseboard_fab2(sch_1):page189_i27@mstr_discrete.res(chips)!RES_0402-0.0,5%,1/16W,EMPTY,G2A!!!F1646!B!!!!
S!FM_PE_BMC_WAKE_N!R8E29!1!@baseboard_fab2_lib.baseboard_fab2(sch_1):page142_i18@mstr_discrete.res(chips)!RES_0402-0.0,5%,1/16W,EMPTY,G2A!!!F1641!A!!!!
S!FM_ALL_WAKE_N!R8E29!2!@baseboard_fab2_lib.baseboard_fab2(sch_1):page142_i18@mstr_discrete.res(chips)!RES_0402-0.0,5%,1/16W,EMPTY,G2A!!!F1641!B!!!!
S!PD_USB_BMC_P1_DN!R9G5!1!@baseboard_fab2_lib.baseboard_fab2(sch_1):page144_i516@mstr_discrete.res(chips)!RES_0402-0.0,5%,1/16W,EMPTY,G2A!!!F1632!A!!!!
S!GND!R9G5!2!@baseboard_fab2_lib.baseboard_fab2(sch_1):page144_i516@mstr_discrete.res(chips)!RES_0402-0.0,5%,1/16W,EMPTY,G2A!!!F1632!B!!!!
S!PD_USB_BMC_P1_DP!R9G6!1!@baseboard_fab2_lib.baseboard_fab2(sch_1):page144_i517@mstr_discrete.res(chips)!RES_0402-0.0,5%,1/16W,EMPTY,G2A!!!F1631!A!!!!
S!GND!R9G6!2!@baseboard_fab2_lib.baseboard_fab2(sch_1):page144_i517@mstr_discrete.res(chips)!RES_0402-0.0,5%,1/16W,EMPTY,G2A!!!F1631!B!!!!
S!FM_BMC_ONCTL_N!R1T15!1!@baseboard_fab2_lib.baseboard_fab2(sch_1):page145_i183@mstr_discrete.res(chips)!RES_0402-0.0,5%,1/16W,EMPTY,G2A!!!F1675!A!!!!
S!FM_BMC_ONCTL_R_N!R1T15!2!@baseboard_fab2_lib.baseboard_fab2(sch_1):page145_i183@mstr_discrete.res(chips)!RES_0402-0.0,5%,1/16W,EMPTY,G2A!!!F1675!B!!!!
S!FM_BMC_ONCTL_R_N!R1T23!1!@baseboard_fab2_lib.baseboard_fab2(sch_1):page145_i184@mstr_discrete.res(chips)!RES_0402-0.0,5%,1/16W,EMPTY,G2A!!!F1674!A!!!!
S!GND!R1T23!2!@baseboard_fab2_lib.baseboard_fab2(sch_1):page145_i184@mstr_discrete.res(chips)!RES_0402-0.0,5%,1/16W,EMPTY,G2A!!!F1674!B!!!!
S!SPA_MID_DBG_RX!R9F24!1!@baseboard_fab2_lib.baseboard_fab2(sch_1):page158_i100@mstr_discrete.res(chips)!RES_0402-0.0,5%,1/16W,EMPTY,G2A!!!F1634!A!!!!
S!SP2_BMC_CM_UART_RX!R9F24!2!@baseboard_fab2_lib.baseboard_fab2(sch_1):page158_i100@mstr_discrete.res(chips)!RES_0402-0.0,5%,1/16W,EMPTY,G2A!!!F1634!B!!!!
S!SP2_BMC_CM_UART_TX!R9F26!1!@baseboard_fab2_lib.baseboard_fab2(sch_1):page158_i99@mstr_discrete.res(chips)!RES_0402-0.0,5%,1/16W,EMPTY,G2A!!!F1633!A!!!!
S!SPA_MID_DBG_TX!R9F26!2!@baseboard_fab2_lib.baseboard_fab2(sch_1):page158_i99@mstr_discrete.res(chips)!RES_0402-0.0,5%,1/16W,EMPTY,G2A!!!F1633!B!!!!
S!FM_ADR_COMPLETE!R4T2!1!@baseboard_fab2_lib.baseboard_fab2(sch_1):page89_i1@mstr_discrete.res(chips)!RES_0402-0.0,5%,1/16W,EMPTY,G2A!!!F1653!A!!!!
S!FM_ADR_COMPLETE_R!R4T2!2!@baseboard_fab2_lib.baseboard_fab2(sch_1):page89_i1@mstr_discrete.res(chips)!RES_0402-0.0,5%,1/16W,EMPTY,G2A!!!F1653!B!!!!
S!VR_P1V05_PCH_STBY_PH1_VCIN!R3L4!1!@baseboard_fab2_lib.baseboard_fab2(sch_1):page236_i41@mstr_discrete.res(chips)!RES_0402-1.0,1%,1/16W,CHIP,G21A!!!F1593!A!!!!
S!P5V_STBY!R3L4!2!@baseboard_fab2_lib.baseboard_fab2(sch_1):page236_i41@mstr_discrete.res(chips)!RES_0402-1.0,1%,1/16W,CHIP,G21A!!!F1593!B!!!!
S!VR_PVNN_PCH_PH1_VCIN!R3L1!1!@baseboard_fab2_lib.baseboard_fab2(sch_1):page236_i14@mstr_discrete.res(chips)!RES_0402-1.0,1%,1/16W,CHIP,G21A!!!F1594!A!!!!
S!P5V_STBY!R3L1!2!@baseboard_fab2_lib.baseboard_fab2(sch_1):page236_i14@mstr_discrete.res(chips)!RES_0402-1.0,1%,1/16W,CHIP,G21A!!!F1594!B!!!!
S!VR_PVCCIO_CPU0_PH1_VCIN!R3N7!1!@baseboard_fab2_lib.baseboard_fab2(sch_1):page212_i32@mstr_discrete.res(chips)!RES_0402-1.0,1%,1/16W,CHIP,G21A!!!F1590!A!!!!
S!P5V_STBY!R3N7!2!@baseboard_fab2_lib.baseboard_fab2(sch_1):page212_i32@mstr_discrete.res(chips)!RES_0402-1.0,1%,1/16W,CHIP,G21A!!!F1590!B!!!!
S!VR_PVCCIO_CPU1_PH1_VCIN!R6R5!1!@baseboard_fab2_lib.baseboard_fab2(sch_1):page214_i71@mstr_discrete.res(chips)!RES_0402-1.0,1%,1/16W,CHIP,G21A!!!F1581!A!!!!
S!P5V_STBY!R6R5!2!@baseboard_fab2_lib.baseboard_fab2(sch_1):page214_i71@mstr_discrete.res(chips)!RES_0402-1.0,1%,1/16W,CHIP,G21A!!!F1581!B!!!!
S!VR_PVCCIN_CPU0_PH3_VCIN!R6P19!1!@baseboard_fab2_lib.baseboard_fab2(sch_1):page203_i38@mstr_discrete.res(chips)!RES_0402-1.0,1%,1/16W,CHIP,G21A!!!F1584!A!!!!
S!P5V_STBY!R6P19!2!@baseboard_fab2_lib.baseboard_fab2(sch_1):page203_i38@mstr_discrete.res(chips)!RES_0402-1.0,1%,1/16W,CHIP,G21A!!!F1584!B!!!!
S!VR_PVCCIN_CPU0_PH4_VCIN!R6P10!1!@baseboard_fab2_lib.baseboard_fab2(sch_1):page203_i50@mstr_discrete.res(chips)!RES_0402-1.0,1%,1/16W,CHIP,G21A!!!F1585!A!!!!
S!P5V_STBY!R6P10!2!@baseboard_fab2_lib.baseboard_fab2(sch_1):page203_i50@mstr_discrete.res(chips)!RES_0402-1.0,1%,1/16W,CHIP,G21A!!!F1585!B!!!!
S!VR_PVCCIN_CPU1_PH5_VCIN!R9P32!1!@baseboard_fab2_lib.baseboard_fab2(sch_1):page209_i24@mstr_discrete.res(chips)!RES_0402-1.0,1%,1/16W,CHIP,G21A!!!F1577!A!!!!
S!P5V_STBY!R9P32!2!@baseboard_fab2_lib.baseboard_fab2(sch_1):page209_i24@mstr_discrete.res(chips)!RES_0402-1.0,1%,1/16W,CHIP,G21A!!!F1577!B!!!!
S!VR_PVCCIN_CPU0_PH2_VCIN!R6R6!1!@baseboard_fab2_lib.baseboard_fab2(sch_1):page202_i39@mstr_discrete.res(chips)!RES_0402-1.0,1%,1/16W,CHIP,G21A!!!F1583!A!!!!
S!P5V_STBY!R6R6!2!@baseboard_fab2_lib.baseboard_fab2(sch_1):page202_i39@mstr_discrete.res(chips)!RES_0402-1.0,1%,1/16W,CHIP,G21A!!!F1583!B!!!!
S!VR_PVCCIN_CPU0_PH1_VCIN!R6R2!1!@baseboard_fab2_lib.baseboard_fab2(sch_1):page202_i33@mstr_discrete.res(chips)!RES_0402-1.0,1%,1/16W,CHIP,G21A!!!F1582!A!!!!
S!P5V_STBY!R6R2!2!@baseboard_fab2_lib.baseboard_fab2(sch_1):page202_i33@mstr_discrete.res(chips)!RES_0402-1.0,1%,1/16W,CHIP,G21A!!!F1582!B!!!!
S!VR_PVCCIN_CPU0_PH5_VCIN!R6P47!1!@baseboard_fab2_lib.baseboard_fab2(sch_1):page204_i33@mstr_discrete.res(chips)!RES_0402-1.0,1%,1/16W,CHIP,G21A!!!F1586!A!!!!
S!P5V_STBY!R6P47!2!@baseboard_fab2_lib.baseboard_fab2(sch_1):page204_i33@mstr_discrete.res(chips)!RES_0402-1.0,1%,1/16W,CHIP,G21A!!!F1586!B!!!!
S!VR_PVDDQ_ABC_PH1_VCIN!R3U6!1!@baseboard_fab2_lib.baseboard_fab2(sch_1):page216_i52@mstr_discrete.res(chips)!RES_0402-1.0,1%,1/16W,CHIP,G21A!!!F1589!A!!!!
S!P5V_STBY!R3U6!2!@baseboard_fab2_lib.baseboard_fab2(sch_1):page216_i52@mstr_discrete.res(chips)!RES_0402-1.0,1%,1/16W,CHIP,G21A!!!F1589!B!!!!
S!VR_PVDDQ_ABC_PH2_VCIN!R3U9!1!@baseboard_fab2_lib.baseboard_fab2(sch_1):page216_i76@mstr_discrete.res(chips)!RES_0402-1.0,1%,1/16W,CHIP,G21A!!!F1588!A!!!!
S!P5V_STBY!R3U9!2!@baseboard_fab2_lib.baseboard_fab2(sch_1):page216_i76@mstr_discrete.res(chips)!RES_0402-1.0,1%,1/16W,CHIP,G21A!!!F1588!B!!!!
S!VR_PVDDQ_DEF_PH1_VCIN!R3L6!1!@baseboard_fab2_lib.baseboard_fab2(sch_1):page219_i52@mstr_discrete.res(chips)!RES_0402-1.0,1%,1/16W,CHIP,G21A!!!F1592!A!!!!
S!P5V_STBY!R3L6!2!@baseboard_fab2_lib.baseboard_fab2(sch_1):page219_i52@mstr_discrete.res(chips)!RES_0402-1.0,1%,1/16W,CHIP,G21A!!!F1592!B!!!!
S!VR_PVDDQ_DEF_PH2_VCIN!R3L8!1!@baseboard_fab2_lib.baseboard_fab2(sch_1):page219_i76@mstr_discrete.res(chips)!RES_0402-1.0,1%,1/16W,CHIP,G21A!!!F1591!A!!!!
S!P5V_STBY!R3L8!2!@baseboard_fab2_lib.baseboard_fab2(sch_1):page219_i76@mstr_discrete.res(chips)!RES_0402-1.0,1%,1/16W,CHIP,G21A!!!F1591!B!!!!
S!VR_PVDDQ_KLM_PH1_VCIN!R9L9!1!@baseboard_fab2_lib.baseboard_fab2(sch_1):page227_i52@mstr_discrete.res(chips)!RES_0402-1.0,1%,1/16W,CHIP,G21A!!!F1579!A!!!!
S!P5V_STBY!R9L9!2!@baseboard_fab2_lib.baseboard_fab2(sch_1):page227_i52@mstr_discrete.res(chips)!RES_0402-1.0,1%,1/16W,CHIP,G21A!!!F1579!B!!!!
S!VR_PVDDQ_KLM_PH2_VCIN!R9L4!1!@baseboard_fab2_lib.baseboard_fab2(sch_1):page227_i76@mstr_discrete.res(chips)!RES_0402-1.0,1%,1/16W,CHIP,G21A!!!F1580!A!!!!
S!P5V_STBY!R9L4!2!@baseboard_fab2_lib.baseboard_fab2(sch_1):page227_i76@mstr_discrete.res(chips)!RES_0402-1.0,1%,1/16W,CHIP,G21A!!!F1580!B!!!!
S!VR_PVSA_CPU0_VCIN!R6N3!1!@baseboard_fab2_lib.baseboard_fab2(sch_1):page205_i19@mstr_discrete.res(chips)!RES_0402-1.0,1%,1/16W,CHIP,G21A!!!F1587!A!!!!
S!P5V_STBY!R6N3!2!@baseboard_fab2_lib.baseboard_fab2(sch_1):page205_i19@mstr_discrete.res(chips)!RES_0402-1.0,1%,1/16W,CHIP,G21A!!!F1587!B!!!!
S!VR_PVDDQ_GHJ_PH1_VCIN!R9U1!1!@baseboard_fab2_lib.baseboard_fab2(sch_1):page224_i52@mstr_discrete.res(chips)!RES_0402-1.0,1%,1/16W,CHIP,G21A!!!F1571!A!!!!
S!P5V_STBY!R9U1!2!@baseboard_fab2_lib.baseboard_fab2(sch_1):page224_i52@mstr_discrete.res(chips)!RES_0402-1.0,1%,1/16W,CHIP,G21A!!!F1571!B!!!!
S!VR_PVDDQ_GHJ_PH2_VCIN!R9U12!1!@baseboard_fab2_lib.baseboard_fab2(sch_1):page224_i76@mstr_discrete.res(chips)!RES_0402-1.0,1%,1/16W,CHIP,G21A!!!F1572!A!!!!
S!P5V_STBY!R9U12!2!@baseboard_fab2_lib.baseboard_fab2(sch_1):page224_i76@mstr_discrete.res(chips)!RES_0402-1.0,1%,1/16W,CHIP,G21A!!!F1572!B!!!!
S!VR_PVCCIN_CPU1_PH2_VCIN!R9R11!1!@baseboard_fab2_lib.baseboard_fab2(sch_1):page207_i39@mstr_discrete.res(chips)!RES_0402-1.0,1%,1/16W,CHIP,G21A!!!F1574!A!!!!
S!P5V_STBY!R9R11!2!@baseboard_fab2_lib.baseboard_fab2(sch_1):page207_i39@mstr_discrete.res(chips)!RES_0402-1.0,1%,1/16W,CHIP,G21A!!!F1574!B!!!!
S!VR_PVCCIN_CPU1_PH1_VCIN!R9R2!1!@baseboard_fab2_lib.baseboard_fab2(sch_1):page207_i26@mstr_discrete.res(chips)!RES_0402-1.0,1%,1/16W,CHIP,G21A!!!F1573!A!!!!
S!P5V_STBY!R9R2!2!@baseboard_fab2_lib.baseboard_fab2(sch_1):page207_i26@mstr_discrete.res(chips)!RES_0402-1.0,1%,1/16W,CHIP,G21A!!!F1573!B!!!!
S!VR_PVCCIN_CPU1_PH3_VCIN!R9P22!1!@baseboard_fab2_lib.baseboard_fab2(sch_1):page208_i36@mstr_discrete.res(chips)!RES_0402-1.0,1%,1/16W,CHIP,G21A!!!F1575!A!!!!
S!P5V_STBY!R9P22!2!@baseboard_fab2_lib.baseboard_fab2(sch_1):page208_i36@mstr_discrete.res(chips)!RES_0402-1.0,1%,1/16W,CHIP,G21A!!!F1575!B!!!!
S!VR_PVCCIN_CPU1_PH4_VCIN!R9P8!1!@baseboard_fab2_lib.baseboard_fab2(sch_1):page208_i49@mstr_discrete.res(chips)!RES_0402-1.0,1%,1/16W,CHIP,G21A!!!F1576!A!!!!
S!P5V_STBY!R9P8!2!@baseboard_fab2_lib.baseboard_fab2(sch_1):page208_i49@mstr_discrete.res(chips)!RES_0402-1.0,1%,1/16W,CHIP,G21A!!!F1576!B!!!!
S!VR_PVSA_CPU1_VCIN!R9N3!1!@baseboard_fab2_lib.baseboard_fab2(sch_1):page210_i20@mstr_discrete.res(chips)!RES_0402-1.0,1%,1/16W,CHIP,G21A!!!F1578!A!!!!
S!P5V_STBY!R9N3!2!@baseboard_fab2_lib.baseboard_fab2(sch_1):page210_i20@mstr_discrete.res(chips)!RES_0402-1.0,1%,1/16W,CHIP,G21A!!!F1578!B!!!!
S!FM_CPU0_SM_WP!R3P56!1!@baseboard_fab2_lib.baseboard_fab2(sch_1):page156_i333@mstr_discrete.res(chips)!RES_0402-1.00K,1%,1/16W,CHIP,GA!!!F1432!A!!!!
S!GND!R3P56!2!@baseboard_fab2_lib.baseboard_fab2(sch_1):page156_i333@mstr_discrete.res(chips)!RES_0402-1.00K,1%,1/16W,CHIP,GA!!!F1432!B!!!!
S!FM_CPU1_SM_WP!R1C36!1!@baseboard_fab2_lib.baseboard_fab2(sch_1):page156_i337@mstr_discrete.res(chips)!RES_0402-1.00K,1%,1/16W,CHIP,GA!!!F1431!A!!!!
S!GND!R1C36!2!@baseboard_fab2_lib.baseboard_fab2(sch_1):page156_i337@mstr_discrete.res(chips)!RES_0402-1.00K,1%,1/16W,CHIP,GA!!!F1431!B!!!!
S!GND!R6N14!1!@baseboard_fab2_lib.baseboard_fab2(sch_1):page156_i302@mstr_discrete.res(chips)!RES_0402-1.00K,1%,1/16W,CHIP,GA!!!F1438!A!!!!
S!PD_PIROM_CPU0_ADDR0!R6N14!2!@baseboard_fab2_lib.baseboard_fab2(sch_1):page156_i302@mstr_discrete.res(chips)!RES_0402-1.00K,1%,1/16W,CHIP,GA!!!F1438!B!!!!
S!GND!R6N13!1!@baseboard_fab2_lib.baseboard_fab2(sch_1):page156_i303@mstr_discrete.res(chips)!RES_0402-1.00K,1%,1/16W,CHIP,GA!!!F1437!A!!!!
S!PD_PIROM_CPU0_ADDR1!R6N13!2!@baseboard_fab2_lib.baseboard_fab2(sch_1):page156_i303@mstr_discrete.res(chips)!RES_0402-1.00K,1%,1/16W,CHIP,GA!!!F1437!B!!!!
S!GND!R6N15!1!@baseboard_fab2_lib.baseboard_fab2(sch_1):page156_i304@mstr_discrete.res(chips)!RES_0402-1.00K,1%,1/16W,CHIP,GA!!!F1436!A!!!!
S!PD_PIROM_CPU0_ADDR2!R6N15!2!@baseboard_fab2_lib.baseboard_fab2(sch_1):page156_i304@mstr_discrete.res(chips)!RES_0402-1.00K,1%,1/16W,CHIP,GA!!!F1436!B!!!!
S!GND!R1C33!1!@baseboard_fab2_lib.baseboard_fab2(sch_1):page156_i313@mstr_discrete.res(chips)!RES_0402-1.00K,1%,1/16W,CHIP,GA!!!F1435!A!!!!
S!PD_PIROM_CPU1_ADDR1!R1C33!2!@baseboard_fab2_lib.baseboard_fab2(sch_1):page156_i313@mstr_discrete.res(chips)!RES_0402-1.00K,1%,1/16W,CHIP,GA!!!F1435!B!!!!
S!GND!R1C32!1!@baseboard_fab2_lib.baseboard_fab2(sch_1):page156_i312@mstr_discrete.res(chips)!RES_0402-1.00K,1%,1/16W,CHIP,GA!!!F1434!A!!!!
S!PD_PIROM_CPU1_ADDR2!R1C32!2!@baseboard_fab2_lib.baseboard_fab2(sch_1):page156_i312@mstr_discrete.res(chips)!RES_0402-1.00K,1%,1/16W,CHIP,GA!!!F1434!B!!!!
S!FM_MEM_EVENT_FUNC!R7E20!1!@baseboard_fab2_lib.baseboard_fab2(sch_1):page192_i59@mstr_discrete.res(chips)!RES_0402-1.00K,1%,1/16W,CHIP,GA!!!F1433!A!!!!
S!GND!R7E20!2!@baseboard_fab2_lib.baseboard_fab2(sch_1):page192_i59@mstr_discrete.res(chips)!RES_0402-1.00K,1%,1/16W,CHIP,GA!!!F1433!B!!!!
S!P1V8_MCP_CPU0!R1M20!1!@baseboard_fab2_lib.baseboard_fab2(sch_1):page113_i204@mstr_discrete.res(chips)!RES_0402-1.00K,1%,1/16W,CHIP,GA!!!F1443!A!!!!
S!JTAG_MCP_MUX_TDI!R1M20!2!@baseboard_fab2_lib.baseboard_fab2(sch_1):page113_i204@mstr_discrete.res(chips)!RES_0402-1.00K,1%,1/16W,CHIP,GA!!!F1443!B!!!!
S!P1V8_MCP_CPU0!R1M19!1!@baseboard_fab2_lib.baseboard_fab2(sch_1):page113_i202@mstr_discrete.res(chips)!RES_0402-1.00K,1%,1/16W,CHIP,GA!!!F1442!A!!!!
S!JTAG_MCP_TMS!R1M19!2!@baseboard_fab2_lib.baseboard_fab2(sch_1):page113_i202@mstr_discrete.res(chips)!RES_0402-1.00K,1%,1/16W,CHIP,GA!!!F1442!B!!!!
S!P1V8_MCP_CPU0!R9B12!1!@baseboard_fab2_lib.baseboard_fab2(sch_1):page113_i203@mstr_discrete.res(chips)!RES_0402-1.00K,1%,1/16W,CHIP,GA!!!F1441!A!!!!
S!JTAG_MCP_MUX_TDO!R9B12!2!@baseboard_fab2_lib.baseboard_fab2(sch_1):page113_i203@mstr_discrete.res(chips)!RES_0402-1.00K,1%,1/16W,CHIP,GA!!!F1441!B!!!!
S!P1V8_MCP_CPU0!R1M21!1!@baseboard_fab2_lib.baseboard_fab2(sch_1):page113_i205@mstr_discrete.res(chips)!RES_0402-1.00K,1%,1/16W,CHIP,GA!!!F1440!A!!!!
S!JTAG_MCP_TRST_N!R1M21!2!@baseboard_fab2_lib.baseboard_fab2(sch_1):page113_i205@mstr_discrete.res(chips)!RES_0402-1.00K,1%,1/16W,CHIP,GA!!!F1440!B!!!!
S!JTAG_MCP_TCK!R9B9!1!@baseboard_fab2_lib.baseboard_fab2(sch_1):page113_i179@mstr_discrete.res(chips)!RES_0402-1.00K,1%,1/16W,CHIP,GA!!!F1439!A!!!!
S!GND!R9B9!2!@baseboard_fab2_lib.baseboard_fab2(sch_1):page113_i179@mstr_discrete.res(chips)!RES_0402-1.00K,1%,1/16W,CHIP,GA!!!F1439!B!!!!
S!PWRGD_CPU0_G!R9B14!1!@baseboard_fab2_lib.baseboard_fab2(sch_1):page113_i168@mstr_discrete.res(chips)!RES_0402-1.00K,1%,1/16W,CHIP,GA!!!F1464!A!!!!
S!PWRGD_CPU0_G_R!R9B14!2!@baseboard_fab2_lib.baseboard_fab2(sch_1):page113_i168@mstr_discrete.res(chips)!RES_0402-1.00K,1%,1/16W,CHIP,GA!!!F1464!B!!!!
S!P3V3_STBY!R2T5!1!@baseboard_fab2_lib.baseboard_fab2(sch_1):page157_i326@mstr_discrete.res(chips)!RES_0402-1.00K,1%,1/16W,CHIP,GA!!!F1533!A!!!!
S!H_CPU0_FAST_WAKE!R2T5!2!@baseboard_fab2_lib.baseboard_fab2(sch_1):page157_i326@mstr_discrete.res(chips)!RES_0402-1.00K,1%,1/16W,CHIP,GA!!!F1533!B!!!!
S!P3V3_STBY!R2T7!1!@baseboard_fab2_lib.baseboard_fab2(sch_1):page157_i327@mstr_discrete.res(chips)!RES_0402-1.00K,1%,1/16W,CHIP,GA!!!F1532!A!!!!
S!H_CPU0_FAST_WAKE_LVT3_N!R2T7!2!@baseboard_fab2_lib.baseboard_fab2(sch_1):page157_i327@mstr_discrete.res(chips)!RES_0402-1.00K,1%,1/16W,CHIP,GA!!!F1532!B!!!!
S!XDP_SPI_PCH_MOSI_BOOT_HALT_N!R8E2!1!@baseboard_fab2_lib.baseboard_fab2(sch_1):page111_i89@mstr_discrete.res(chips)!RES_0402-1.00K,1%,1/16W,CHIP,GA!!!F1460!A!!!!
S!SPI_PCH_MOSI!R8E2!2!@baseboard_fab2_lib.baseboard_fab2(sch_1):page111_i89@mstr_discrete.res(chips)!RES_0402-1.00K,1%,1/16W,CHIP,GA!!!F1460!B!!!!
S!H_CPU0_FAST_WAKE_N!R4R1!1!@baseboard_fab2_lib.baseboard_fab2(sch_1):page157_i368@mstr_discrete.res(chips)!RES_0402-1.00K,1%,1/16W,CHIP,GA!!!F1498!A!!!!
S!H_CPU0_FAST_WAKE_B_N!R4R1!2!@baseboard_fab2_lib.baseboard_fab2(sch_1):page157_i368@mstr_discrete.res(chips)!RES_0402-1.00K,1%,1/16W,CHIP,GA!!!F1498!B!!!!
S!FM_PI7C9X1172_A0!R9F51!1!@baseboard_fab2_lib.baseboard_fab2(sch_1):page183_i12@mstr_discrete.res(chips)!RES_0402-1.00K,1%,1/16W,CHIP,GA!!!F1451!A!!!!
S!GND!R9F51!2!@baseboard_fab2_lib.baseboard_fab2(sch_1):page183_i12@mstr_discrete.res(chips)!RES_0402-1.00K,1%,1/16W,CHIP,GA!!!F1451!B!!!!
S!FM_PI7C9X1172_A1!R9F50!1!@baseboard_fab2_lib.baseboard_fab2(sch_1):page183_i11@mstr_discrete.res(chips)!RES_0402-1.00K,1%,1/16W,CHIP,GA!!!F1452!A!!!!
S!GND!R9F50!2!@baseboard_fab2_lib.baseboard_fab2(sch_1):page183_i11@mstr_discrete.res(chips)!RES_0402-1.00K,1%,1/16W,CHIP,GA!!!F1452!B!!!!
S!P3V3_STBY!R7D2!1!@baseboard_fab2_lib.baseboard_fab2(sch_1):page133_i332@mstr_discrete.res(chips)!RES_0402-1.00K,1%,1/16W,CHIP,GA!!!F1481!A!!!!
S!PU_FM_RCIN_N!R7D2!2!@baseboard_fab2_lib.baseboard_fab2(sch_1):page133_i332@mstr_discrete.res(chips)!RES_0402-1.00K,1%,1/16W,CHIP,GA!!!F1481!B!!!!
S!P3V3_STBY!R7D7!1!@baseboard_fab2_lib.baseboard_fab2(sch_1):page133_i331@mstr_discrete.res(chips)!RES_0402-1.00K,1%,1/16W,CHIP,GA!!!F1480!A!!!!
S!IRQ_PIRQA_SPI_TPM_N!R7D7!2!@baseboard_fab2_lib.baseboard_fab2(sch_1):page133_i331@mstr_discrete.res(chips)!RES_0402-1.00K,1%,1/16W,CHIP,GA!!!F1480!B!!!!
S!P3V3_STBY!R3R15!1!@baseboard_fab2_lib.baseboard_fab2(sch_1):page189_i44@mstr_discrete.res(chips)!RES_0402-1.00K,1%,1/16W,CHIP,GA!!!F1514!A!!!!
S!FM_JTAG_PLD_EN_DEBUG!R3R15!2!@baseboard_fab2_lib.baseboard_fab2(sch_1):page189_i44@mstr_discrete.res(chips)!RES_0402-1.00K,1%,1/16W,CHIP,GA!!!F1514!B!!!!
S!PVCCIO_CPU0!R6P16!1!@baseboard_fab2_lib.baseboard_fab2(sch_1):page201_i132@mstr_discrete.res(chips)!RES_0402-1.00K,1%,1/16W,CHIP,GA!!!F1491!A!!!!
S!VR_PVCCIN_CPU0_VREN!R6P16!2!@baseboard_fab2_lib.baseboard_fab2(sch_1):page201_i132@mstr_discrete.res(chips)!RES_0402-1.00K,1%,1/16W,CHIP,GA!!!F1491!B!!!!
S!PVCCIO_CPU1!R9N14!1!@baseboard_fab2_lib.baseboard_fab2(sch_1):page206_i120@mstr_discrete.res(chips)!RES_0402-1.00K,1%,1/16W,CHIP,GA!!!F1444!A!!!!
S!VR_PVCCIN_CPU1_VREN!R9N14!2!@baseboard_fab2_lib.baseboard_fab2(sch_1):page206_i120@mstr_discrete.res(chips)!RES_0402-1.00K,1%,1/16W,CHIP,GA!!!F1444!B!!!!
S!FM_DB1200_SMB_SA0!R6P21!1!@baseboard_fab2_lib.baseboard_fab2(sch_1):page102_i80@mstr_discrete.res(chips)!RES_0402-1.00K,1%,1/16W,CHIP,GA!!!F1489!A!!!!
S!GND!R6P21!2!@baseboard_fab2_lib.baseboard_fab2(sch_1):page102_i80@mstr_discrete.res(chips)!RES_0402-1.00K,1%,1/16W,CHIP,GA!!!F1489!B!!!!
S!FM_DB1200_SMB_SA1!R6P20!1!@baseboard_fab2_lib.baseboard_fab2(sch_1):page102_i81@mstr_discrete.res(chips)!RES_0402-1.00K,1%,1/16W,CHIP,GA!!!F1490!A!!!!
S!GND!R6P20!2!@baseboard_fab2_lib.baseboard_fab2(sch_1):page102_i81@mstr_discrete.res(chips)!RES_0402-1.00K,1%,1/16W,CHIP,GA!!!F1490!B!!!!
S!FM_THERMTRIP_DLY!R7D18!1!@baseboard_fab2_lib.baseboard_fab2(sch_1):page135_i99@mstr_discrete.res(chips)!RES_0402-1.00K,1%,1/16W,CHIP,GA!!!F1479!A!!!!
S!FM_THERMTRIP_DLY_R!R7D18!2!@baseboard_fab2_lib.baseboard_fab2(sch_1):page135_i99@mstr_discrete.res(chips)!RES_0402-1.00K,1%,1/16W,CHIP,GA!!!F1479!B!!!!
S!H_CPU1_FIVR_FAULT_G!R3R2!1!@baseboard_fab2_lib.baseboard_fab2(sch_1):page92_i75@mstr_discrete.res(chips)!RES_0402-1.00K,1%,1/16W,CHIP,GA!!!F1515!A!!!!
S!GND!R3R2!2!@baseboard_fab2_lib.baseboard_fab2(sch_1):page92_i75@mstr_discrete.res(chips)!RES_0402-1.00K,1%,1/16W,CHIP,GA!!!F1515!B!!!!
S!P1V05_PCH_STBY!R3P7!1!@baseboard_fab2_lib.baseboard_fab2(sch_1):page133_i315@mstr_discrete.res(chips)!RES_0402-1.00K,1%,1/16W,CHIP,GA!!!F1523!A!!!!
S!FM_PRSNT_2_1_N!R3P7!2!@baseboard_fab2_lib.baseboard_fab2(sch_1):page133_i315@mstr_discrete.res(chips)!RES_0402-1.00K,1%,1/16W,CHIP,GA!!!F1523!B!!!!
S!P1V05_PCH_STBY!R3P5!1!@baseboard_fab2_lib.baseboard_fab2(sch_1):page133_i316@mstr_discrete.res(chips)!RES_0402-1.00K,1%,1/16W,CHIP,GA!!!F1525!A!!!!
S!FM_PRSNT_2_2_N!R3P5!2!@baseboard_fab2_lib.baseboard_fab2(sch_1):page133_i316@mstr_discrete.res(chips)!RES_0402-1.00K,1%,1/16W,CHIP,GA!!!F1525!B!!!!
S!P1V05_PCH_STBY!R3P6!1!@baseboard_fab2_lib.baseboard_fab2(sch_1):page133_i317@mstr_discrete.res(chips)!RES_0402-1.00K,1%,1/16W,CHIP,GA!!!F1524!A!!!!
S!FM_PRSNT_2_3_N!R3P6!2!@baseboard_fab2_lib.baseboard_fab2(sch_1):page133_i317@mstr_discrete.res(chips)!RES_0402-1.00K,1%,1/16W,CHIP,GA!!!F1524!B!!!!
S!P1V05_PCH_STBY!R3N15!1!@baseboard_fab2_lib.baseboard_fab2(sch_1):page133_i318@mstr_discrete.res(chips)!RES_0402-1.00K,1%,1/16W,CHIP,GA!!!F1527!A!!!!
S!FM_PRSNT_2_4_N!R3N15!2!@baseboard_fab2_lib.baseboard_fab2(sch_1):page133_i318@mstr_discrete.res(chips)!RES_0402-1.00K,1%,1/16W,CHIP,GA!!!F1527!B!!!!
S!P1V05_PCH_STBY!R3N16!1!@baseboard_fab2_lib.baseboard_fab2(sch_1):page133_i321@mstr_discrete.res(chips)!RES_0402-1.00K,1%,1/16W,CHIP,GA!!!F1526!A!!!!
S!FM_PRSNT_2_5_N!R3N16!2!@baseboard_fab2_lib.baseboard_fab2(sch_1):page133_i321@mstr_discrete.res(chips)!RES_0402-1.00K,1%,1/16W,CHIP,GA!!!F1526!B!!!!
S!P1V05_PCH_STBY!R3P8!1!@baseboard_fab2_lib.baseboard_fab2(sch_1):page133_i322@mstr_discrete.res(chips)!RES_0402-1.00K,1%,1/16W,CHIP,GA!!!F1522!A!!!!
S!FM_PRSNT_2_6_N!R3P8!2!@baseboard_fab2_lib.baseboard_fab2(sch_1):page133_i322@mstr_discrete.res(chips)!RES_0402-1.00K,1%,1/16W,CHIP,GA!!!F1522!B!!!!
S!P3V3_STBY!R8D28!1!@baseboard_fab2_lib.baseboard_fab2(sch_1):page167_i70@mstr_discrete.res(chips)!RES_0402-1.00K,1%,1/16W,CHIP,GA!!!F1461!A!!!!
S!PU_AT24C64_A2!R8D28!2!@baseboard_fab2_lib.baseboard_fab2(sch_1):page167_i70@mstr_discrete.res(chips)!RES_0402-1.00K,1%,1/16W,CHIP,GA!!!F1461!B!!!!
S!P3V3_STBY!R1E9!1!@baseboard_fab2_lib.baseboard_fab2(sch_1):page167_i34@mstr_discrete.res(chips)!RES_0402-1.00K,1%,1/16W,CHIP,GA!!!F1564!A!!!!
S!PU_TMP421_2_A0!R1E9!2!@baseboard_fab2_lib.baseboard_fab2(sch_1):page167_i34@mstr_discrete.res(chips)!RES_0402-1.00K,1%,1/16W,CHIP,GA!!!F1564!B!!!!
S!P3V3_STBY!R7G27!1!@baseboard_fab2_lib.baseboard_fab2(sch_1):page136_i155@mstr_discrete.res(chips)!RES_0402-1.00K,1%,1/16W,CHIP,GA!!!F1478!A!!!!
S!PU_BIOS_USB_RECOVERY!R7G27!2!@baseboard_fab2_lib.baseboard_fab2(sch_1):page136_i155@mstr_discrete.res(chips)!RES_0402-1.00K,1%,1/16W,CHIP,GA!!!F1478!B!!!!
S!P3V3_STBY!R7B17!1!@baseboard_fab2_lib.baseboard_fab2(sch_1):page232_i210@mstr_discrete.res(chips)!RES_0402-1.00K,1%,1/16W,CHIP,GA!!!F1485!A!!!!
S!PWRGD_PVPP_DEF_R!R7B17!2!@baseboard_fab2_lib.baseboard_fab2(sch_1):page232_i210@mstr_discrete.res(chips)!RES_0402-1.00K,1%,1/16W,CHIP,GA!!!F1485!B!!!!
S!P3V3_STBY!R4G14!1!@baseboard_fab2_lib.baseboard_fab2(sch_1):page233_i185@mstr_discrete.res(chips)!RES_0402-1.00K,1%,1/16W,CHIP,GA!!!F1501!A!!!!
S!PWRGD_PVPP_GHJ_R!R4G14!2!@baseboard_fab2_lib.baseboard_fab2(sch_1):page233_i185@mstr_discrete.res(chips)!RES_0402-1.00K,1%,1/16W,CHIP,GA!!!F1501!B!!!!
S!P3V3_STBY!R4B10!1!@baseboard_fab2_lib.baseboard_fab2(sch_1):page234_i143@mstr_discrete.res(chips)!RES_0402-1.00K,1%,1/16W,CHIP,GA!!!F1513!A!!!!
S!PWRGD_PVPP_KLM_R!R4B10!2!@baseboard_fab2_lib.baseboard_fab2(sch_1):page234_i143@mstr_discrete.res(chips)!RES_0402-1.00K,1%,1/16W,CHIP,GA!!!F1513!B!!!!
S!P3V3_STBY!R8C4!1!@baseboard_fab2_lib.baseboard_fab2(sch_1):page133_i286@mstr_discrete.res(chips)!RES_0402-1.00K,1%,1/16W,CHIP,GA!!!F1467!A!!!!
S!IRQ_BMC_PCH_SMI_LPC_N!R8C4!2!@baseboard_fab2_lib.baseboard_fab2(sch_1):page133_i286@mstr_discrete.res(chips)!RES_0402-1.00K,1%,1/16W,CHIP,GA!!!F1467!B!!!!
S!P3V3_STBY!R8B23!1!@baseboard_fab2_lib.baseboard_fab2(sch_1):page133_i280@mstr_discrete.res(chips)!RES_0402-1.00K,1%,1/16W,CHIP,GA!!!F1469!A!!!!
S!FM_XRC_PRESENT_N!R8B23!2!@baseboard_fab2_lib.baseboard_fab2(sch_1):page133_i280@mstr_discrete.res(chips)!RES_0402-1.00K,1%,1/16W,CHIP,GA!!!F1469!B!!!!
S!P3V3_STBY!R8B30!1!@baseboard_fab2_lib.baseboard_fab2(sch_1):page133_i282@mstr_discrete.res(chips)!RES_0402-1.00K,1%,1/16W,CHIP,GA!!!F1468!A!!!!
S!FM_XRC_READY_N!R8B30!2!@baseboard_fab2_lib.baseboard_fab2(sch_1):page133_i282@mstr_discrete.res(chips)!RES_0402-1.00K,1%,1/16W,CHIP,GA!!!F1468!B!!!!
S!FM_BOARD_SKU_ID4!R2N18!1!@baseboard_fab2_lib.baseboard_fab2(sch_1):page164_i32@mstr_discrete.res(chips)!RES_0402-1.00K,1%,1/16W,CHIP,GA!!!F1537!A!!!!
S!GND!R2N18!2!@baseboard_fab2_lib.baseboard_fab2(sch_1):page164_i32@mstr_discrete.res(chips)!RES_0402-1.00K,1%,1/16W,CHIP,GA!!!F1537!B!!!!
S!P3V3_STBY!R2M4!1!@baseboard_fab2_lib.baseboard_fab2(sch_1):page133_i284@mstr_discrete.res(chips)!RES_0402-1.00K,1%,1/16W,CHIP,GA!!!F1538!A!!!!
S!IRQ_HSC_FAULT_N!R2M4!2!@baseboard_fab2_lib.baseboard_fab2(sch_1):page133_i284@mstr_discrete.res(chips)!RES_0402-1.00K,1%,1/16W,CHIP,GA!!!F1538!B!!!!
S!P3V3_STBY!R7F19!1!@baseboard_fab2_lib.baseboard_fab2(sch_1):page231_i143@mstr_discrete.res(chips)!RES_0402-1.00K,1%,1/16W,CHIP,GA!!!F1475!A!!!!
S!PWRGD_PVPP_ABC_R!R7F19!2!@baseboard_fab2_lib.baseboard_fab2(sch_1):page231_i143@mstr_discrete.res(chips)!RES_0402-1.00K,1%,1/16W,CHIP,GA!!!F1475!B!!!!
S!P3V3_STBY!R8F5!1!@baseboard_fab2_lib.baseboard_fab2(sch_1):page240_i117@mstr_discrete.res(chips)!RES_0402-1.00K,1%,1/16W,CHIP,GA!!!F1458!A!!!!
S!PWRGD_P3V3_STBY_R!R8F5!2!@baseboard_fab2_lib.baseboard_fab2(sch_1):page240_i117@mstr_discrete.res(chips)!RES_0402-1.00K,1%,1/16W,CHIP,GA!!!F1458!B!!!!
S!P3V3_STBY!R8D21!1!@baseboard_fab2_lib.baseboard_fab2(sch_1):page134_i24@mstr_discrete.res(chips)!RES_0402-1.00K,1%,1/16W,CHIP,GA!!!F1463!A!!!!
S!FM_IE_DISABLE_N!R8D21!2!@baseboard_fab2_lib.baseboard_fab2(sch_1):page134_i24@mstr_discrete.res(chips)!RES_0402-1.00K,1%,1/16W,CHIP,GA!!!F1463!B!!!!
S!PD_SATA0_CONTROLLER_TYPE_R!R2L18!1!@baseboard_fab2_lib.baseboard_fab2(sch_1):page173_i266@mstr_discrete.res(chips)!RES_0402-1.00K,1%,1/16W,CHIP,GA!!!F1540!A!!!!
S!GND!R2L18!2!@baseboard_fab2_lib.baseboard_fab2(sch_1):page173_i266@mstr_discrete.res(chips)!RES_0402-1.00K,1%,1/16W,CHIP,GA!!!F1540!B!!!!
S!PD_SATA1_CONTROLLER_TYPE_R!R2L22!1!@baseboard_fab2_lib.baseboard_fab2(sch_1):page173_i264@mstr_discrete.res(chips)!RES_0402-1.00K,1%,1/16W,CHIP,GA!!!F1539!A!!!!
S!GND!R2L22!2!@baseboard_fab2_lib.baseboard_fab2(sch_1):page173_i264@mstr_discrete.res(chips)!RES_0402-1.00K,1%,1/16W,CHIP,GA!!!F1539!B!!!!
S!PD_IE_DEBUG_MODE!R1U64!1!@baseboard_fab2_lib.baseboard_fab2(sch_1):page137_i69@mstr_discrete.res(chips)!RES_0402-1.00K,1%,1/16W,CHIP,GA!!!F1484!A!!!!
S!GND!R1U64!2!@baseboard_fab2_lib.baseboard_fab2(sch_1):page137_i69@mstr_discrete.res(chips)!RES_0402-1.00K,1%,1/16W,CHIP,GA!!!F1484!B!!!!
S!XDP_CPU_TRST_N!R6T5!1!@baseboard_fab2_lib.baseboard_fab2(sch_1):page112_i62@mstr_discrete.res(chips)!RES_0402-1.00K,1%,1/16W,CHIP,GA!!!F1488!A!!!!
S!GND!R6T5!2!@baseboard_fab2_lib.baseboard_fab2(sch_1):page112_i62@mstr_discrete.res(chips)!RES_0402-1.00K,1%,1/16W,CHIP,GA!!!F1488!B!!!!
S!PD_ME_RCVR_N!R7G28!1!@baseboard_fab2_lib.baseboard_fab2(sch_1):page136_i102@mstr_discrete.res(chips)!RES_0402-1.00K,1%,1/16W,CHIP,GA!!!F1519!A!!!!
S!GND!R7G28!2!@baseboard_fab2_lib.baseboard_fab2(sch_1):page136_i102@mstr_discrete.res(chips)!RES_0402-1.00K,1%,1/16W,CHIP,GA!!!F1519!B!!!!
S!A_P12V_STBY_SCALED!R1U33!1!@baseboard_fab2_lib.baseboard_fab2(sch_1):page169_i83@mstr_discrete.res(chips)!RES_0402-1.00K,1%,1/16W,CHIP,GA!!!F1541!A!!!!
S!GND!R1U33!2!@baseboard_fab2_lib.baseboard_fab2(sch_1):page169_i83@mstr_discrete.res(chips)!RES_0402-1.00K,1%,1/16W,CHIP,GA!!!F1541!B!!!!
S!P3V3_STBY!R1L36!1!@baseboard_fab2_lib.baseboard_fab2(sch_1):page168_i11@mstr_discrete.res(chips)!RES_0402-1.00K,1%,1/16W,CHIP,GA!!!F1550!A!!!!
S!FM_DB_PRESENT!R1L36!2!@baseboard_fab2_lib.baseboard_fab2(sch_1):page168_i11@mstr_discrete.res(chips)!RES_0402-1.00K,1%,1/16W,CHIP,GA!!!F1550!B!!!!
S!P3V3_STBY!R1L38!1!@baseboard_fab2_lib.baseboard_fab2(sch_1):page168_i22@mstr_discrete.res(chips)!RES_0402-1.00K,1%,1/16W,CHIP,GA!!!F1549!A!!!!
S!FM_POST_CARD_PRES_BMC_N!R1L38!2!@baseboard_fab2_lib.baseboard_fab2(sch_1):page168_i22@mstr_discrete.res(chips)!RES_0402-1.00K,1%,1/16W,CHIP,GA!!!F1549!B!!!!
S!P3V3_STBY!R1L5!1!@baseboard_fab2_lib.baseboard_fab2(sch_1):page168_i10@mstr_discrete.res(chips)!RES_0402-1.00K,1%,1/16W,CHIP,GA!!!F1553!A!!!!
S!FM_SOL_UART_CH_SEL!R1L5!2!@baseboard_fab2_lib.baseboard_fab2(sch_1):page168_i10@mstr_discrete.res(chips)!RES_0402-1.00K,1%,1/16W,CHIP,GA!!!F1553!B!!!!
S!PD_SATA2_CONTROLLER_TYPE!R1L3!1!@baseboard_fab2_lib.baseboard_fab2(sch_1):page174_i5@mstr_discrete.res(chips)!RES_0402-1.00K,1%,1/16W,CHIP,GA!!!F1554!A!!!!
S!GND!R1L3!2!@baseboard_fab2_lib.baseboard_fab2(sch_1):page174_i5@mstr_discrete.res(chips)!RES_0402-1.00K,1%,1/16W,CHIP,GA!!!F1554!B!!!!
S!P3V3_STBY!R2R5!1!@baseboard_fab2_lib.baseboard_fab2(sch_1):page133_i258@mstr_discrete.res(chips)!RES_0402-1.00K,1%,1/16W,CHIP,GA!!!F1535!A!!!!
S!FM_PCH_PLD_DATA!R2R5!2!@baseboard_fab2_lib.baseboard_fab2(sch_1):page133_i258@mstr_discrete.res(chips)!RES_0402-1.00K,1%,1/16W,CHIP,GA!!!F1535!B!!!!
S!XDP_TRST_N!R8B2!1!@baseboard_fab2_lib.baseboard_fab2(sch_1):page112_i94@mstr_discrete.res(chips)!RES_0402-1.00K,1%,1/16W,CHIP,GA!!!F1470!A!!!!
S!GND!R8B2!2!@baseboard_fab2_lib.baseboard_fab2(sch_1):page112_i94@mstr_discrete.res(chips)!RES_0402-1.00K,1%,1/16W,CHIP,GA!!!F1470!B!!!!
S!XDP_PCH_CPU_TCK0!R3M10!1!@baseboard_fab2_lib.baseboard_fab2(sch_1):page112_i85@mstr_discrete.res(chips)!RES_0402-1.00K,1%,1/16W,CHIP,GA!!!F1528!A!!!!
S!GND!R3M10!2!@baseboard_fab2_lib.baseboard_fab2(sch_1):page112_i85@mstr_discrete.res(chips)!RES_0402-1.00K,1%,1/16W,CHIP,GA!!!F1528!B!!!!
S!P3V3_STBY!R3P18!1!@baseboard_fab2_lib.baseboard_fab2(sch_1):page211_i64@mstr_discrete.res(chips)!RES_0402-1.00K,1%,1/16W,CHIP,GA!!!F1521!A!!!!
S!IRQ_PVCCIO_CPU0_VRHOT_N!R3P18!2!@baseboard_fab2_lib.baseboard_fab2(sch_1):page211_i64@mstr_discrete.res(chips)!RES_0402-1.00K,1%,1/16W,CHIP,GA!!!F1521!B!!!!
S!P3V3_STBY!R4D49!1!@baseboard_fab2_lib.baseboard_fab2(sch_1):page213_i63@mstr_discrete.res(chips)!RES_0402-1.00K,1%,1/16W,CHIP,GA!!!F1509!A!!!!
S!IRQ_PVCCIO_CPU1_VRHOT_N!R4D49!2!@baseboard_fab2_lib.baseboard_fab2(sch_1):page213_i63@mstr_discrete.res(chips)!RES_0402-1.00K,1%,1/16W,CHIP,GA!!!F1509!B!!!!
S!P3V3_STBY!R8A5!1!@baseboard_fab2_lib.baseboard_fab2(sch_1):page235_i216@mstr_discrete.res(chips)!RES_0402-1.00K,1%,1/16W,CHIP,GA!!!F1472!A!!!!
S!IRQ_PVNN_PCH_VRHOT_N!R8A5!2!@baseboard_fab2_lib.baseboard_fab2(sch_1):page235_i216@mstr_discrete.res(chips)!RES_0402-1.00K,1%,1/16W,CHIP,GA!!!F1472!B!!!!
S!P3V3_STBY!R7B4!1!@baseboard_fab2_lib.baseboard_fab2(sch_1):page218_i17@mstr_discrete.res(chips)!RES_0402-1.00K,1%,1/16W,CHIP,GA!!!F1487!A!!!!
S!IRQ_PVDDQ_DEF_VRHOT_LVT3_R_N!R7B4!2!@baseboard_fab2_lib.baseboard_fab2(sch_1):page218_i17@mstr_discrete.res(chips)!RES_0402-1.00K,1%,1/16W,CHIP,GA!!!F1487!B!!!!
S!P3V3_STBY!R1G11!1!@baseboard_fab2_lib.baseboard_fab2(sch_1):page223_i79@mstr_discrete.res(chips)!RES_0402-1.00K,1%,1/16W,CHIP,GA!!!F1558!A!!!!
S!IRQ_PVDDQ_GHJ_VRHOT_LVT3_R_N!R1G11!2!@baseboard_fab2_lib.baseboard_fab2(sch_1):page223_i79@mstr_discrete.res(chips)!RES_0402-1.00K,1%,1/16W,CHIP,GA!!!F1558!B!!!!
S!P3V3_STBY!R1B1!1!@baseboard_fab2_lib.baseboard_fab2(sch_1):page226_i79@mstr_discrete.res(chips)!RES_0402-1.00K,1%,1/16W,CHIP,GA!!!F1570!A!!!!
S!IRQ_PVDDQ_KLM_VRHOT_LVT3_R_N!R1B1!2!@baseboard_fab2_lib.baseboard_fab2(sch_1):page226_i79@mstr_discrete.res(chips)!RES_0402-1.00K,1%,1/16W,CHIP,GA!!!F1570!B!!!!
S!P3V3_STBY!R7F27!1!@baseboard_fab2_lib.baseboard_fab2(sch_1):page215_i303@mstr_discrete.res(chips)!RES_0402-1.00K,1%,1/16W,CHIP,GA!!!F1473!A!!!!
S!IRQ_PVDDQ_ABC_VRHOT_LVT3_R_N!R7F27!2!@baseboard_fab2_lib.baseboard_fab2(sch_1):page215_i303@mstr_discrete.res(chips)!RES_0402-1.00K,1%,1/16W,CHIP,GA!!!F1473!B!!!!
S!P3V3_STBY!R8A6!1!@baseboard_fab2_lib.baseboard_fab2(sch_1):page235_i149@mstr_discrete.res(chips)!RES_0402-1.00K,1%,1/16W,CHIP,GA!!!F1471!A!!!!
S!PWRGD_PVNN_PCH_R!R8A6!2!@baseboard_fab2_lib.baseboard_fab2(sch_1):page235_i149@mstr_discrete.res(chips)!RES_0402-1.00K,1%,1/16W,CHIP,GA!!!F1471!B!!!!
S!FM_BOARD_SKU_ID3!R1U15!1!@baseboard_fab2_lib.baseboard_fab2(sch_1):page164_i22@mstr_discrete.res(chips)!RES_0402-1.00K,1%,1/16W,CHIP,GA!!!F1544!A!!!!
S!GND!R1U15!2!@baseboard_fab2_lib.baseboard_fab2(sch_1):page164_i22@mstr_discrete.res(chips)!RES_0402-1.00K,1%,1/16W,CHIP,GA!!!F1544!B!!!!
S!FM_BOARD_REV_ID2!R1T11!1!@baseboard_fab2_lib.baseboard_fab2(sch_1):page164_i7@mstr_discrete.res(chips)!RES_0402-1.00K,1%,1/16W,CHIP,GA!!!F1548!A!!!!
S!GND!R1T11!2!@baseboard_fab2_lib.baseboard_fab2(sch_1):page164_i7@mstr_discrete.res(chips)!RES_0402-1.00K,1%,1/16W,CHIP,GA!!!F1548!B!!!!
S!FM_BOARD_SKU_ID1!R1U16!1!@baseboard_fab2_lib.baseboard_fab2(sch_1):page164_i20@mstr_discrete.res(chips)!RES_0402-1.00K,1%,1/16W,CHIP,GA!!!F1543!A!!!!
S!GND!R1U16!2!@baseboard_fab2_lib.baseboard_fab2(sch_1):page164_i20@mstr_discrete.res(chips)!RES_0402-1.00K,1%,1/16W,CHIP,GA!!!F1543!B!!!!
S!FM_BOARD_REV_ID1!R1T12!1!@baseboard_fab2_lib.baseboard_fab2(sch_1):page164_i6@mstr_discrete.res(chips)!RES_0402-1.00K,1%,1/16W,CHIP,GA!!!F1547!A!!!!
S!GND!R1T12!2!@baseboard_fab2_lib.baseboard_fab2(sch_1):page164_i6@mstr_discrete.res(chips)!RES_0402-1.00K,1%,1/16W,CHIP,GA!!!F1547!B!!!!
S!PD_DIR_2!R1U30!1!@baseboard_fab2_lib.baseboard_fab2(sch_1):page152_i2@mstr_discrete.res(chips)!RES_0402-1.00K,1%,1/16W,CHIP,GA!!!F1542!A!!!!
S!GND!R1U30!2!@baseboard_fab2_lib.baseboard_fab2(sch_1):page152_i2@mstr_discrete.res(chips)!RES_0402-1.00K,1%,1/16W,CHIP,GA!!!F1542!B!!!!
S!P3V3_STBY!R3P25!1!@baseboard_fab2_lib.baseboard_fab2(sch_1):page211_i56@mstr_discrete.res(chips)!RES_0402-1.00K,1%,1/16W,CHIP,GA!!!F1520!A!!!!
S!PWRGD_PVCCIO_CPU0_R!R3P25!2!@baseboard_fab2_lib.baseboard_fab2(sch_1):page211_i56@mstr_discrete.res(chips)!RES_0402-1.00K,1%,1/16W,CHIP,GA!!!F1520!B!!!!
S!P3V3_STBY!R4D42!1!@baseboard_fab2_lib.baseboard_fab2(sch_1):page213_i15@mstr_discrete.res(chips)!RES_0402-1.00K,1%,1/16W,CHIP,GA!!!F1510!A!!!!
S!PWRGD_PVCCIO_CPU1_R!R4D42!2!@baseboard_fab2_lib.baseboard_fab2(sch_1):page213_i15@mstr_discrete.res(chips)!RES_0402-1.00K,1%,1/16W,CHIP,GA!!!F1510!B!!!!
S!GND!R3P32!1!@baseboard_fab2_lib.baseboard_fab2(sch_1):page96_i71@mstr_discrete.res(chips)!RES_0402-1.00K,1%,1/16W,CHIP,GA!!!F1518!A!!!!
S!PD_GTL2014_1_VREF!R3P32!2!@baseboard_fab2_lib.baseboard_fab2(sch_1):page96_i71@mstr_discrete.res(chips)!RES_0402-1.00K,1%,1/16W,CHIP,GA!!!F1518!B!!!!
S!GND!R4C9!1!@baseboard_fab2_lib.baseboard_fab2(sch_1):page96_i69@mstr_discrete.res(chips)!RES_0402-1.00K,1%,1/16W,CHIP,GA!!!F1511!A!!!!
S!PD_GTL2014_2_VREF!R4C9!2!@baseboard_fab2_lib.baseboard_fab2(sch_1):page96_i69@mstr_discrete.res(chips)!RES_0402-1.00K,1%,1/16W,CHIP,GA!!!F1511!B!!!!
S!P3V3_STBY!R9B6!1!@baseboard_fab2_lib.baseboard_fab2(sch_1):page167_i35@mstr_discrete.res(chips)!RES_0402-1.00K,1%,1/16W,CHIP,GA!!!F1454!A!!!!
S!PU_TMP421_1_A1!R9B6!2!@baseboard_fab2_lib.baseboard_fab2(sch_1):page167_i35@mstr_discrete.res(chips)!RES_0402-1.00K,1%,1/16W,CHIP,GA!!!F1454!B!!!!
S!PD_FRU_WP!R8D27!1!@baseboard_fab2_lib.baseboard_fab2(sch_1):page167_i50@mstr_discrete.res(chips)!RES_0402-1.00K,1%,1/16W,CHIP,GA!!!F1462!A!!!!
S!GND!R8D27!2!@baseboard_fab2_lib.baseboard_fab2(sch_1):page167_i50@mstr_discrete.res(chips)!RES_0402-1.00K,1%,1/16W,CHIP,GA!!!F1462!B!!!!
S!PD_TMP421_1_A0!R9B8!1!@baseboard_fab2_lib.baseboard_fab2(sch_1):page167_i10@mstr_discrete.res(chips)!RES_0402-1.00K,1%,1/16W,CHIP,GA!!!F1453!A!!!!
S!GND!R9B8!2!@baseboard_fab2_lib.baseboard_fab2(sch_1):page167_i10@mstr_discrete.res(chips)!RES_0402-1.00K,1%,1/16W,CHIP,GA!!!F1453!B!!!!
S!P3V3_STBY!R8C18!1!@baseboard_fab2_lib.baseboard_fab2(sch_1):page125_i40@mstr_discrete.res(chips)!RES_0402-1.00K,1%,1/16W,CHIP,GA!!!F1465!A!!!!
S!PU_PCH_TLS_ENABLE_STRAP!R8C18!2!@baseboard_fab2_lib.baseboard_fab2(sch_1):page125_i40@mstr_discrete.res(chips)!RES_0402-1.00K,1%,1/16W,CHIP,GA!!!F1465!B!!!!
S!SPI_PCH_IO3!R2T1!1!@baseboard_fab2_lib.baseboard_fab2(sch_1):page125_i15@mstr_discrete.res(chips)!RES_0402-1.00K,1%,1/16W,CHIP,GA!!!F1534!A!!!!
S!GND!R2T1!2!@baseboard_fab2_lib.baseboard_fab2(sch_1):page125_i15@mstr_discrete.res(chips)!RES_0402-1.00K,1%,1/16W,CHIP,GA!!!F1534!B!!!!
S!RMII_PCH_SPRNGVLLE_ARB_OUT!R7D1!1!@baseboard_fab2_lib.baseboard_fab2(sch_1):page125_i70@mstr_discrete.res(chips)!RES_0402-1.00K,1%,1/16W,CHIP,GA!!!F1482!A!!!!
S!GND!R7D1!2!@baseboard_fab2_lib.baseboard_fab2(sch_1):page125_i70@mstr_discrete.res(chips)!RES_0402-1.00K,1%,1/16W,CHIP,GA!!!F1482!B!!!!
S!P3V3_STBY!R1E10!1!@baseboard_fab2_lib.baseboard_fab2(sch_1):page167_i38@mstr_discrete.res(chips)!RES_0402-1.00K,1%,1/16W,CHIP,GA!!!F1563!A!!!!
S!PD_TMP421_2_A1!R1E10!2!@baseboard_fab2_lib.baseboard_fab2(sch_1):page167_i38@mstr_discrete.res(chips)!RES_0402-1.00K,1%,1/16W,CHIP,GA!!!F1563!B!!!!
S!P3V3_STBY!R7B5!1!@baseboard_fab2_lib.baseboard_fab2(sch_1):page218_i16@mstr_discrete.res(chips)!RES_0402-1.00K,1%,1/16W,CHIP,GA!!!F1486!A!!!!
S!PWRGD_PVDDQ_DEF_R!R7B5!2!@baseboard_fab2_lib.baseboard_fab2(sch_1):page218_i16@mstr_discrete.res(chips)!RES_0402-1.00K,1%,1/16W,CHIP,GA!!!F1486!B!!!!
S!P3V3_STBY!R1G16!1!@baseboard_fab2_lib.baseboard_fab2(sch_1):page223_i17@mstr_discrete.res(chips)!RES_0402-1.00K,1%,1/16W,CHIP,GA!!!F1556!A!!!!
S!PWRGD_PVDDQ_GHJ_R!R1G16!2!@baseboard_fab2_lib.baseboard_fab2(sch_1):page223_i17@mstr_discrete.res(chips)!RES_0402-1.00K,1%,1/16W,CHIP,GA!!!F1556!B!!!!
S!P3V3_STBY!R1B2!1!@baseboard_fab2_lib.baseboard_fab2(sch_1):page226_i17@mstr_discrete.res(chips)!RES_0402-1.00K,1%,1/16W,CHIP,GA!!!F1569!A!!!!
S!PWRGD_PVDDQ_KLM_R!R1B2!2!@baseboard_fab2_lib.baseboard_fab2(sch_1):page226_i17@mstr_discrete.res(chips)!RES_0402-1.00K,1%,1/16W,CHIP,GA!!!F1569!B!!!!
S!P5V_STBY!R7E12!1!@baseboard_fab2_lib.baseboard_fab2(sch_1):page241_i11@mstr_discrete.res(chips)!RES_0402-1.00K,1%,1/16W,CHIP,GA!!!F1476!A!!!!
S!PWRGD_P5V_STBY_R!R7E12!2!@baseboard_fab2_lib.baseboard_fab2(sch_1):page241_i11@mstr_discrete.res(chips)!RES_0402-1.00K,1%,1/16W,CHIP,GA!!!F1476!B!!!!
S!PD_GTL2104_4_DIR!R2T50!1!@baseboard_fab2_lib.baseboard_fab2(sch_1):page93_i127@mstr_discrete.res(chips)!RES_0402-1.00K,1%,1/16W,CHIP,GA!!!F1530!A!!!!
S!GND!R2T50!2!@baseboard_fab2_lib.baseboard_fab2(sch_1):page93_i127@mstr_discrete.res(chips)!RES_0402-1.00K,1%,1/16W,CHIP,GA!!!F1530!B!!!!
S!PD_CKMNG_OE!R2T25!1!@baseboard_fab2_lib.baseboard_fab2(sch_1):page101_i48@mstr_discrete.res(chips)!RES_0402-1.00K,1%,1/16W,CHIP,GA!!!F1531!A!!!!
S!GND!R2T25!2!@baseboard_fab2_lib.baseboard_fab2(sch_1):page101_i48@mstr_discrete.res(chips)!RES_0402-1.00K,1%,1/16W,CHIP,GA!!!F1531!B!!!!
S!PVDDQ_GHJ!R1G2!1!@baseboard_fab2_lib.baseboard_fab2(sch_1):page100_i19@mstr_discrete.res(chips)!RES_0402-1.00K,1%,1/16W,CHIP,GA!!!F1560!A!!!!
S!M_H_VREF!R1G2!2!@baseboard_fab2_lib.baseboard_fab2(sch_1):page100_i19@mstr_discrete.res(chips)!RES_0402-1.00K,1%,1/16W,CHIP,GA!!!F1560!B!!!!
S!PVDDQ_GHJ!R1G15!1!@baseboard_fab2_lib.baseboard_fab2(sch_1):page100_i35@mstr_discrete.res(chips)!RES_0402-1.00K,1%,1/16W,CHIP,GA!!!F1557!A!!!!
S!M_J_VREF!R1G15!2!@baseboard_fab2_lib.baseboard_fab2(sch_1):page100_i35@mstr_discrete.res(chips)!RES_0402-1.00K,1%,1/16W,CHIP,GA!!!F1557!B!!!!
S!PVDDQ_KLM!R9L7!1!@baseboard_fab2_lib.baseboard_fab2(sch_1):page100_i22@mstr_discrete.res(chips)!RES_0402-1.00K,1%,1/16W,CHIP,GA!!!F1447!A!!!!
S!M_L_VREF!R9L7!2!@baseboard_fab2_lib.baseboard_fab2(sch_1):page100_i22@mstr_discrete.res(chips)!RES_0402-1.00K,1%,1/16W,CHIP,GA!!!F1447!B!!!!
S!PVDDQ_KLM!R9L2!1!@baseboard_fab2_lib.baseboard_fab2(sch_1):page100_i38@mstr_discrete.res(chips)!RES_0402-1.00K,1%,1/16W,CHIP,GA!!!F1449!A!!!!
S!M_M_VREF!R9L2!2!@baseboard_fab2_lib.baseboard_fab2(sch_1):page100_i38@mstr_discrete.res(chips)!RES_0402-1.00K,1%,1/16W,CHIP,GA!!!F1449!B!!!!
S!M_H_VREF!R1G3!1!@baseboard_fab2_lib.baseboard_fab2(sch_1):page100_i20@mstr_discrete.res(chips)!RES_0402-1.00K,1%,1/16W,CHIP,GA!!!F1559!A!!!!
S!GND!R1G3!2!@baseboard_fab2_lib.baseboard_fab2(sch_1):page100_i20@mstr_discrete.res(chips)!RES_0402-1.00K,1%,1/16W,CHIP,GA!!!F1559!B!!!!
S!M_J_VREF!R1G17!1!@baseboard_fab2_lib.baseboard_fab2(sch_1):page100_i36@mstr_discrete.res(chips)!RES_0402-1.00K,1%,1/16W,CHIP,GA!!!F1555!A!!!!
S!GND!R1G17!2!@baseboard_fab2_lib.baseboard_fab2(sch_1):page100_i36@mstr_discrete.res(chips)!RES_0402-1.00K,1%,1/16W,CHIP,GA!!!F1555!B!!!!
S!M_L_VREF!R9L6!1!@baseboard_fab2_lib.baseboard_fab2(sch_1):page100_i24@mstr_discrete.res(chips)!RES_0402-1.00K,1%,1/16W,CHIP,GA!!!F1448!A!!!!
S!GND!R9L6!2!@baseboard_fab2_lib.baseboard_fab2(sch_1):page100_i24@mstr_discrete.res(chips)!RES_0402-1.00K,1%,1/16W,CHIP,GA!!!F1448!B!!!!
S!M_M_VREF!R9L1!1!@baseboard_fab2_lib.baseboard_fab2(sch_1):page100_i40@mstr_discrete.res(chips)!RES_0402-1.00K,1%,1/16W,CHIP,GA!!!F1450!A!!!!
S!GND!R9L1!2!@baseboard_fab2_lib.baseboard_fab2(sch_1):page100_i40@mstr_discrete.res(chips)!RES_0402-1.00K,1%,1/16W,CHIP,GA!!!F1450!B!!!!
S!PVDDQ_DEF!R6L13!1!@baseboard_fab2_lib.baseboard_fab2(sch_1):page98_i54@mstr_discrete.res(chips)!RES_0402-1.00K,1%,1/16W,CHIP,GA!!!F1494!A!!!!
S!M_E_VREF!R6L13!2!@baseboard_fab2_lib.baseboard_fab2(sch_1):page98_i54@mstr_discrete.res(chips)!RES_0402-1.00K,1%,1/16W,CHIP,GA!!!F1494!B!!!!
S!PVDDQ_ABC!R4G2!1!@baseboard_fab2_lib.baseboard_fab2(sch_1):page98_i38@mstr_discrete.res(chips)!RES_0402-1.00K,1%,1/16W,CHIP,GA!!!F1503!A!!!!
S!M_B_VREF!R4G2!2!@baseboard_fab2_lib.baseboard_fab2(sch_1):page98_i38@mstr_discrete.res(chips)!RES_0402-1.00K,1%,1/16W,CHIP,GA!!!F1503!B!!!!
S!PVDDQ_ABC!R4G21!1!@baseboard_fab2_lib.baseboard_fab2(sch_1):page98_i46@mstr_discrete.res(chips)!RES_0402-1.00K,1%,1/16W,CHIP,GA!!!F1500!A!!!!
S!M_C_VREF!R4G21!2!@baseboard_fab2_lib.baseboard_fab2(sch_1):page98_i46@mstr_discrete.res(chips)!RES_0402-1.00K,1%,1/16W,CHIP,GA!!!F1500!B!!!!
S!PVDDQ_DEF!R6L2!1!@baseboard_fab2_lib.baseboard_fab2(sch_1):page98_i62@mstr_discrete.res(chips)!RES_0402-1.00K,1%,1/16W,CHIP,GA!!!F1496!A!!!!
S!M_F_VREF!R6L2!2!@baseboard_fab2_lib.baseboard_fab2(sch_1):page98_i62@mstr_discrete.res(chips)!RES_0402-1.00K,1%,1/16W,CHIP,GA!!!F1496!B!!!!
S!M_E_VREF!R6L12!1!@baseboard_fab2_lib.baseboard_fab2(sch_1):page98_i56@mstr_discrete.res(chips)!RES_0402-1.00K,1%,1/16W,CHIP,GA!!!F1495!A!!!!
S!GND!R6L12!2!@baseboard_fab2_lib.baseboard_fab2(sch_1):page98_i56@mstr_discrete.res(chips)!RES_0402-1.00K,1%,1/16W,CHIP,GA!!!F1495!B!!!!
S!M_B_VREF!R4G3!1!@baseboard_fab2_lib.baseboard_fab2(sch_1):page98_i40@mstr_discrete.res(chips)!RES_0402-1.00K,1%,1/16W,CHIP,GA!!!F1502!A!!!!
S!GND!R4G3!2!@baseboard_fab2_lib.baseboard_fab2(sch_1):page98_i40@mstr_discrete.res(chips)!RES_0402-1.00K,1%,1/16W,CHIP,GA!!!F1502!B!!!!
S!M_C_VREF!R4G22!1!@baseboard_fab2_lib.baseboard_fab2(sch_1):page98_i48@mstr_discrete.res(chips)!RES_0402-1.00K,1%,1/16W,CHIP,GA!!!F1499!A!!!!
S!GND!R4G22!2!@baseboard_fab2_lib.baseboard_fab2(sch_1):page98_i48@mstr_discrete.res(chips)!RES_0402-1.00K,1%,1/16W,CHIP,GA!!!F1499!B!!!!
S!M_F_VREF!R6L1!1!@baseboard_fab2_lib.baseboard_fab2(sch_1):page98_i64@mstr_discrete.res(chips)!RES_0402-1.00K,1%,1/16W,CHIP,GA!!!F1497!A!!!!
S!GND!R6L1!2!@baseboard_fab2_lib.baseboard_fab2(sch_1):page98_i64@mstr_discrete.res(chips)!RES_0402-1.00K,1%,1/16W,CHIP,GA!!!F1497!B!!!!
S!P3V3_STBY!R3P36!1!@baseboard_fab2_lib.baseboard_fab2(sch_1):page96_i36@mstr_discrete.res(chips)!RES_0402-1.00K,1%,1/16W,CHIP,GA!!!F1517!A!!!!
S!PU_GTL2014_1_DIR!R3P36!2!@baseboard_fab2_lib.baseboard_fab2(sch_1):page96_i36@mstr_discrete.res(chips)!RES_0402-1.00K,1%,1/16W,CHIP,GA!!!F1517!B!!!!
S!P3V3_STBY!R4C8!1!@baseboard_fab2_lib.baseboard_fab2(sch_1):page96_i55@mstr_discrete.res(chips)!RES_0402-1.00K,1%,1/16W,CHIP,GA!!!F1512!A!!!!
S!PU_GTL2014_2_DIR!R4C8!2!@baseboard_fab2_lib.baseboard_fab2(sch_1):page96_i55@mstr_discrete.res(chips)!RES_0402-1.00K,1%,1/16W,CHIP,GA!!!F1512!B!!!!
S!XDP_ITP_PMODE!R9A17!1!@baseboard_fab2_lib.baseboard_fab2(sch_1):page111_i57@mstr_discrete.res(chips)!RES_0402-1.00K,1%,1/16W,CHIP,GA!!!F1455!A!!!!
S!P1V05_PCH_STBY!R9A17!2!@baseboard_fab2_lib.baseboard_fab2(sch_1):page111_i57@mstr_discrete.res(chips)!RES_0402-1.00K,1%,1/16W,CHIP,GA!!!F1455!B!!!!
S!RST_RSMRST_N!R9A15!1!@baseboard_fab2_lib.baseboard_fab2(sch_1):page111_i60@mstr_discrete.res(chips)!RES_0402-1.00K,1%,1/16W,CHIP,GA!!!F1456!A!!!!
S!XDP_RSMRST_N!R9A15!2!@baseboard_fab2_lib.baseboard_fab2(sch_1):page111_i60@mstr_discrete.res(chips)!RES_0402-1.00K,1%,1/16W,CHIP,GA!!!F1456!B!!!!
S!SPI_PCH_IO2!R2P2!1!@baseboard_fab2_lib.baseboard_fab2(sch_1):page111_i37@mstr_discrete.res(chips)!RES_0402-1.00K,1%,1/16W,CHIP,GA!!!F1536!A!!!!
S!XDP_DEBUG_CONSENT_N!R2P2!2!@baseboard_fab2_lib.baseboard_fab2(sch_1):page111_i37@mstr_discrete.res(chips)!RES_0402-1.00K,1%,1/16W,CHIP,GA!!!F1536!B!!!!
S!PVDDQ_ABC!R4F4!1!@baseboard_fab2_lib.baseboard_fab2(sch_1):page98_i36@mstr_discrete.res(chips)!RES_0402-1.00K,1%,1/16W,CHIP,GA!!!F1505!A!!!!
S!M_A_VREF!R4F4!2!@baseboard_fab2_lib.baseboard_fab2(sch_1):page98_i36@mstr_discrete.res(chips)!RES_0402-1.00K,1%,1/16W,CHIP,GA!!!F1505!B!!!!
S!PVDDQ_KLM!R9M1!1!@baseboard_fab2_lib.baseboard_fab2(sch_1):page100_i11@mstr_discrete.res(chips)!RES_0402-1.00K,1%,1/16W,CHIP,GA!!!F1445!A!!!!
S!M_K_VREF!R9M1!2!@baseboard_fab2_lib.baseboard_fab2(sch_1):page100_i11@mstr_discrete.res(chips)!RES_0402-1.00K,1%,1/16W,CHIP,GA!!!F1445!B!!!!
S!PVDDQ_GHJ!R1F5!1!@baseboard_fab2_lib.baseboard_fab2(sch_1):page100_i6@mstr_discrete.res(chips)!RES_0402-1.00K,1%,1/16W,CHIP,GA!!!F1562!A!!!!
S!M_G_VREF!R1F5!2!@baseboard_fab2_lib.baseboard_fab2(sch_1):page100_i6@mstr_discrete.res(chips)!RES_0402-1.00K,1%,1/16W,CHIP,GA!!!F1562!B!!!!
S!PVDDQ_DEF!R6M1!1!@baseboard_fab2_lib.baseboard_fab2(sch_1):page98_i9@mstr_discrete.res(chips)!RES_0402-1.00K,1%,1/16W,CHIP,GA!!!F1492!A!!!!
S!M_D_VREF!R6M1!2!@baseboard_fab2_lib.baseboard_fab2(sch_1):page98_i9@mstr_discrete.res(chips)!RES_0402-1.00K,1%,1/16W,CHIP,GA!!!F1492!B!!!!
S!XDP_SYSPWROK!R1L13!1!@baseboard_fab2_lib.baseboard_fab2(sch_1):page111_i6@mstr_discrete.res(chips)!RES_0402-1.00K,1%,1/16W,CHIP,GA!!!F1552!A!!!!
S!P3V3_STBY!R1L13!2!@baseboard_fab2_lib.baseboard_fab2(sch_1):page111_i6@mstr_discrete.res(chips)!RES_0402-1.00K,1%,1/16W,CHIP,GA!!!F1552!B!!!!
S!XDP_RST_CO_N!R9A14!1!@baseboard_fab2_lib.baseboard_fab2(sch_1):page111_i11@mstr_discrete.res(chips)!RES_0402-1.00K,1%,1/16W,CHIP,GA!!!F1457!A!!!!
S!P3V3_STBY!R9A14!2!@baseboard_fab2_lib.baseboard_fab2(sch_1):page111_i11@mstr_discrete.res(chips)!RES_0402-1.00K,1%,1/16W,CHIP,GA!!!F1457!B!!!!
S!XDP_PWRGD_RST_N!R1L23!1!@baseboard_fab2_lib.baseboard_fab2(sch_1):page111_i13@mstr_discrete.res(chips)!RES_0402-1.00K,1%,1/16W,CHIP,GA!!!F1551!A!!!!
S!P3V3_STBY!R1L23!2!@baseboard_fab2_lib.baseboard_fab2(sch_1):page111_i13@mstr_discrete.res(chips)!RES_0402-1.00K,1%,1/16W,CHIP,GA!!!F1551!B!!!!
S!P3V_BAT_SOURCE!R2U43!1!@baseboard_fab2_lib.baseboard_fab2(sch_1):page196_i46@mstr_discrete.res(chips)!RES_0402-1.00K,1%,1/16W,CHIP,GA!!!F1529!A!!!!
S!A_P3V_BAT_R!R2U43!2!@baseboard_fab2_lib.baseboard_fab2(sch_1):page196_i46@mstr_discrete.res(chips)!RES_0402-1.00K,1%,1/16W,CHIP,GA!!!F1529!B!!!!
S!P1V538_BMC_STBY!R1T30!1!@baseboard_fab2_lib.baseboard_fab2(sch_1):page151_i60@mstr_discrete.res(chips)!RES_0402-1.00K,1%,1/16W,CHIP,GA!!!F1545!A!!!!
S!M_BMC_DDR3_MVREF!R1T30!2!@baseboard_fab2_lib.baseboard_fab2(sch_1):page151_i60@mstr_discrete.res(chips)!RES_0402-1.00K,1%,1/16W,CHIP,GA!!!F1545!B!!!!
S!M_BMC_DDR3_MVREF!R1T29!1!@baseboard_fab2_lib.baseboard_fab2(sch_1):page151_i61@mstr_discrete.res(chips)!RES_0402-1.00K,1%,1/16W,CHIP,GA!!!F1546!A!!!!
S!GND!R1T29!2!@baseboard_fab2_lib.baseboard_fab2(sch_1):page151_i61@mstr_discrete.res(chips)!RES_0402-1.00K,1%,1/16W,CHIP,GA!!!F1546!B!!!!
S!PD_PASSWORD_CLEAR!R7G29!1!@baseboard_fab2_lib.baseboard_fab2(sch_1):page136_i148@mstr_discrete.res(chips)!RES_0402-1.00K,1%,1/16W,CHIP,GA!!!F1466!A!!!!
S!GND!R7G29!2!@baseboard_fab2_lib.baseboard_fab2(sch_1):page136_i148@mstr_discrete.res(chips)!RES_0402-1.00K,1%,1/16W,CHIP,GA!!!F1466!B!!!!
S!P3V3_STBY!R7G31!1!@baseboard_fab2_lib.baseboard_fab2(sch_1):page136_i139@mstr_discrete.res(chips)!RES_0402-1.00K,1%,1/16W,CHIP,GA!!!F1459!A!!!!
S!PU_BIOS_RECOVER_BOOT!R7G31!2!@baseboard_fab2_lib.baseboard_fab2(sch_1):page136_i139@mstr_discrete.res(chips)!RES_0402-1.00K,1%,1/16W,CHIP,GA!!!F1459!B!!!!
S!PD_RST_RTCRST_N!R1U63!1!@baseboard_fab2_lib.baseboard_fab2(sch_1):page137_i15@mstr_discrete.res(chips)!RES_0402-1.00K,1%,1/16W,CHIP,GA!!!F1483!A!!!!
S!GND!R1U63!2!@baseboard_fab2_lib.baseboard_fab2(sch_1):page137_i15@mstr_discrete.res(chips)!RES_0402-1.00K,1%,1/16W,CHIP,GA!!!F1483!B!!!!
S!M_G_VREF!R1F6!1!@baseboard_fab2_lib.baseboard_fab2(sch_1):page100_i2@mstr_discrete.res(chips)!RES_0402-1.00K,1%,1/16W,CHIP,GA!!!F1561!A!!!!
S!GND!R1F6!2!@baseboard_fab2_lib.baseboard_fab2(sch_1):page100_i2@mstr_discrete.res(chips)!RES_0402-1.00K,1%,1/16W,CHIP,GA!!!F1561!B!!!!
S!M_A_VREF!R4F5!1!@baseboard_fab2_lib.baseboard_fab2(sch_1):page98_i4@mstr_discrete.res(chips)!RES_0402-1.00K,1%,1/16W,CHIP,GA!!!F1504!A!!!!
S!GND!R4F5!2!@baseboard_fab2_lib.baseboard_fab2(sch_1):page98_i4@mstr_discrete.res(chips)!RES_0402-1.00K,1%,1/16W,CHIP,GA!!!F1504!B!!!!
S!M_D_VREF!R6L16!1!@baseboard_fab2_lib.baseboard_fab2(sch_1):page98_i12@mstr_discrete.res(chips)!RES_0402-1.00K,1%,1/16W,CHIP,GA!!!F1493!A!!!!
S!GND!R6L16!2!@baseboard_fab2_lib.baseboard_fab2(sch_1):page98_i12@mstr_discrete.res(chips)!RES_0402-1.00K,1%,1/16W,CHIP,GA!!!F1493!B!!!!
S!M_K_VREF!R9L11!1!@baseboard_fab2_lib.baseboard_fab2(sch_1):page100_i4@mstr_discrete.res(chips)!RES_0402-1.00K,1%,1/16W,CHIP,GA!!!F1446!A!!!!
S!GND!R9L11!2!@baseboard_fab2_lib.baseboard_fab2(sch_1):page100_i4@mstr_discrete.res(chips)!RES_0402-1.00K,1%,1/16W,CHIP,GA!!!F1446!B!!!!
S!P3V3_STBY!R7F22!1!@baseboard_fab2_lib.baseboard_fab2(sch_1):page215_i301@mstr_discrete.res(chips)!RES_0402-1.00K,1%,1/16W,CHIP,GA!!!F1474!A!!!!
S!PWRGD_PVDDQ_ABC_R!R7F22!2!@baseboard_fab2_lib.baseboard_fab2(sch_1):page215_i301@mstr_discrete.res(chips)!RES_0402-1.00K,1%,1/16W,CHIP,GA!!!F1474!B!!!!
S!P3V3_STBY!R4E5!1!@baseboard_fab2_lib.baseboard_fab2(sch_1):page201_i27@mstr_discrete.res(chips)!RES_0402-1.00K,1%,1/16W,CHIP,GA!!!F1506!A!!!!
S!PWRGD_PVSA_CPU0_R!R4E5!2!@baseboard_fab2_lib.baseboard_fab2(sch_1):page201_i27@mstr_discrete.res(chips)!RES_0402-1.00K,1%,1/16W,CHIP,GA!!!F1506!B!!!!
S!P3V3_STBY!R4D58!1!@baseboard_fab2_lib.baseboard_fab2(sch_1):page201_i25@mstr_discrete.res(chips)!RES_0402-1.00K,1%,1/16W,CHIP,GA!!!F1508!A!!!!
S!VR_VRRDY_PVCCIN_CPU0!R4D58!2!@baseboard_fab2_lib.baseboard_fab2(sch_1):page201_i25@mstr_discrete.res(chips)!RES_0402-1.00K,1%,1/16W,CHIP,GA!!!F1508!B!!!!
S!P3V3_STBY!R4E3!1!@baseboard_fab2_lib.baseboard_fab2(sch_1):page201_i111@mstr_discrete.res(chips)!RES_0402-1.00K,1%,1/16W,CHIP,GA!!!F1507!A!!!!
S!IRQ_PVCCIN_CPU0_VRHOT_LVC3_R_N!R4E3!2!@baseboard_fab2_lib.baseboard_fab2(sch_1):page201_i111@mstr_discrete.res(chips)!RES_0402-1.00K,1%,1/16W,CHIP,GA!!!F1507!B!!!!
S!P3V3_STBY!R1D8!1!@baseboard_fab2_lib.baseboard_fab2(sch_1):page206_i36@mstr_discrete.res(chips)!RES_0402-1.00K,1%,1/16W,CHIP,GA!!!F1566!A!!!!
S!PWRGD_PVSA_CPU1_R!R1D8!2!@baseboard_fab2_lib.baseboard_fab2(sch_1):page206_i36@mstr_discrete.res(chips)!RES_0402-1.00K,1%,1/16W,CHIP,GA!!!F1566!B!!!!
S!P3V3_STBY!R1C28!1!@baseboard_fab2_lib.baseboard_fab2(sch_1):page206_i35@mstr_discrete.res(chips)!RES_0402-1.00K,1%,1/16W,CHIP,GA!!!F1568!A!!!!
S!VR_VRRDY_PVCCIN_CPU1!R1C28!2!@baseboard_fab2_lib.baseboard_fab2(sch_1):page206_i35@mstr_discrete.res(chips)!RES_0402-1.00K,1%,1/16W,CHIP,GA!!!F1568!B!!!!
S!P3V3_STBY!R1D6!1!@baseboard_fab2_lib.baseboard_fab2(sch_1):page206_i6@mstr_discrete.res(chips)!RES_0402-1.00K,1%,1/16W,CHIP,GA!!!F1567!A!!!!
S!IRQ_PVCCIN_CPU1_VRHOT_LVC3_R_N!R1D6!2!@baseboard_fab2_lib.baseboard_fab2(sch_1):page206_i6@mstr_discrete.res(chips)!RES_0402-1.00K,1%,1/16W,CHIP,GA!!!F1567!B!!!!
S!P12V_STBY!R1D36!1!@baseboard_fab2_lib.baseboard_fab2(sch_1):page199_i65@mstr_discrete.res(chips)!RES_0402-1.00K,1%,1/16W,CHIP,GA!!!F1565!A!!!!
S!A_HSC_VOUT!R1D36!2!@baseboard_fab2_lib.baseboard_fab2(sch_1):page199_i65@mstr_discrete.res(chips)!RES_0402-1.00K,1%,1/16W,CHIP,GA!!!F1565!B!!!!
S!PD_GTL2104_DIR_0!R7D26!1!@baseboard_fab2_lib.baseboard_fab2(sch_1):page92_i54@mstr_discrete.res(chips)!RES_0402-1.00K,1%,1/16W,CHIP,GA!!!F1477!A!!!!
S!GND!R7D26!2!@baseboard_fab2_lib.baseboard_fab2(sch_1):page92_i54@mstr_discrete.res(chips)!RES_0402-1.00K,1%,1/16W,CHIP,GA!!!F1477!B!!!!
S!PD_GTL2104_DIR_1!R3R1!1!@baseboard_fab2_lib.baseboard_fab2(sch_1):page92_i46@mstr_discrete.res(chips)!RES_0402-1.00K,1%,1/16W,CHIP,GA!!!F1516!A!!!!
S!GND!R3R1!2!@baseboard_fab2_lib.baseboard_fab2(sch_1):page92_i46@mstr_discrete.res(chips)!RES_0402-1.00K,1%,1/16W,CHIP,GA!!!F1516!B!!!!
S!FM_CPLD_DBG_PWR_EN_N!R1L2!1!@baseboard_fab2_lib.baseboard_fab2(sch_1):page155_i186@mstr_discrete.res(chips)!RES_0402-10.0,1%,1/16W,CHIP,G2A!!!F1367!A!!!!
S!FM_CPLD_DBG_PWR_EN_R_N!R1L2!2!@baseboard_fab2_lib.baseboard_fab2(sch_1):page155_i186@mstr_discrete.res(chips)!RES_0402-10.0,1%,1/16W,CHIP,G2A!!!F1367!B!!!!
S!VSENSE_PVCCIN_CPU0_P!R4E8!1!@baseboard_fab2_lib.baseboard_fab2(sch_1):page201_i109@mstr_discrete.res(chips)!RES_0402-10.0,1%,1/16W,CHIP,G2A!!!F1352!A!!!!
S!VSENSE_PVCCIN_CPU0_AVSP!R4E8!2!@baseboard_fab2_lib.baseboard_fab2(sch_1):page201_i109@mstr_discrete.res(chips)!RES_0402-10.0,1%,1/16W,CHIP,G2A!!!F1352!B!!!!
S!VSENSE_PVSA_CPU0_P!R4D39!1!@baseboard_fab2_lib.baseboard_fab2(sch_1):page201_i110@mstr_discrete.res(chips)!RES_0402-10.0,1%,1/16W,CHIP,G2A!!!F1354!A!!!!
S!VSENSE_PVSA_CPU0_BVSP!R4D39!2!@baseboard_fab2_lib.baseboard_fab2(sch_1):page201_i110@mstr_discrete.res(chips)!RES_0402-10.0,1%,1/16W,CHIP,G2A!!!F1354!B!!!!
S!VSENSE_PVCCIN_CPU1_P!R1D4!1!@baseboard_fab2_lib.baseboard_fab2(sch_1):page206_i79@mstr_discrete.res(chips)!RES_0402-10.0,1%,1/16W,CHIP,G2A!!!F1374!A!!!!
S!VSENSE_PVCCIN_CPU1_AVSP!R1D4!2!@baseboard_fab2_lib.baseboard_fab2(sch_1):page206_i79@mstr_discrete.res(chips)!RES_0402-10.0,1%,1/16W,CHIP,G2A!!!F1374!B!!!!
S!VSENSE_PVSA_CPU1_P!R1C21!1!@baseboard_fab2_lib.baseboard_fab2(sch_1):page206_i77@mstr_discrete.res(chips)!RES_0402-10.0,1%,1/16W,CHIP,G2A!!!F1375!A!!!!
S!VSENSE_PVSA_CPU1_BVSP!R1C21!2!@baseboard_fab2_lib.baseboard_fab2(sch_1):page206_i77@mstr_discrete.res(chips)!RES_0402-10.0,1%,1/16W,CHIP,G2A!!!F1375!B!!!!
S!VSENSE_PVCCIO_CPU0_AVSP!R3N19!1!@baseboard_fab2_lib.baseboard_fab2(sch_1):page211_i81@mstr_discrete.res(chips)!RES_0402-10.0,1%,1/16W,CHIP,G2A!!!F1357!A!!!!
S!VR_PVCCIO_CPU0_AVSP!R3N19!2!@baseboard_fab2_lib.baseboard_fab2(sch_1):page211_i81@mstr_discrete.res(chips)!RES_0402-10.0,1%,1/16W,CHIP,G2A!!!F1357!B!!!!
S!VSENSE_PVCCIO_CPU1_AVSP!R4E7!1!@baseboard_fab2_lib.baseboard_fab2(sch_1):page213_i84@mstr_discrete.res(chips)!RES_0402-10.0,1%,1/16W,CHIP,G2A!!!F1353!A!!!!
S!VR_PVCCIO_CPU1_AVSP!R4E7!2!@baseboard_fab2_lib.baseboard_fab2(sch_1):page213_i84@mstr_discrete.res(chips)!RES_0402-10.0,1%,1/16W,CHIP,G2A!!!F1353!B!!!!
S!SMB_CPU1_PE_HP_GTL_SCL!R6N8!1!@baseboard_fab2_lib.baseboard_fab2(sch_1):page163_i2@mstr_discrete.res(chips)!RES_0402-10.0,1%,1/16W,CHIP,G2A!!!F1349!A!!!!
S!SMB_CPU1_PE_HP_GTL_R_SCL!R6N8!2!@baseboard_fab2_lib.baseboard_fab2(sch_1):page163_i2@mstr_discrete.res(chips)!RES_0402-10.0,1%,1/16W,CHIP,G2A!!!F1349!B!!!!
S!SMB_CPU1_PE_HP_GTL_SDA!R6N9!1!@baseboard_fab2_lib.baseboard_fab2(sch_1):page163_i3@mstr_discrete.res(chips)!RES_0402-10.0,1%,1/16W,CHIP,G2A!!!F1348!A!!!!
S!SMB_CPU1_PE_HP_GTL_R_SDA!R6N9!2!@baseboard_fab2_lib.baseboard_fab2(sch_1):page163_i3@mstr_discrete.res(chips)!RES_0402-10.0,1%,1/16W,CHIP,G2A!!!F1348!B!!!!
S!A_HSC_C!R1D51!1!@baseboard_fab2_lib.baseboard_fab2(sch_1):page200_i154@mstr_discrete.res(chips)!RES_0402-10.0,1%,1/16W,CHIP,G2A!!!F1370!A!!!!
S!A_HSC_GATE!R1D51!2!@baseboard_fab2_lib.baseboard_fab2(sch_1):page200_i154@mstr_discrete.res(chips)!RES_0402-10.0,1%,1/16W,CHIP,G2A!!!F1370!B!!!!
S!VSENSE_PVNN_PCH_STBY_QAT!R7A19!1!@baseboard_fab2_lib.baseboard_fab2(sch_1):page236_i93@mstr_discrete.res(chips)!RES_0402-10.0,1%,1/16W,CHIP,G2A!!!F1343!A!!!!
S!VSENSE_PVNN_PCH_STBY_AVSP!R7A19!2!@baseboard_fab2_lib.baseboard_fab2(sch_1):page236_i93@mstr_discrete.res(chips)!RES_0402-10.0,1%,1/16W,CHIP,G2A!!!F1343!B!!!!
S!VSENSE_PVNN_PCH_STBY_FPK!R7A14!1!@baseboard_fab2_lib.baseboard_fab2(sch_1):page236_i94@mstr_discrete.res(chips)!RES_0402-10.0,1%,1/16W,CHIP,G2A!!!F1344!A!!!!
S!VSENSE_PVNN_PCH_STBY_AVSP!R7A14!2!@baseboard_fab2_lib.baseboard_fab2(sch_1):page236_i94@mstr_discrete.res(chips)!RES_0402-10.0,1%,1/16W,CHIP,G2A!!!F1344!B!!!!
S!H_PM_SYNC1_GTL_R!R3N9!1!@baseboard_fab2_lib.baseboard_fab2(sch_1):page118_i66@mstr_discrete.res(chips)!RES_0402-10.0,1%,1/16W,CHIP,G2A!!!F1358!A!!!!
S!H_PM_SYNC_GTL!R3N9!2!@baseboard_fab2_lib.baseboard_fab2(sch_1):page118_i66@mstr_discrete.res(chips)!RES_0402-10.0,1%,1/16W,CHIP,G2A!!!F1358!B!!!!
S!H_PMSYNC_CLK_24M_R!R8B20!1!@baseboard_fab2_lib.baseboard_fab2(sch_1):page114_i110@mstr_discrete.res(chips)!RES_0402-10.0,1%,1/16W,CHIP,G2A!!!F1338!A!!!!
S!H_PMSYNC_CLK_24M!R8B20!2!@baseboard_fab2_lib.baseboard_fab2(sch_1):page114_i110@mstr_discrete.res(chips)!RES_0402-10.0,1%,1/16W,CHIP,G2A!!!F1338!B!!!!
S!VSENSE_PVNN_PCH_STBY_AVSP!R8A1!1!@baseboard_fab2_lib.baseboard_fab2(sch_1):page235_i210@mstr_discrete.res(chips)!RES_0402-10.0,1%,1/16W,CHIP,G2A!!!F1339!A!!!!
S!VR_PVNN_PCH_AVSP!R8A1!2!@baseboard_fab2_lib.baseboard_fab2(sch_1):page235_i210@mstr_discrete.res(chips)!RES_0402-10.0,1%,1/16W,CHIP,G2A!!!F1339!B!!!!
S!VSENSE_PVDDQ_DEF_P!R7A7!1!@baseboard_fab2_lib.baseboard_fab2(sch_1):page218_i60@mstr_discrete.res(chips)!RES_0402-10.0,1%,1/16W,CHIP,G2A!!!F1345!A!!!!
S!VR_PVDDQ_DEF_AVSP!R7A7!2!@baseboard_fab2_lib.baseboard_fab2(sch_1):page218_i60@mstr_discrete.res(chips)!RES_0402-10.0,1%,1/16W,CHIP,G2A!!!F1345!B!!!!
S!VSENSE_PVDDQ_GHJ_P!R1G5!1!@baseboard_fab2_lib.baseboard_fab2(sch_1):page223_i32@mstr_discrete.res(chips)!RES_0402-10.0,1%,1/16W,CHIP,G2A!!!F1368!A!!!!
S!VR_PVDDQ_GHJ_AVSP!R1G5!2!@baseboard_fab2_lib.baseboard_fab2(sch_1):page223_i32@mstr_discrete.res(chips)!RES_0402-10.0,1%,1/16W,CHIP,G2A!!!F1368!B!!!!
S!VSENSE_PVDDQ_KLM_P!R1B16!1!@baseboard_fab2_lib.baseboard_fab2(sch_1):page226_i32@mstr_discrete.res(chips)!RES_0402-10.0,1%,1/16W,CHIP,G2A!!!F1376!A!!!!
S!VR_PVDDQ_KLM_AVSP!R1B16!2!@baseboard_fab2_lib.baseboard_fab2(sch_1):page226_i32@mstr_discrete.res(chips)!RES_0402-10.0,1%,1/16W,CHIP,G2A!!!F1376!B!!!!
S!LED_POSTCODE_0!R1L32!1!@baseboard_fab2_lib.baseboard_fab2(sch_1):page155_i65@mstr_discrete.res(chips)!RES_0402-10.0,1%,1/16W,CHIP,G2A!!!F1359!A!!!!
S!LED_POSTCODE_0_R!R1L32!2!@baseboard_fab2_lib.baseboard_fab2(sch_1):page155_i65@mstr_discrete.res(chips)!RES_0402-10.0,1%,1/16W,CHIP,G2A!!!F1359!B!!!!
S!LED_POSTCODE_1!R1L30!1!@baseboard_fab2_lib.baseboard_fab2(sch_1):page155_i66@mstr_discrete.res(chips)!RES_0402-10.0,1%,1/16W,CHIP,G2A!!!F1360!A!!!!
S!LED_POSTCODE_1_R!R1L30!2!@baseboard_fab2_lib.baseboard_fab2(sch_1):page155_i66@mstr_discrete.res(chips)!RES_0402-10.0,1%,1/16W,CHIP,G2A!!!F1360!B!!!!
S!LED_POSTCODE_2!R1L25!1!@baseboard_fab2_lib.baseboard_fab2(sch_1):page155_i67@mstr_discrete.res(chips)!RES_0402-10.0,1%,1/16W,CHIP,G2A!!!F1361!A!!!!
S!LED_POSTCODE_2_R!R1L25!2!@baseboard_fab2_lib.baseboard_fab2(sch_1):page155_i67@mstr_discrete.res(chips)!RES_0402-10.0,1%,1/16W,CHIP,G2A!!!F1361!B!!!!
S!LED_POSTCODE_3!R1L24!1!@baseboard_fab2_lib.baseboard_fab2(sch_1):page155_i68@mstr_discrete.res(chips)!RES_0402-10.0,1%,1/16W,CHIP,G2A!!!F1362!A!!!!
S!LED_POSTCODE_3_R!R1L24!2!@baseboard_fab2_lib.baseboard_fab2(sch_1):page155_i68@mstr_discrete.res(chips)!RES_0402-10.0,1%,1/16W,CHIP,G2A!!!F1362!B!!!!
S!LED_POSTCODE_4!R1L20!1!@baseboard_fab2_lib.baseboard_fab2(sch_1):page155_i73@mstr_discrete.res(chips)!RES_0402-10.0,1%,1/16W,CHIP,G2A!!!F1363!A!!!!
S!LED_POSTCODE_4_R!R1L20!2!@baseboard_fab2_lib.baseboard_fab2(sch_1):page155_i73@mstr_discrete.res(chips)!RES_0402-10.0,1%,1/16W,CHIP,G2A!!!F1363!B!!!!
S!LED_POSTCODE_5!R1L18!1!@baseboard_fab2_lib.baseboard_fab2(sch_1):page155_i74@mstr_discrete.res(chips)!RES_0402-10.0,1%,1/16W,CHIP,G2A!!!F1364!A!!!!
S!LED_POSTCODE_5_R!R1L18!2!@baseboard_fab2_lib.baseboard_fab2(sch_1):page155_i74@mstr_discrete.res(chips)!RES_0402-10.0,1%,1/16W,CHIP,G2A!!!F1364!B!!!!
S!LED_POSTCODE_6!R1L14!1!@baseboard_fab2_lib.baseboard_fab2(sch_1):page155_i75@mstr_discrete.res(chips)!RES_0402-10.0,1%,1/16W,CHIP,G2A!!!F1365!A!!!!
S!LED_POSTCODE_6_R!R1L14!2!@baseboard_fab2_lib.baseboard_fab2(sch_1):page155_i75@mstr_discrete.res(chips)!RES_0402-10.0,1%,1/16W,CHIP,G2A!!!F1365!B!!!!
S!LED_POSTCODE_7!R1L11!1!@baseboard_fab2_lib.baseboard_fab2(sch_1):page155_i76@mstr_discrete.res(chips)!RES_0402-10.0,1%,1/16W,CHIP,G2A!!!F1366!A!!!!
S!LED_POSTCODE_7_R!R1L11!2!@baseboard_fab2_lib.baseboard_fab2(sch_1):page155_i76@mstr_discrete.res(chips)!RES_0402-10.0,1%,1/16W,CHIP,G2A!!!F1366!B!!!!
S!SMB_DDR_DEF_SCL_G_R!R3R7!1!@baseboard_fab2_lib.baseboard_fab2(sch_1):page99_i88@mstr_discrete.res(chips)!RES_0402-10.0,1%,1/16W,CHIP,G2A!!!F1356!A!!!!
S!SMB_DDR_DEF_SCL_G!R3R7!2!@baseboard_fab2_lib.baseboard_fab2(sch_1):page99_i88@mstr_discrete.res(chips)!RES_0402-10.0,1%,1/16W,CHIP,G2A!!!F1356!B!!!!
S!SMB_DDR_GHJ_SCL_G_R!R6T3!1!@baseboard_fab2_lib.baseboard_fab2(sch_1):page99_i92@mstr_discrete.res(chips)!RES_0402-10.0,1%,1/16W,CHIP,G2A!!!F1347!A!!!!
S!SMB_DDR_GHJ_SCL_G!R6T3!2!@baseboard_fab2_lib.baseboard_fab2(sch_1):page99_i92@mstr_discrete.res(chips)!RES_0402-10.0,1%,1/16W,CHIP,G2A!!!F1347!B!!!!
S!SMB_DDR_ABC_SCL_G_R!R4T3!1!@baseboard_fab2_lib.baseboard_fab2(sch_1):page99_i83@mstr_discrete.res(chips)!RES_0402-10.0,1%,1/16W,CHIP,G2A!!!F1351!A!!!!
S!SMB_DDR_ABC_SCL_G!R4T3!2!@baseboard_fab2_lib.baseboard_fab2(sch_1):page99_i83@mstr_discrete.res(chips)!RES_0402-10.0,1%,1/16W,CHIP,G2A!!!F1351!B!!!!
S!SMB_DDR_KLM_SCL_G_R!R7M3!1!@baseboard_fab2_lib.baseboard_fab2(sch_1):page99_i98@mstr_discrete.res(chips)!RES_0402-10.0,1%,1/16W,CHIP,G2A!!!F1341!A!!!!
S!SMB_DDR_KLM_SCL_G!R7M3!2!@baseboard_fab2_lib.baseboard_fab2(sch_1):page99_i98@mstr_discrete.res(chips)!RES_0402-10.0,1%,1/16W,CHIP,G2A!!!F1341!B!!!!
S!SMB_DDR_KLM_SDA_G_R!R7M8!1!@baseboard_fab2_lib.baseboard_fab2(sch_1):page99_i112@mstr_discrete.res(chips)!RES_0402-10.0,1%,1/16W,CHIP,G2A!!!F1340!A!!!!
S!SMB_DDR_KLM_SDA_G!R7M8!2!@baseboard_fab2_lib.baseboard_fab2(sch_1):page99_i112@mstr_discrete.res(chips)!RES_0402-10.0,1%,1/16W,CHIP,G2A!!!F1340!B!!!!
S!SMB_DDR_DEF_SDA_G_R!R3R14!1!@baseboard_fab2_lib.baseboard_fab2(sch_1):page99_i110@mstr_discrete.res(chips)!RES_0402-10.0,1%,1/16W,CHIP,G2A!!!F1355!A!!!!
S!SMB_DDR_DEF_SDA_G!R3R14!2!@baseboard_fab2_lib.baseboard_fab2(sch_1):page99_i110@mstr_discrete.res(chips)!RES_0402-10.0,1%,1/16W,CHIP,G2A!!!F1355!B!!!!
S!SMB_DDR_GHJ_SDA_G_R!R6T4!1!@baseboard_fab2_lib.baseboard_fab2(sch_1):page99_i111@mstr_discrete.res(chips)!RES_0402-10.0,1%,1/16W,CHIP,G2A!!!F1346!A!!!!
S!SMB_DDR_GHJ_SDA_G!R6T4!2!@baseboard_fab2_lib.baseboard_fab2(sch_1):page99_i111@mstr_discrete.res(chips)!RES_0402-10.0,1%,1/16W,CHIP,G2A!!!F1346!B!!!!
S!VSENSE_PVDDQ_ABC_P!R7G9!1!@baseboard_fab2_lib.baseboard_fab2(sch_1):page215_i344@mstr_discrete.res(chips)!RES_0402-10.0,1%,1/16W,CHIP,G2A!!!F1342!A!!!!
S!VR_PVDDQ_ABC_AVSP!R7G9!2!@baseboard_fab2_lib.baseboard_fab2(sch_1):page215_i344@mstr_discrete.res(chips)!RES_0402-10.0,1%,1/16W,CHIP,G2A!!!F1342!B!!!!
S!SMB_DDR_ABC_SDA_G_R!R4T4!1!@baseboard_fab2_lib.baseboard_fab2(sch_1):page99_i20@mstr_discrete.res(chips)!RES_0402-10.0,1%,1/16W,CHIP,G2A!!!F1350!A!!!!
S!SMB_DDR_ABC_SDA_G!R4T4!2!@baseboard_fab2_lib.baseboard_fab2(sch_1):page99_i20@mstr_discrete.res(chips)!RES_0402-10.0,1%,1/16W,CHIP,G2A!!!F1350!B!!!!
S!P12V_HSC_SENP0!R1D46!1!@baseboard_fab2_lib.baseboard_fab2(sch_1):page200_i48@mstr_discrete.res(chips)!RES_0402-10.0,1%,1/16W,CHIP,G2A!!!F1373!A!!!!
S!A_HSC_HSP!R1D46!2!@baseboard_fab2_lib.baseboard_fab2(sch_1):page200_i48@mstr_discrete.res(chips)!RES_0402-10.0,1%,1/16W,CHIP,G2A!!!F1373!B!!!!
S!P12V_HSC_SENP1!R9P27!1!@baseboard_fab2_lib.baseboard_fab2(sch_1):page200_i47@mstr_discrete.res(chips)!RES_0402-10.0,1%,1/16W,CHIP,G2A!!!F1336!A!!!!
S!A_HSC_HSP!R9P27!2!@baseboard_fab2_lib.baseboard_fab2(sch_1):page200_i47@mstr_discrete.res(chips)!RES_0402-10.0,1%,1/16W,CHIP,G2A!!!F1336!B!!!!
S!P12V_HSC_SENN1!R9P26!1!@baseboard_fab2_lib.baseboard_fab2(sch_1):page200_i51@mstr_discrete.res(chips)!RES_0402-10.0,1%,1/16W,CHIP,G2A!!!F1337!A!!!!
S!A_HSC_HSN!R9P26!2!@baseboard_fab2_lib.baseboard_fab2(sch_1):page200_i51@mstr_discrete.res(chips)!RES_0402-10.0,1%,1/16W,CHIP,G2A!!!F1337!B!!!!
S!P12V_HSC_SENN0!R1D47!1!@baseboard_fab2_lib.baseboard_fab2(sch_1):page200_i52@mstr_discrete.res(chips)!RES_0402-10.0,1%,1/16W,CHIP,G2A!!!F1372!A!!!!
S!A_HSC_HSN!R1D47!2!@baseboard_fab2_lib.baseboard_fab2(sch_1):page200_i52@mstr_discrete.res(chips)!RES_0402-10.0,1%,1/16W,CHIP,G2A!!!F1372!B!!!!
S!A_HSC_GATE!R1D48!1!@baseboard_fab2_lib.baseboard_fab2(sch_1):page200_i60@mstr_discrete.res(chips)!RES_0402-10.0,1%,1/16W,CHIP,G2A!!!F1371!A!!!!
S!A_HSC_GATE3_R!R1D48!2!@baseboard_fab2_lib.baseboard_fab2(sch_1):page200_i60@mstr_discrete.res(chips)!RES_0402-10.0,1%,1/16W,CHIP,G2A!!!F1371!B!!!!
S!A_HSC_GATE!R9R4!1!@baseboard_fab2_lib.baseboard_fab2(sch_1):page200_i58@mstr_discrete.res(chips)!RES_0402-10.0,1%,1/16W,CHIP,G2A!!!F1335!A!!!!
S!A_HSC_GATE2_R!R9R4!2!@baseboard_fab2_lib.baseboard_fab2(sch_1):page200_i58@mstr_discrete.res(chips)!RES_0402-10.0,1%,1/16W,CHIP,G2A!!!F1335!B!!!!
S!A_HSC_GATE!R1E1!1!@baseboard_fab2_lib.baseboard_fab2(sch_1):page200_i56@mstr_discrete.res(chips)!RES_0402-10.0,1%,1/16W,CHIP,G2A!!!F1369!A!!!!
S!A_HSC_GATE1_R!R1E1!2!@baseboard_fab2_lib.baseboard_fab2(sch_1):page200_i56@mstr_discrete.res(chips)!RES_0402-10.0,1%,1/16W,CHIP,G2A!!!F1369!B!!!!
S!PD_HSC_RETRY_N!R1D28!1!@baseboard_fab2_lib.baseboard_fab2(sch_1):page199_i26@mstr_discrete.res(chips)!RES_0402-100.0,1%,1/16W,EMPTY,A!!!F1167!A!!!!
S!AGND_HSC!R1D28!2!@baseboard_fab2_lib.baseboard_fab2(sch_1):page199_i26@mstr_discrete.res(chips)!RES_0402-100.0,1%,1/16W,EMPTY,A!!!F1167!B!!!!
S!PVCCIO_CPU1!R6P35!1!@baseboard_fab2_lib.baseboard_fab2(sch_1):page213_i27@mstr_discrete.res(chips)!RES_0402-100.0,1%,1/16W,EMPTY,A!!!F1162!A!!!!
S!SVID_DIO0_CPU1_R!R6P35!2!@baseboard_fab2_lib.baseboard_fab2(sch_1):page213_i27@mstr_discrete.res(chips)!RES_0402-100.0,1%,1/16W,EMPTY,A!!!F1162!B!!!!
S!PVCCIO_CPU0!R3L11!1!@baseboard_fab2_lib.baseboard_fab2(sch_1):page218_i7@mstr_discrete.res(chips)!RES_0402-100.0,1%,1/16W,EMPTY,A!!!F1166!A!!!!
S!SVID_DIO1_CPU0_R!R3L11!2!@baseboard_fab2_lib.baseboard_fab2(sch_1):page218_i7@mstr_discrete.res(chips)!RES_0402-100.0,1%,1/16W,EMPTY,A!!!F1166!B!!!!
S!PVCCIO_CPU1!R9M7!1!@baseboard_fab2_lib.baseboard_fab2(sch_1):page226_i8@mstr_discrete.res(chips)!RES_0402-100.0,1%,1/16W,EMPTY,A!!!F1158!A!!!!
S!SVID_DIO1_CPU1_R!R9M7!2!@baseboard_fab2_lib.baseboard_fab2(sch_1):page226_i8@mstr_discrete.res(chips)!RES_0402-100.0,1%,1/16W,EMPTY,A!!!F1158!B!!!!
S!PVCCIO_CPU0!R3P13!1!@baseboard_fab2_lib.baseboard_fab2(sch_1):page211_i17@mstr_discrete.res(chips)!RES_0402-100.0,1%,1/16W,EMPTY,A!!!F1165!A!!!!
S!SVID_DIO0_CPU0_R!R3P13!2!@baseboard_fab2_lib.baseboard_fab2(sch_1):page211_i17@mstr_discrete.res(chips)!RES_0402-100.0,1%,1/16W,EMPTY,A!!!F1165!B!!!!
S!VSENSE_P1V05_PCH_STBY_AVSP!R8B15!1!@baseboard_fab2_lib.baseboard_fab2(sch_1):page236_i57@mstr_discrete.res(chips)!RES_0402-100.0,1%,1/16W,EMPTY,A!!!F1159!A!!!!
S!VSENSE_P1V05_PCH_STBY_AVSN!R8B15!2!@baseboard_fab2_lib.baseboard_fab2(sch_1):page236_i57@mstr_discrete.res(chips)!RES_0402-100.0,1%,1/16W,EMPTY,A!!!F1159!B!!!!
S!VSENSE_PVDDQ_ABC_P!R4U6!1!@baseboard_fab2_lib.baseboard_fab2(sch_1):page217_i74@mstr_discrete.res(chips)!RES_0402-100.0,1%,1/16W,EMPTY,A!!!F1163!A!!!!
S!VSENSE_PVDDQ_ABC_N!R4U6!2!@baseboard_fab2_lib.baseboard_fab2(sch_1):page217_i74@mstr_discrete.res(chips)!RES_0402-100.0,1%,1/16W,EMPTY,A!!!F1163!B!!!!
S!VSENSE_PVDDQ_DEF_P!R4L2!1!@baseboard_fab2_lib.baseboard_fab2(sch_1):page220_i74@mstr_discrete.res(chips)!RES_0402-100.0,1%,1/16W,EMPTY,A!!!F1164!A!!!!
S!VSENSE_PVDDQ_DEF_N!R4L2!2!@baseboard_fab2_lib.baseboard_fab2(sch_1):page220_i74@mstr_discrete.res(chips)!RES_0402-100.0,1%,1/16W,EMPTY,A!!!F1164!B!!!!
S!VSENSE_PVDDQ_GHJ_P!R7U2!1!@baseboard_fab2_lib.baseboard_fab2(sch_1):page225_i74@mstr_discrete.res(chips)!RES_0402-100.0,1%,1/16W,EMPTY,A!!!F1160!A!!!!
S!VSENSE_PVDDQ_GHJ_N!R7U2!2!@baseboard_fab2_lib.baseboard_fab2(sch_1):page225_i74@mstr_discrete.res(chips)!RES_0402-100.0,1%,1/16W,EMPTY,A!!!F1160!B!!!!
S!VSENSE_PVDDQ_KLM_P!R7L2!1!@baseboard_fab2_lib.baseboard_fab2(sch_1):page228_i74@mstr_discrete.res(chips)!RES_0402-100.0,1%,1/16W,EMPTY,A!!!F1161!A!!!!
S!VSENSE_PVDDQ_KLM_N!R7L2!2!@baseboard_fab2_lib.baseboard_fab2(sch_1):page228_i74@mstr_discrete.res(chips)!RES_0402-100.0,1%,1/16W,EMPTY,A!!!F1161!B!!!!
S!PVCCIO_CPU1!R6T7!1!@baseboard_fab2_lib.baseboard_fab2(sch_1):page112_i55@mstr_discrete.res(chips)!RES_0402-150.0,1%,1/16W,CHIP,GA!!!F1080!A!!!!
S!XDP_CPU1_TDO!R6T7!2!@baseboard_fab2_lib.baseboard_fab2(sch_1):page112_i55@mstr_discrete.res(chips)!RES_0402-150.0,1%,1/16W,CHIP,GA!!!F1080!B!!!!
S!PVCCIO_CPU1!R6T6!1!@baseboard_fab2_lib.baseboard_fab2(sch_1):page112_i56@mstr_discrete.res(chips)!RES_0402-150.0,1%,1/16W,CHIP,GA!!!F1081!A!!!!
S!XDP_CPU1_TDI!R6T6!2!@baseboard_fab2_lib.baseboard_fab2(sch_1):page112_i56@mstr_discrete.res(chips)!RES_0402-150.0,1%,1/16W,CHIP,GA!!!F1081!B!!!!
S!PVCCIO_CPU0!R1L15!1!@baseboard_fab2_lib.baseboard_fab2(sch_1):page112_i60@mstr_discrete.res(chips)!RES_0402-150.0,1%,1/16W,CHIP,GA!!!F1099!A!!!!
S!XDP_CPU_TMS!R1L15!2!@baseboard_fab2_lib.baseboard_fab2(sch_1):page112_i60@mstr_discrete.res(chips)!RES_0402-150.0,1%,1/16W,CHIP,GA!!!F1099!B!!!!
S!PVCCIO_CPU1!R3P40!1!@baseboard_fab2_lib.baseboard_fab2(sch_1):page93_i104@mstr_discrete.res(chips)!RES_0402-150.0,1%,1/16W,CHIP,GA!!!F1092!A!!!!
S!H_CPU1_PROCHOT_G_N!R3P40!2!@baseboard_fab2_lib.baseboard_fab2(sch_1):page93_i104@mstr_discrete.res(chips)!RES_0402-150.0,1%,1/16W,CHIP,GA!!!F1092!B!!!!
S!PVCCIO_CPU0!R7E1!1!@baseboard_fab2_lib.baseboard_fab2(sch_1):page93_i80@mstr_discrete.res(chips)!RES_0402-150.0,1%,1/16W,CHIP,GA!!!F1078!A!!!!
S!H_CPU0_PROCHOT_G_N!R7E1!2!@baseboard_fab2_lib.baseboard_fab2(sch_1):page93_i80@mstr_discrete.res(chips)!RES_0402-150.0,1%,1/16W,CHIP,GA!!!F1078!B!!!!
S!H_CPU1_MEMKLM_MEMHOT_G_N!R7P21!1!@baseboard_fab2_lib.baseboard_fab2(sch_1):page152_i62@mstr_discrete.res(chips)!RES_0402-150.0,1%,1/16W,CHIP,GA!!!F1073!A!!!!
S!PVCCIO_CPU1!R7P21!2!@baseboard_fab2_lib.baseboard_fab2(sch_1):page152_i62@mstr_discrete.res(chips)!RES_0402-150.0,1%,1/16W,CHIP,GA!!!F1073!B!!!!
S!PVCCIO_CPU1!R1U35!1!@baseboard_fab2_lib.baseboard_fab2(sch_1):page152_i57@mstr_discrete.res(chips)!RES_0402-150.0,1%,1/16W,CHIP,GA!!!F1097!A!!!!
S!H_CPU1_MEMKLM_MEMHOT_G_N!R1U35!2!@baseboard_fab2_lib.baseboard_fab2(sch_1):page152_i57@mstr_discrete.res(chips)!RES_0402-150.0,1%,1/16W,CHIP,GA!!!F1097!B!!!!
S!H_CPU1_MEMGHJ_MEMHOT_G_N!R7P5!1!@baseboard_fab2_lib.baseboard_fab2(sch_1):page152_i61@mstr_discrete.res(chips)!RES_0402-150.0,1%,1/16W,CHIP,GA!!!F1076!A!!!!
S!PVCCIO_CPU1!R7P5!2!@baseboard_fab2_lib.baseboard_fab2(sch_1):page152_i61@mstr_discrete.res(chips)!RES_0402-150.0,1%,1/16W,CHIP,GA!!!F1076!B!!!!
S!PVCCIO_CPU1!R1U41!1!@baseboard_fab2_lib.baseboard_fab2(sch_1):page152_i56@mstr_discrete.res(chips)!RES_0402-150.0,1%,1/16W,CHIP,GA!!!F1096!A!!!!
S!H_CPU1_MEMGHJ_MEMHOT_G_N!R1U41!2!@baseboard_fab2_lib.baseboard_fab2(sch_1):page152_i56@mstr_discrete.res(chips)!RES_0402-150.0,1%,1/16W,CHIP,GA!!!F1096!B!!!!
S!PVCCIO_CPU0!R2U40!1!@baseboard_fab2_lib.baseboard_fab2(sch_1):page152_i53@mstr_discrete.res(chips)!RES_0402-150.0,1%,1/16W,CHIP,GA!!!F1095!A!!!!
S!H_CPU0_MEMABC_MEMHOT_G_N!R2U40!2!@baseboard_fab2_lib.baseboard_fab2(sch_1):page152_i53@mstr_discrete.res(chips)!RES_0402-150.0,1%,1/16W,CHIP,GA!!!F1095!B!!!!
S!PVCCIO_CPU0!R2U41!1!@baseboard_fab2_lib.baseboard_fab2(sch_1):page152_i54@mstr_discrete.res(chips)!RES_0402-150.0,1%,1/16W,CHIP,GA!!!F1094!A!!!!
S!H_CPU0_MEMDEF_MEMHOT_G_N!R2U41!2!@baseboard_fab2_lib.baseboard_fab2(sch_1):page152_i54@mstr_discrete.res(chips)!RES_0402-150.0,1%,1/16W,CHIP,GA!!!F1094!B!!!!
S!H_CPU0_MEMABC_MEMHOT_G_N!R4P17!1!@baseboard_fab2_lib.baseboard_fab2(sch_1):page152_i58@mstr_discrete.res(chips)!RES_0402-150.0,1%,1/16W,CHIP,GA!!!F1089!A!!!!
S!PVCCIO_CPU0!R4P17!2!@baseboard_fab2_lib.baseboard_fab2(sch_1):page152_i58@mstr_discrete.res(chips)!RES_0402-150.0,1%,1/16W,CHIP,GA!!!F1089!B!!!!
S!H_CPU0_MEMDEF_MEMHOT_G_N!R4P20!1!@baseboard_fab2_lib.baseboard_fab2(sch_1):page152_i59@mstr_discrete.res(chips)!RES_0402-150.0,1%,1/16W,CHIP,GA!!!F1088!A!!!!
S!PVCCIO_CPU0!R4P20!2!@baseboard_fab2_lib.baseboard_fab2(sch_1):page152_i59@mstr_discrete.res(chips)!RES_0402-150.0,1%,1/16W,CHIP,GA!!!F1088!B!!!!
S!PVCCIO_CPU1!R7P28!1!@baseboard_fab2_lib.baseboard_fab2(sch_1):page93_i106@mstr_discrete.res(chips)!RES_0402-150.0,1%,1/16W,CHIP,GA!!!F1071!A!!!!
S!H_CPU1_PROCHOT_G_N!R7P28!2!@baseboard_fab2_lib.baseboard_fab2(sch_1):page93_i106@mstr_discrete.res(chips)!RES_0402-150.0,1%,1/16W,CHIP,GA!!!F1071!B!!!!
S!PVCCIO_CPU0!R4R3!1!@baseboard_fab2_lib.baseboard_fab2(sch_1):page93_i79@mstr_discrete.res(chips)!RES_0402-150.0,1%,1/16W,CHIP,GA!!!F1084!A!!!!
S!H_CPU0_PROCHOT_G_N!R4R3!2!@baseboard_fab2_lib.baseboard_fab2(sch_1):page93_i79@mstr_discrete.res(chips)!RES_0402-150.0,1%,1/16W,CHIP,GA!!!F1084!B!!!!
S!PVCCIO_CPU0!R4P24!1!@baseboard_fab2_lib.baseboard_fab2(sch_1):page112_i59@mstr_discrete.res(chips)!RES_0402-150.0,1%,1/16W,CHIP,GA!!!F1086!A!!!!
S!XDP_CPU_TDI!R4P24!2!@baseboard_fab2_lib.baseboard_fab2(sch_1):page112_i59@mstr_discrete.res(chips)!RES_0402-150.0,1%,1/16W,CHIP,GA!!!F1086!B!!!!
S!PVCCIO_CPU0!R4P23!1!@baseboard_fab2_lib.baseboard_fab2(sch_1):page112_i58@mstr_discrete.res(chips)!RES_0402-150.0,1%,1/16W,CHIP,GA!!!F1087!A!!!!
S!XDP_CPU0_TDO!R4P23!2!@baseboard_fab2_lib.baseboard_fab2(sch_1):page112_i58@mstr_discrete.res(chips)!RES_0402-150.0,1%,1/16W,CHIP,GA!!!F1087!B!!!!
S!P1V05_PCH_STBY!R8A14!1!@baseboard_fab2_lib.baseboard_fab2(sch_1):page112_i80@mstr_discrete.res(chips)!RES_0402-150.0,1%,1/16W,CHIP,GA!!!F1069!A!!!!
S!XDP_TMS!R8A14!2!@baseboard_fab2_lib.baseboard_fab2(sch_1):page112_i80@mstr_discrete.res(chips)!RES_0402-150.0,1%,1/16W,CHIP,GA!!!F1069!B!!!!
S!P1V05_PCH_STBY!R8A13!1!@baseboard_fab2_lib.baseboard_fab2(sch_1):page112_i79@mstr_discrete.res(chips)!RES_0402-150.0,1%,1/16W,CHIP,GA!!!F1070!A!!!!
S!XDP_TDI!R8A13!2!@baseboard_fab2_lib.baseboard_fab2(sch_1):page112_i79@mstr_discrete.res(chips)!RES_0402-150.0,1%,1/16W,CHIP,GA!!!F1070!B!!!!
S!P1V05_PCH_STBY!R9A11!1!@baseboard_fab2_lib.baseboard_fab2(sch_1):page112_i78@mstr_discrete.res(chips)!RES_0402-150.0,1%,1/16W,CHIP,GA!!!F1068!A!!!!
S!XDP_TDO!R9A11!2!@baseboard_fab2_lib.baseboard_fab2(sch_1):page112_i78@mstr_discrete.res(chips)!RES_0402-150.0,1%,1/16W,CHIP,GA!!!F1068!B!!!!
S!SVID_CLK0_CPU1_R!R4D51!1!@baseboard_fab2_lib.baseboard_fab2(sch_1):page213_i46@mstr_discrete.res(chips)!RES_0402-150.0,1%,1/16W,CHIP,GA!!!F1091!A!!!!
S!SVID_CLK_PVCCIO_CPU1!R4D51!2!@baseboard_fab2_lib.baseboard_fab2(sch_1):page213_i46@mstr_discrete.res(chips)!RES_0402-150.0,1%,1/16W,CHIP,GA!!!F1091!B!!!!
S!SVID_CLK0_CPU0_R!R3P15!1!@baseboard_fab2_lib.baseboard_fab2(sch_1):page211_i29@mstr_discrete.res(chips)!RES_0402-150.0,1%,1/16W,CHIP,GA!!!F1093!A!!!!
S!SVID_CLK_PVCCIO_CPU0!R3P15!2!@baseboard_fab2_lib.baseboard_fab2(sch_1):page211_i29@mstr_discrete.res(chips)!RES_0402-150.0,1%,1/16W,CHIP,GA!!!F1093!B!!!!
S!SVID_CLK1_CPU0_R!R7A17!1!@baseboard_fab2_lib.baseboard_fab2(sch_1):page218_i48@mstr_discrete.res(chips)!RES_0402-150.0,1%,1/16W,CHIP,GA!!!F1079!A!!!!
S!SVID_CLK_PVDDQ_DEF!R7A17!2!@baseboard_fab2_lib.baseboard_fab2(sch_1):page218_i48@mstr_discrete.res(chips)!RES_0402-150.0,1%,1/16W,CHIP,GA!!!F1079!B!!!!
S!SVID_CLK1_CPU1_R!R1G7!1!@baseboard_fab2_lib.baseboard_fab2(sch_1):page223_i53@mstr_discrete.res(chips)!RES_0402-150.0,1%,1/16W,CHIP,GA!!!F1100!A!!!!
S!SVID_CLK_PVDDQ_GHJ!R1G7!2!@baseboard_fab2_lib.baseboard_fab2(sch_1):page223_i53@mstr_discrete.res(chips)!RES_0402-150.0,1%,1/16W,CHIP,GA!!!F1100!B!!!!
S!SVID_CLK1_CPU1_R!R1B8!1!@baseboard_fab2_lib.baseboard_fab2(sch_1):page226_i53@mstr_discrete.res(chips)!RES_0402-150.0,1%,1/16W,CHIP,GA!!!F1102!A!!!!
S!SVID_CLK_PVDDQ_KLM!R1B8!2!@baseboard_fab2_lib.baseboard_fab2(sch_1):page226_i53@mstr_discrete.res(chips)!RES_0402-150.0,1%,1/16W,CHIP,GA!!!F1102!B!!!!
S!SVID_CLK1_CPU0_R!R7G24!1!@baseboard_fab2_lib.baseboard_fab2(sch_1):page215_i331@mstr_discrete.res(chips)!RES_0402-150.0,1%,1/16W,CHIP,GA!!!F1077!A!!!!
S!SVID_CLK_PVDDQ_ABC!R7G24!2!@baseboard_fab2_lib.baseboard_fab2(sch_1):page215_i331@mstr_discrete.res(chips)!RES_0402-150.0,1%,1/16W,CHIP,GA!!!F1077!B!!!!
S!SVID_CLK0_CPU1_R!R1D9!1!@baseboard_fab2_lib.baseboard_fab2(sch_1):page206_i54@mstr_discrete.res(chips)!RES_0402-150.0,1%,1/16W,CHIP,GA!!!F1101!A!!!!
S!SVID_VCLK_PVCCIN_CPU1!R1D9!2!@baseboard_fab2_lib.baseboard_fab2(sch_1):page206_i54@mstr_discrete.res(chips)!RES_0402-150.0,1%,1/16W,CHIP,GA!!!F1101!B!!!!
S!XDP_CPU_PWR_DEBUG_N!R1L17!1!@baseboard_fab2_lib.baseboard_fab2(sch_1):page111_i56@mstr_discrete.res(chips)!RES_0402-150.0,1%,1/16W,CHIP,GA!!!F1098!A!!!!
S!PVCCIO_CPU0!R1L17!2!@baseboard_fab2_lib.baseboard_fab2(sch_1):page111_i56@mstr_discrete.res(chips)!RES_0402-150.0,1%,1/16W,CHIP,GA!!!F1098!B!!!!
S!PVCCIO_CPU0!R4R2!1!@baseboard_fab2_lib.baseboard_fab2(sch_1):page92_i101@mstr_discrete.res(chips)!RES_0402-150.0,1%,1/16W,CHIP,GA!!!F1085!A!!!!
S!H_CPU0_CATERR_G_N!R4R2!2!@baseboard_fab2_lib.baseboard_fab2(sch_1):page92_i101@mstr_discrete.res(chips)!RES_0402-150.0,1%,1/16W,CHIP,GA!!!F1085!B!!!!
S!PVCCIO_CPU0!R7P18!1!@baseboard_fab2_lib.baseboard_fab2(sch_1):page92_i100@mstr_discrete.res(chips)!RES_0402-150.0,1%,1/16W,CHIP,GA!!!F1075!A!!!!
S!H_CPU1_CATERR_G_N!R7P18!2!@baseboard_fab2_lib.baseboard_fab2(sch_1):page92_i100@mstr_discrete.res(chips)!RES_0402-150.0,1%,1/16W,CHIP,GA!!!F1075!B!!!!
S!PVCCIO_CPU0!R7P20!1!@baseboard_fab2_lib.baseboard_fab2(sch_1):page97_i44@mstr_discrete.res(chips)!RES_0402-150.0,1%,1/16W,CHIP,GA!!!F1074!A!!!!
S!H_CPU1_FAST_WAKE_N!R7P20!2!@baseboard_fab2_lib.baseboard_fab2(sch_1):page97_i44@mstr_discrete.res(chips)!RES_0402-150.0,1%,1/16W,CHIP,GA!!!F1074!B!!!!
S!SVID_CLK0_CPU0_R!R4E6!1!@baseboard_fab2_lib.baseboard_fab2(sch_1):page201_i56@mstr_discrete.res(chips)!RES_0402-150.0,1%,1/16W,CHIP,GA!!!F1090!A!!!!
S!SVID_VCLK_PVCCIN_CPU0!R4E6!2!@baseboard_fab2_lib.baseboard_fab2(sch_1):page201_i56@mstr_discrete.res(chips)!RES_0402-150.0,1%,1/16W,CHIP,GA!!!F1090!B!!!!
S!PVCCIO_CPU0!R4R4!1!@baseboard_fab2_lib.baseboard_fab2(sch_1):page97_i42@mstr_discrete.res(chips)!RES_0402-150.0,1%,1/16W,CHIP,GA!!!F1083!A!!!!
S!H_CPU0_FAST_WAKE_N!R4R4!2!@baseboard_fab2_lib.baseboard_fab2(sch_1):page97_i42@mstr_discrete.res(chips)!RES_0402-150.0,1%,1/16W,CHIP,GA!!!F1083!B!!!!
S!PVCCIO_CPU0!R6D9!1!@baseboard_fab2_lib.baseboard_fab2(sch_1):page92_i64@mstr_discrete.res(chips)!RES_0402-150.0,1%,1/16W,CHIP,GA!!!F1082!A!!!!
S!H_CPU0_MSMI_G_N!R6D9!2!@baseboard_fab2_lib.baseboard_fab2(sch_1):page92_i64@mstr_discrete.res(chips)!RES_0402-150.0,1%,1/16W,CHIP,GA!!!F1082!B!!!!
S!PVCCIO_CPU0!R7P27!1!@baseboard_fab2_lib.baseboard_fab2(sch_1):page92_i65@mstr_discrete.res(chips)!RES_0402-150.0,1%,1/16W,CHIP,GA!!!F1072!A!!!!
S!H_CPU1_MSMI_G_N!R7P27!2!@baseboard_fab2_lib.baseboard_fab2(sch_1):page92_i65@mstr_discrete.res(chips)!RES_0402-150.0,1%,1/16W,CHIP,GA!!!F1072!B!!!!
S!M_H_CPU_VREF!R1G1!1!@baseboard_fab2_lib.baseboard_fab2(sch_1):page100_i25@mstr_discrete.res(chips)!RES_0402-2,1.0%,1/16W,CHIP,G21A!!!F1061!A!!!!
S!M_H_VREF!R1G1!2!@baseboard_fab2_lib.baseboard_fab2(sch_1):page100_i25@mstr_discrete.res(chips)!RES_0402-2,1.0%,1/16W,CHIP,G21A!!!F1061!B!!!!
S!M_J_CPU_VREF!R1G14!1!@baseboard_fab2_lib.baseboard_fab2(sch_1):page100_i41@mstr_discrete.res(chips)!RES_0402-2,1.0%,1/16W,CHIP,G21A!!!F1060!A!!!!
S!M_J_VREF!R1G14!2!@baseboard_fab2_lib.baseboard_fab2(sch_1):page100_i41@mstr_discrete.res(chips)!RES_0402-2,1.0%,1/16W,CHIP,G21A!!!F1060!B!!!!
S!M_L_CPU_VREF!R9L8!1!@baseboard_fab2_lib.baseboard_fab2(sch_1):page100_i29@mstr_discrete.res(chips)!RES_0402-2,1.0%,1/16W,CHIP,G21A!!!F1052!A!!!!
S!M_L_VREF!R9L8!2!@baseboard_fab2_lib.baseboard_fab2(sch_1):page100_i29@mstr_discrete.res(chips)!RES_0402-2,1.0%,1/16W,CHIP,G21A!!!F1052!B!!!!
S!M_M_CPU_VREF!R9L3!1!@baseboard_fab2_lib.baseboard_fab2(sch_1):page100_i45@mstr_discrete.res(chips)!RES_0402-2,1.0%,1/16W,CHIP,G21A!!!F1053!A!!!!
S!M_M_VREF!R9L3!2!@baseboard_fab2_lib.baseboard_fab2(sch_1):page100_i45@mstr_discrete.res(chips)!RES_0402-2,1.0%,1/16W,CHIP,G21A!!!F1053!B!!!!
S!M_E_CPU_VREF!R6L14!1!@baseboard_fab2_lib.baseboard_fab2(sch_1):page98_i58@mstr_discrete.res(chips)!RES_0402-2,1.0%,1/16W,CHIP,G21A!!!F1055!A!!!!
S!M_E_VREF!R6L14!2!@baseboard_fab2_lib.baseboard_fab2(sch_1):page98_i58@mstr_discrete.res(chips)!RES_0402-2,1.0%,1/16W,CHIP,G21A!!!F1055!B!!!!
S!M_B_CPU_VREF!R4G1!1!@baseboard_fab2_lib.baseboard_fab2(sch_1):page98_i42@mstr_discrete.res(chips)!RES_0402-2,1.0%,1/16W,CHIP,G21A!!!F1058!A!!!!
S!M_B_VREF!R4G1!2!@baseboard_fab2_lib.baseboard_fab2(sch_1):page98_i42@mstr_discrete.res(chips)!RES_0402-2,1.0%,1/16W,CHIP,G21A!!!F1058!B!!!!
S!M_C_CPU_VREF!R4G20!1!@baseboard_fab2_lib.baseboard_fab2(sch_1):page98_i50@mstr_discrete.res(chips)!RES_0402-2,1.0%,1/16W,CHIP,G21A!!!F1057!A!!!!
S!M_C_VREF!R4G20!2!@baseboard_fab2_lib.baseboard_fab2(sch_1):page98_i50@mstr_discrete.res(chips)!RES_0402-2,1.0%,1/16W,CHIP,G21A!!!F1057!B!!!!
S!M_F_CPU_VREF!R6L3!1!@baseboard_fab2_lib.baseboard_fab2(sch_1):page98_i66@mstr_discrete.res(chips)!RES_0402-2,1.0%,1/16W,CHIP,G21A!!!F1056!A!!!!
S!M_F_VREF!R6L3!2!@baseboard_fab2_lib.baseboard_fab2(sch_1):page98_i66@mstr_discrete.res(chips)!RES_0402-2,1.0%,1/16W,CHIP,G21A!!!F1056!B!!!!
S!M_G_CPU_VREF!R1F4!1!@baseboard_fab2_lib.baseboard_fab2(sch_1):page100_i7@mstr_discrete.res(chips)!RES_0402-2,1.0%,1/16W,CHIP,G21A!!!F1062!A!!!!
S!M_G_VREF!R1F4!2!@baseboard_fab2_lib.baseboard_fab2(sch_1):page100_i7@mstr_discrete.res(chips)!RES_0402-2,1.0%,1/16W,CHIP,G21A!!!F1062!B!!!!
S!M_A_CPU_VREF!R4F3!1!@baseboard_fab2_lib.baseboard_fab2(sch_1):page98_i5@mstr_discrete.res(chips)!RES_0402-2,1.0%,1/16W,CHIP,G21A!!!F1059!A!!!!
S!M_A_VREF!R4F3!2!@baseboard_fab2_lib.baseboard_fab2(sch_1):page98_i5@mstr_discrete.res(chips)!RES_0402-2,1.0%,1/16W,CHIP,G21A!!!F1059!B!!!!
S!M_K_CPU_VREF!R9M2!1!@baseboard_fab2_lib.baseboard_fab2(sch_1):page100_i13@mstr_discrete.res(chips)!RES_0402-2,1.0%,1/16W,CHIP,G21A!!!F1051!A!!!!
S!M_K_VREF!R9M2!2!@baseboard_fab2_lib.baseboard_fab2(sch_1):page100_i13@mstr_discrete.res(chips)!RES_0402-2,1.0%,1/16W,CHIP,G21A!!!F1051!B!!!!
S!M_D_CPU_VREF!R6M2!1!@baseboard_fab2_lib.baseboard_fab2(sch_1):page98_i14@mstr_discrete.res(chips)!RES_0402-2,1.0%,1/16W,CHIP,G21A!!!F1054!A!!!!
S!M_D_VREF!R6M2!2!@baseboard_fab2_lib.baseboard_fab2(sch_1):page98_i14@mstr_discrete.res(chips)!RES_0402-2,1.0%,1/16W,CHIP,G21A!!!F1054!B!!!!
S!P3V3_STBY!R7D5!1!@baseboard_fab2_lib.baseboard_fab2(sch_1):page181_i199@mstr_discrete.res(chips)!RES_0402-2.26K,1.0%,1/16W,CHIPA!!!F1013!A!!!!
S!FM_MB_SLOT_ID0!R7D5!2!@baseboard_fab2_lib.baseboard_fab2(sch_1):page181_i199@mstr_discrete.res(chips)!RES_0402-2.26K,1.0%,1/16W,CHIPA!!!F1013!B!!!!
S!P3V3_STBY!R7D9!1!@baseboard_fab2_lib.baseboard_fab2(sch_1):page181_i200@mstr_discrete.res(chips)!RES_0402-2.26K,1.0%,1/16W,CHIPA!!!F1012!A!!!!
S!FM_MB_SLOT_ID1!R7D9!2!@baseboard_fab2_lib.baseboard_fab2(sch_1):page181_i200@mstr_discrete.res(chips)!RES_0402-2.26K,1.0%,1/16W,CHIPA!!!F1012!B!!!!
S!P3V3_STBY!R7D11!1!@baseboard_fab2_lib.baseboard_fab2(sch_1):page181_i201@mstr_discrete.res(chips)!RES_0402-2.26K,1.0%,1/16W,CHIPA!!!F1011!A!!!!
S!FM_MB_SLOT_ID2!R7D11!2!@baseboard_fab2_lib.baseboard_fab2(sch_1):page181_i201@mstr_discrete.res(chips)!RES_0402-2.26K,1.0%,1/16W,CHIPA!!!F1011!B!!!!
S!P3V3_STBY!R4E4!1!@baseboard_fab2_lib.baseboard_fab2(sch_1):page201_i19@mstr_discrete.res(chips)!RES_0402-2.26K,1.0%,1/16W,CHIPA!!!F1014!A!!!!
S!FM_PVCCIN_CPU0_PWR_IN_ALERT_N!R4E4!2!@baseboard_fab2_lib.baseboard_fab2(sch_1):page201_i19@mstr_discrete.res(chips)!RES_0402-2.26K,1.0%,1/16W,CHIPA!!!F1014!B!!!!
S!P3V3_STBY!R1D7!1!@baseboard_fab2_lib.baseboard_fab2(sch_1):page206_i7@mstr_discrete.res(chips)!RES_0402-2.26K,1.0%,1/16W,CHIPA!!!F1015!A!!!!
S!FM_PVCCIN_CPU1_PWR_IN_ALERT_N!R1D7!2!@baseboard_fab2_lib.baseboard_fab2(sch_1):page206_i7@mstr_discrete.res(chips)!RES_0402-2.26K,1.0%,1/16W,CHIPA!!!F1015!B!!!!
S!SMB_SENSOR_STBY_LVC3_SCL!R8D24!1!@baseboard_fab2_lib.baseboard_fab2(sch_1):page167_i84@mstr_discrete.res(chips)!RES_0402-20.0,1%,1/16W,CHIP,G2A!!!F928!A!!!!
S!SMB_SENSOR_STBY_LVC3_SCL_R2!R8D24!2!@baseboard_fab2_lib.baseboard_fab2(sch_1):page167_i84@mstr_discrete.res(chips)!RES_0402-20.0,1%,1/16W,CHIP,G2A!!!F928!B!!!!
S!SMB_SENSOR_STBY_LVC3_SDA_R2!R8D23!1!@baseboard_fab2_lib.baseboard_fab2(sch_1):page167_i85@mstr_discrete.res(chips)!RES_0402-20.0,1%,1/16W,CHIP,G2A!!!F929!A!!!!
S!SMB_SENSOR_STBY_LVC3_SDA!R8D23!2!@baseboard_fab2_lib.baseboard_fab2(sch_1):page167_i85@mstr_discrete.res(chips)!RES_0402-20.0,1%,1/16W,CHIP,G2A!!!F929!B!!!!
S!SMB_SLOTX24_STBY_LVC3_SDA_R!R1T8!1!@baseboard_fab2_lib.baseboard_fab2(sch_1):page160_i4@mstr_discrete.res(chips)!RES_0402-20.0,1%,1/16W,CHIP,G2A!!!F976!A!!!!
S!SMB_SLOTX24_BMC_STBY_LVC3_SDA!R1T8!2!@baseboard_fab2_lib.baseboard_fab2(sch_1):page160_i4@mstr_discrete.res(chips)!RES_0402-20.0,1%,1/16W,CHIP,G2A!!!F976!B!!!!
S!SMB_SLOTX24_STBY_LVC3_SCL_R!R1T7!1!@baseboard_fab2_lib.baseboard_fab2(sch_1):page160_i50@mstr_discrete.res(chips)!RES_0402-20.0,1%,1/16W,CHIP,G2A!!!F977!A!!!!
S!SMB_SLOTX24_BMC_STBY_LVC3_SCL!R1T7!2!@baseboard_fab2_lib.baseboard_fab2(sch_1):page160_i50@mstr_discrete.res(chips)!RES_0402-20.0,1%,1/16W,CHIP,G2A!!!F977!B!!!!
S!SMB_LAN_STBY_LVC3_SDA_R!R9F23!1!@baseboard_fab2_lib.baseboard_fab2(sch_1):page160_i51@mstr_discrete.res(chips)!RES_0402-20.0,1%,1/16W,CHIP,G2A!!!F924!A!!!!
S!SMB_LAN_STBY_LVC3_SDA!R9F23!2!@baseboard_fab2_lib.baseboard_fab2(sch_1):page160_i51@mstr_discrete.res(chips)!RES_0402-20.0,1%,1/16W,CHIP,G2A!!!F924!B!!!!
S!SMB_LAN_STBY_LVC3_SCL_R!R9F22!1!@baseboard_fab2_lib.baseboard_fab2(sch_1):page160_i52@mstr_discrete.res(chips)!RES_0402-20.0,1%,1/16W,CHIP,G2A!!!F925!A!!!!
S!SMB_LAN_STBY_LVC3_SCL!R9F22!2!@baseboard_fab2_lib.baseboard_fab2(sch_1):page160_i52@mstr_discrete.res(chips)!RES_0402-20.0,1%,1/16W,CHIP,G2A!!!F925!B!!!!
S!SMB_SLOTX24_BMC_STBY_LVC3_SDA!R2U31!1!@baseboard_fab2_lib.baseboard_fab2(sch_1):page108_i330@mstr_discrete.res(chips)!RES_0402-20.0,1%,1/16W,CHIP,G2A!!!F961!A!!!!
S!SMB_SLOTX24_STBY_LVC3_SDA_R2!R2U31!2!@baseboard_fab2_lib.baseboard_fab2(sch_1):page108_i330@mstr_discrete.res(chips)!RES_0402-20.0,1%,1/16W,CHIP,G2A!!!F961!B!!!!
S!SMB_SLOTX24_BMC_STBY_LVC3_SCL!R2U32!1!@baseboard_fab2_lib.baseboard_fab2(sch_1):page108_i339@mstr_discrete.res(chips)!RES_0402-20.0,1%,1/16W,CHIP,G2A!!!F960!A!!!!
S!SMB_SLOTX24_STBY_LVC3_SCL_R2!R2U32!2!@baseboard_fab2_lib.baseboard_fab2(sch_1):page108_i339@mstr_discrete.res(chips)!RES_0402-20.0,1%,1/16W,CHIP,G2A!!!F960!B!!!!
S!SMB_OCP_LAN_STBY_LVC3_SDA!R9G12!1!@baseboard_fab2_lib.baseboard_fab2(sch_1):page159_i224@mstr_discrete.res(chips)!RES_0402-20.0,1%,1/16W,CHIP,G2A!!!F923!A!!!!
S!SMB_SPRINGVILLE_STBY_LVC3_SDA!R9G12!2!@baseboard_fab2_lib.baseboard_fab2(sch_1):page159_i224@mstr_discrete.res(chips)!RES_0402-20.0,1%,1/16W,CHIP,G2A!!!F923!B!!!!
S!SMB_SMLINK0_STBY_LVC3_SDA!R1U20!1!@baseboard_fab2_lib.baseboard_fab2(sch_1):page159_i225@mstr_discrete.res(chips)!RES_0402-20.0,1%,1/16W,CHIP,G2A!!!F972!A!!!!
S!SMB_SPRINGVILLE_STBY_LVC3_SDA!R1U20!2!@baseboard_fab2_lib.baseboard_fab2(sch_1):page159_i225@mstr_discrete.res(chips)!RES_0402-20.0,1%,1/16W,CHIP,G2A!!!F972!B!!!!
S!SMB_SMLINK0_STBY_LVC3_SCL!R1U19!1!@baseboard_fab2_lib.baseboard_fab2(sch_1):page159_i226@mstr_discrete.res(chips)!RES_0402-20.0,1%,1/16W,CHIP,G2A!!!F973!A!!!!
S!SMB_SPRINGVILLE_STBY_LVC3_SCL!R1U19!2!@baseboard_fab2_lib.baseboard_fab2(sch_1):page159_i226@mstr_discrete.res(chips)!RES_0402-20.0,1%,1/16W,CHIP,G2A!!!F973!B!!!!
S!SMB_OCP_LAN_STBY_LVC3_SCL!R9G13!1!@baseboard_fab2_lib.baseboard_fab2(sch_1):page159_i227@mstr_discrete.res(chips)!RES_0402-20.0,1%,1/16W,CHIP,G2A!!!F922!A!!!!
S!SMB_SPRINGVILLE_STBY_LVC3_SCL!R9G13!2!@baseboard_fab2_lib.baseboard_fab2(sch_1):page159_i227@mstr_discrete.res(chips)!RES_0402-20.0,1%,1/16W,CHIP,G2A!!!F922!B!!!!
S!SMB_SENSOR_BMC_STBY_LVC3_SDA!R9G15!1!@baseboard_fab2_lib.baseboard_fab2(sch_1):page167_i58@mstr_discrete.res(chips)!RES_0402-20.0,1%,1/16W,CHIP,G2A!!!F920!A!!!!
S!SMB_SENSOR_STBY_LVC3_SDA!R9G15!2!@baseboard_fab2_lib.baseboard_fab2(sch_1):page167_i58@mstr_discrete.res(chips)!RES_0402-20.0,1%,1/16W,CHIP,G2A!!!F920!B!!!!
S!SMB_SENSOR_BMC_STBY_LVC3_SCL!R9G14!1!@baseboard_fab2_lib.baseboard_fab2(sch_1):page167_i77@mstr_discrete.res(chips)!RES_0402-20.0,1%,1/16W,CHIP,G2A!!!F921!A!!!!
S!SMB_SENSOR_STBY_LVC3_SCL!R9G14!2!@baseboard_fab2_lib.baseboard_fab2(sch_1):page167_i77@mstr_discrete.res(chips)!RES_0402-20.0,1%,1/16W,CHIP,G2A!!!F921!B!!!!
S!SMB_SENSOR_PCH_STBY_LVC3_SDA!R1U31!1!@baseboard_fab2_lib.baseboard_fab2(sch_1):page167_i78@mstr_discrete.res(chips)!RES_0402-20.0,1%,1/16W,CHIP,G2A!!!F970!A!!!!
S!SMB_SENSOR_STBY_LVC3_SDA!R1U31!2!@baseboard_fab2_lib.baseboard_fab2(sch_1):page167_i78@mstr_discrete.res(chips)!RES_0402-20.0,1%,1/16W,CHIP,G2A!!!F970!B!!!!
S!SMB_SENSOR_PCH_STBY_LVC3_SCL!R1U25!1!@baseboard_fab2_lib.baseboard_fab2(sch_1):page167_i79@mstr_discrete.res(chips)!RES_0402-20.0,1%,1/16W,CHIP,G2A!!!F971!A!!!!
S!SMB_SENSOR_STBY_LVC3_SCL!R1U25!2!@baseboard_fab2_lib.baseboard_fab2(sch_1):page167_i79@mstr_discrete.res(chips)!RES_0402-20.0,1%,1/16W,CHIP,G2A!!!F971!B!!!!
S!SMB_PEHPCPU1_STBY_LVC3_R_SCL!R9M14!1!@baseboard_fab2_lib.baseboard_fab2(sch_1):page163_i20@mstr_discrete.res(chips)!RES_0402-20.0,1%,1/16W,CHIP,G2A!!!F917!A!!!!
S!SMB_PEHPCPU1_STBY_LVC3_SCL!R9M14!2!@baseboard_fab2_lib.baseboard_fab2(sch_1):page163_i20@mstr_discrete.res(chips)!RES_0402-20.0,1%,1/16W,CHIP,G2A!!!F917!B!!!!
S!SMB_PEHPCPU1_STBY_LVC3_R_SCL!R9M15!1!@baseboard_fab2_lib.baseboard_fab2(sch_1):page163_i25@mstr_discrete.res(chips)!RES_0402-20.0,1%,1/16W,CHIP,G2A!!!F916!A!!!!
S!SMB_SLOTX24_BMC_STBY_LVC3_SCL!R9M15!2!@baseboard_fab2_lib.baseboard_fab2(sch_1):page163_i25@mstr_discrete.res(chips)!RES_0402-20.0,1%,1/16W,CHIP,G2A!!!F916!B!!!!
S!SMB_PEHPCPU1_STBY_LVC3_R_SDA!R9M13!1!@baseboard_fab2_lib.baseboard_fab2(sch_1):page163_i21@mstr_discrete.res(chips)!RES_0402-20.0,1%,1/16W,CHIP,G2A!!!F918!A!!!!
S!SMB_PEHPCPU1_STBY_LVC3_SDA!R9M13!2!@baseboard_fab2_lib.baseboard_fab2(sch_1):page163_i21@mstr_discrete.res(chips)!RES_0402-20.0,1%,1/16W,CHIP,G2A!!!F918!B!!!!
S!SMB_PEHPCPU1_STBY_LVC3_R_SDA!R9M12!1!@baseboard_fab2_lib.baseboard_fab2(sch_1):page163_i24@mstr_discrete.res(chips)!RES_0402-20.0,1%,1/16W,CHIP,G2A!!!F919!A!!!!
S!SMB_SLOTX24_BMC_STBY_LVC3_SDA!R9M12!2!@baseboard_fab2_lib.baseboard_fab2(sch_1):page163_i24@mstr_discrete.res(chips)!RES_0402-20.0,1%,1/16W,CHIP,G2A!!!F919!B!!!!
S!SMB_PMBUS_BMC_STBY_LVC3_SDA_R1!R2T55!1!@baseboard_fab2_lib.baseboard_fab2(sch_1):page138_i116@mstr_discrete.res(chips)!RES_0402-20.0,1%,1/16W,CHIP,G2A!!!F968!A!!!!
S!SMB_BMC_PMBUS_STBY_LVC3_SDA!R2T55!2!@baseboard_fab2_lib.baseboard_fab2(sch_1):page138_i116@mstr_discrete.res(chips)!RES_0402-20.0,1%,1/16W,CHIP,G2A!!!F968!B!!!!
S!SMB_PMBUS_BMC_STBY_LVC3_SCL_R1!R2T56!1!@baseboard_fab2_lib.baseboard_fab2(sch_1):page138_i160@mstr_discrete.res(chips)!RES_0402-20.0,1%,1/16W,CHIP,G2A!!!F967!A!!!!
S!SMB_BMC_PMBUS_STBY_LVC3_SCL!R2T56!2!@baseboard_fab2_lib.baseboard_fab2(sch_1):page138_i160@mstr_discrete.res(chips)!RES_0402-20.0,1%,1/16W,CHIP,G2A!!!F967!B!!!!
S!SMB_SMLINK0_STBY_LVC3_SDA_R1!R8C11!1!@baseboard_fab2_lib.baseboard_fab2(sch_1):page138_i169@mstr_discrete.res(chips)!RES_0402-20.0,1%,1/16W,CHIP,G2A!!!F937!A!!!!
S!SMB_SMLINK0_STBY_LVC3_SDA!R8C11!2!@baseboard_fab2_lib.baseboard_fab2(sch_1):page138_i169@mstr_discrete.res(chips)!RES_0402-20.0,1%,1/16W,CHIP,G2A!!!F937!B!!!!
S!SMB_SMLINK0_STBY_LVC3_SCL_R1!R8C12!1!@baseboard_fab2_lib.baseboard_fab2(sch_1):page138_i170@mstr_discrete.res(chips)!RES_0402-20.0,1%,1/16W,CHIP,G2A!!!F936!A!!!!
S!SMB_SMLINK0_STBY_LVC3_SCL!R8C12!2!@baseboard_fab2_lib.baseboard_fab2(sch_1):page138_i170@mstr_discrete.res(chips)!RES_0402-20.0,1%,1/16W,CHIP,G2A!!!F936!B!!!!
S!SMB_HOST_STBY_LVC3_SDA_R1!R8C20!1!@baseboard_fab2_lib.baseboard_fab2(sch_1):page138_i167@mstr_discrete.res(chips)!RES_0402-20.0,1%,1/16W,CHIP,G2A!!!F934!A!!!!
S!SMB_HOST_STBY_LVC3_SDA!R8C20!2!@baseboard_fab2_lib.baseboard_fab2(sch_1):page138_i167@mstr_discrete.res(chips)!RES_0402-20.0,1%,1/16W,CHIP,G2A!!!F934!B!!!!
S!SMB_HOST_STBY_LVC3_SCL_R1!R8C14!1!@baseboard_fab2_lib.baseboard_fab2(sch_1):page138_i168@mstr_discrete.res(chips)!RES_0402-20.0,1%,1/16W,CHIP,G2A!!!F935!A!!!!
S!SMB_HOST_STBY_LVC3_SCL!R8C14!2!@baseboard_fab2_lib.baseboard_fab2(sch_1):page138_i168@mstr_discrete.res(chips)!RES_0402-20.0,1%,1/16W,CHIP,G2A!!!F935!B!!!!
S!SMB_VR_STBY_LVC3_SCL!R3P24!1!@baseboard_fab2_lib.baseboard_fab2(sch_1):page211_i46@mstr_discrete.res(chips)!RES_0402-20.0,1%,1/16W,CHIP,G2A!!!F956!A!!!!
S!SMB_VR_SCL_PVCCIO_CPU0!R3P24!2!@baseboard_fab2_lib.baseboard_fab2(sch_1):page211_i46@mstr_discrete.res(chips)!RES_0402-20.0,1%,1/16W,CHIP,G2A!!!F956!B!!!!
S!SMB_VR_SCL_VDDQ_ABC!R7F25!1!@baseboard_fab2_lib.baseboard_fab2(sch_1):page215_i298@mstr_discrete.res(chips)!RES_0402-20.0,1%,1/16W,CHIP,G2A!!!F945!A!!!!
S!SMB_VR_STBY_LVC3_SCL!R7F25!2!@baseboard_fab2_lib.baseboard_fab2(sch_1):page215_i298@mstr_discrete.res(chips)!RES_0402-20.0,1%,1/16W,CHIP,G2A!!!F945!B!!!!
S!SMB_BMC_PMBUS_STBY_LVC3_SDA_R!R2T49!1!@baseboard_fab2_lib.baseboard_fab2(sch_1):page159_i219@mstr_discrete.res(chips)!RES_0402-20.0,1%,1/16W,CHIP,G2A!!!F969!A!!!!
S!SMB_BMC_PMBUS_STBY_LVC3_SDA!R2T49!2!@baseboard_fab2_lib.baseboard_fab2(sch_1):page159_i219@mstr_discrete.res(chips)!RES_0402-20.0,1%,1/16W,CHIP,G2A!!!F969!B!!!!
S!SMB_BMC_PMBUS_STBY_LVC3_SCL_R!R2U1!1!@baseboard_fab2_lib.baseboard_fab2(sch_1):page159_i218@mstr_discrete.res(chips)!RES_0402-20.0,1%,1/16W,CHIP,G2A!!!F966!A!!!!
S!SMB_BMC_PMBUS_STBY_LVC3_SCL!R2U1!2!@baseboard_fab2_lib.baseboard_fab2(sch_1):page159_i218@mstr_discrete.res(chips)!RES_0402-20.0,1%,1/16W,CHIP,G2A!!!F966!B!!!!
S!SMB_VR_SDA_VDDQ_DEF!R7B2!1!@baseboard_fab2_lib.baseboard_fab2(sch_1):page218_i24@mstr_discrete.res(chips)!RES_0402-20.0,1%,1/16W,CHIP,G2A!!!F947!A!!!!
S!SMB_VR_STBY_LVC3_SDA!R7B2!2!@baseboard_fab2_lib.baseboard_fab2(sch_1):page218_i24@mstr_discrete.res(chips)!RES_0402-20.0,1%,1/16W,CHIP,G2A!!!F947!B!!!!
S!SMB_VR_SCL_VDDQ_DEF!R7B3!1!@baseboard_fab2_lib.baseboard_fab2(sch_1):page218_i21@mstr_discrete.res(chips)!RES_0402-20.0,1%,1/16W,CHIP,G2A!!!F946!A!!!!
S!SMB_VR_STBY_LVC3_SCL!R7B3!2!@baseboard_fab2_lib.baseboard_fab2(sch_1):page218_i21@mstr_discrete.res(chips)!RES_0402-20.0,1%,1/16W,CHIP,G2A!!!F946!B!!!!
S!SMB_VR_SDA_VDDQ_KLM!R1B7!1!@baseboard_fab2_lib.baseboard_fab2(sch_1):page226_i22@mstr_discrete.res(chips)!RES_0402-20.0,1%,1/16W,CHIP,G2A!!!F980!A!!!!
S!SMB_VR_STBY_LVC3_SDA!R1B7!2!@baseboard_fab2_lib.baseboard_fab2(sch_1):page226_i22@mstr_discrete.res(chips)!RES_0402-20.0,1%,1/16W,CHIP,G2A!!!F980!B!!!!
S!SMB_VR_SCL_VDDQ_KLM!R1B6!1!@baseboard_fab2_lib.baseboard_fab2(sch_1):page226_i21@mstr_discrete.res(chips)!RES_0402-20.0,1%,1/16W,CHIP,G2A!!!F981!A!!!!
S!SMB_VR_STBY_LVC3_SCL!R1B6!2!@baseboard_fab2_lib.baseboard_fab2(sch_1):page226_i21@mstr_discrete.res(chips)!RES_0402-20.0,1%,1/16W,CHIP,G2A!!!F981!B!!!!
S!SMB_OCP_FRU_STBY_LVC3_SDA_R!R2U10!1!@baseboard_fab2_lib.baseboard_fab2(sch_1):page159_i221@mstr_discrete.res(chips)!RES_0402-20.0,1%,1/16W,CHIP,G2A!!!F962!A!!!!
S!SMB_OCP_FRU_STBY_LVC3_SDA!R2U10!2!@baseboard_fab2_lib.baseboard_fab2(sch_1):page159_i221@mstr_discrete.res(chips)!RES_0402-20.0,1%,1/16W,CHIP,G2A!!!F962!B!!!!
S!SMB_OCP_FRU_STBY_LVC3_SCL_R!R2U7!1!@baseboard_fab2_lib.baseboard_fab2(sch_1):page159_i220@mstr_discrete.res(chips)!RES_0402-20.0,1%,1/16W,CHIP,G2A!!!F964!A!!!!
S!SMB_OCP_FRU_STBY_LVC3_SCL!R2U7!2!@baseboard_fab2_lib.baseboard_fab2(sch_1):page159_i220@mstr_discrete.res(chips)!RES_0402-20.0,1%,1/16W,CHIP,G2A!!!F964!B!!!!
S!SMB_SLOTX24_STBY_LVC3_SCL_R1!R8B28!1!@baseboard_fab2_lib.baseboard_fab2(sch_1):page138_i174@mstr_discrete.res(chips)!RES_0402-20.0,1%,1/16W,CHIP,G2A!!!F938!A!!!!
S!SMB_SLOTX24_PCH_STBY_LVC3_SCL!R8B28!2!@baseboard_fab2_lib.baseboard_fab2(sch_1):page138_i174@mstr_discrete.res(chips)!RES_0402-20.0,1%,1/16W,CHIP,G2A!!!F938!B!!!!
S!SMB_SLOTX24_STBY_LVC3_SDA_R1!R8B27!1!@baseboard_fab2_lib.baseboard_fab2(sch_1):page138_i173@mstr_discrete.res(chips)!RES_0402-20.0,1%,1/16W,CHIP,G2A!!!F939!A!!!!
S!SMB_SLOTX24_PCH_STBY_LVC3_SDA!R8B27!2!@baseboard_fab2_lib.baseboard_fab2(sch_1):page138_i173@mstr_discrete.res(chips)!RES_0402-20.0,1%,1/16W,CHIP,G2A!!!F939!B!!!!
S!SMB_SENSOR_TMP421_1_SDA!R1M9!1!@baseboard_fab2_lib.baseboard_fab2(sch_1):page167_i8@mstr_discrete.res(chips)!RES_0402-20.0,1%,1/16W,CHIP,G2A!!!F978!A!!!!
S!SMB_SENSOR_STBY_LVC3_SDA!R1M9!2!@baseboard_fab2_lib.baseboard_fab2(sch_1):page167_i8@mstr_discrete.res(chips)!RES_0402-20.0,1%,1/16W,CHIP,G2A!!!F978!B!!!!
S!SMB_SENSOR_TMP421_2_SDA!R9R8!1!@baseboard_fab2_lib.baseboard_fab2(sch_1):page167_i76@mstr_discrete.res(chips)!RES_0402-20.0,1%,1/16W,CHIP,G2A!!!F914!A!!!!
S!SMB_SENSOR_STBY_LVC3_SDA!R9R8!2!@baseboard_fab2_lib.baseboard_fab2(sch_1):page167_i76@mstr_discrete.res(chips)!RES_0402-20.0,1%,1/16W,CHIP,G2A!!!F914!B!!!!
S!SMB_SENSOR_TMP421_1_SCL!R1M8!1!@baseboard_fab2_lib.baseboard_fab2(sch_1):page167_i74@mstr_discrete.res(chips)!RES_0402-20.0,1%,1/16W,CHIP,G2A!!!F979!A!!!!
S!SMB_SENSOR_STBY_LVC3_SCL!R1M8!2!@baseboard_fab2_lib.baseboard_fab2(sch_1):page167_i74@mstr_discrete.res(chips)!RES_0402-20.0,1%,1/16W,CHIP,G2A!!!F979!B!!!!
S!SMB_SENSOR_TMP421_2_SCL!R9R7!1!@baseboard_fab2_lib.baseboard_fab2(sch_1):page167_i75@mstr_discrete.res(chips)!RES_0402-20.0,1%,1/16W,CHIP,G2A!!!F915!A!!!!
S!SMB_SENSOR_STBY_LVC3_SCL!R9R7!2!@baseboard_fab2_lib.baseboard_fab2(sch_1):page167_i75@mstr_discrete.res(chips)!RES_0402-20.0,1%,1/16W,CHIP,G2A!!!F915!B!!!!
S!SMB_LAN_STBY_LVC3_SDA_R1!R2U9!1!@baseboard_fab2_lib.baseboard_fab2(sch_1):page138_i165@mstr_discrete.res(chips)!RES_0402-20.0,1%,1/16W,CHIP,G2A!!!F963!A!!!!
S!SMB_LAN_STBY_LVC3_SDA!R2U9!2!@baseboard_fab2_lib.baseboard_fab2(sch_1):page138_i165@mstr_discrete.res(chips)!RES_0402-20.0,1%,1/16W,CHIP,G2A!!!F963!B!!!!
S!SMB_LAN_STBY_LVC3_SCL_R1!R2U6!1!@baseboard_fab2_lib.baseboard_fab2(sch_1):page138_i166@mstr_discrete.res(chips)!RES_0402-20.0,1%,1/16W,CHIP,G2A!!!F965!A!!!!
S!SMB_LAN_STBY_LVC3_SCL!R2U6!2!@baseboard_fab2_lib.baseboard_fab2(sch_1):page138_i166@mstr_discrete.res(chips)!RES_0402-20.0,1%,1/16W,CHIP,G2A!!!F965!B!!!!
S!SMB_SENSOR_STBY_LVC3_SDA_R1!R8D6!1!@baseboard_fab2_lib.baseboard_fab2(sch_1):page138_i162@mstr_discrete.res(chips)!RES_0402-20.0,1%,1/16W,CHIP,G2A!!!F931!A!!!!
S!SMB_SENSOR_PCH_STBY_LVC3_SDA!R8D6!2!@baseboard_fab2_lib.baseboard_fab2(sch_1):page138_i162@mstr_discrete.res(chips)!RES_0402-20.0,1%,1/16W,CHIP,G2A!!!F931!B!!!!
S!SMB_SENSOR_STBY_LVC3_SCL_R1!R8D3!1!@baseboard_fab2_lib.baseboard_fab2(sch_1):page138_i161@mstr_discrete.res(chips)!RES_0402-20.0,1%,1/16W,CHIP,G2A!!!F933!A!!!!
S!SMB_SENSOR_PCH_STBY_LVC3_SCL!R8D3!2!@baseboard_fab2_lib.baseboard_fab2(sch_1):page138_i161@mstr_discrete.res(chips)!RES_0402-20.0,1%,1/16W,CHIP,G2A!!!F933!B!!!!
S!SMB_VR_STBY_LVC3_SDA_R1!R8D7!1!@baseboard_fab2_lib.baseboard_fab2(sch_1):page138_i163@mstr_discrete.res(chips)!RES_0402-20.0,1%,1/16W,CHIP,G2A!!!F930!A!!!!
S!SMB_VR_STBY_LVC3_SDA!R8D7!2!@baseboard_fab2_lib.baseboard_fab2(sch_1):page138_i163@mstr_discrete.res(chips)!RES_0402-20.0,1%,1/16W,CHIP,G2A!!!F930!B!!!!
S!SMB_VR_STBY_LVC3_SCL_R1!R8D4!1!@baseboard_fab2_lib.baseboard_fab2(sch_1):page138_i164@mstr_discrete.res(chips)!RES_0402-20.0,1%,1/16W,CHIP,G2A!!!F932!A!!!!
S!SMB_VR_STBY_LVC3_SCL!R8D4!2!@baseboard_fab2_lib.baseboard_fab2(sch_1):page138_i164@mstr_discrete.res(chips)!RES_0402-20.0,1%,1/16W,CHIP,G2A!!!F932!B!!!!
S!SMB_SMLINK0_STBY_LVC3_SDA_R!R1U10!1!@baseboard_fab2_lib.baseboard_fab2(sch_1):page159_i233@mstr_discrete.res(chips)!RES_0402-20.0,1%,1/16W,CHIP,G2A!!!F974!A!!!!
S!SMB_SMLINK0_STBY_LVC3_SDA!R1U10!2!@baseboard_fab2_lib.baseboard_fab2(sch_1):page159_i233@mstr_discrete.res(chips)!RES_0402-20.0,1%,1/16W,CHIP,G2A!!!F974!B!!!!
S!SMB_SMLINK0_STBY_LVC3_SCL_R!R1U9!1!@baseboard_fab2_lib.baseboard_fab2(sch_1):page159_i232@mstr_discrete.res(chips)!RES_0402-20.0,1%,1/16W,CHIP,G2A!!!F975!A!!!!
S!SMB_SMLINK0_STBY_LVC3_SCL!R1U9!2!@baseboard_fab2_lib.baseboard_fab2(sch_1):page159_i232@mstr_discrete.res(chips)!RES_0402-20.0,1%,1/16W,CHIP,G2A!!!F975!B!!!!
S!SMB_HOST_STBY_LVC3_SDA_R!R2U33!1!@baseboard_fab2_lib.baseboard_fab2(sch_1):page159_i231@mstr_discrete.res(chips)!RES_0402-20.0,1%,1/16W,CHIP,G2A!!!F959!A!!!!
S!SMB_HOST_STBY_LVC3_SDA!R2U33!2!@baseboard_fab2_lib.baseboard_fab2(sch_1):page159_i231@mstr_discrete.res(chips)!RES_0402-20.0,1%,1/16W,CHIP,G2A!!!F959!B!!!!
S!SMB_HOST_STBY_LVC3_SCL_R!R2U34!1!@baseboard_fab2_lib.baseboard_fab2(sch_1):page159_i230@mstr_discrete.res(chips)!RES_0402-20.0,1%,1/16W,CHIP,G2A!!!F958!A!!!!
S!SMB_HOST_STBY_LVC3_SCL!R2U34!2!@baseboard_fab2_lib.baseboard_fab2(sch_1):page159_i230@mstr_discrete.res(chips)!RES_0402-20.0,1%,1/16W,CHIP,G2A!!!F958!B!!!!
S!SMB_OCP_LAN_STBY_LVC3_SDA_R!R8G5!1!@baseboard_fab2_lib.baseboard_fab2(sch_1):page159_i228@mstr_discrete.res(chips)!RES_0402-20.0,1%,1/16W,CHIP,G2A!!!F926!A!!!!
S!SMB_OCP_LAN_STBY_LVC3_SDA!R8G5!2!@baseboard_fab2_lib.baseboard_fab2(sch_1):page159_i228@mstr_discrete.res(chips)!RES_0402-20.0,1%,1/16W,CHIP,G2A!!!F926!B!!!!
S!SMB_OCP_LAN_STBY_LVC3_SCL_R!R8G4!1!@baseboard_fab2_lib.baseboard_fab2(sch_1):page159_i229@mstr_discrete.res(chips)!RES_0402-20.0,1%,1/16W,CHIP,G2A!!!F927!A!!!!
S!SMB_OCP_LAN_STBY_LVC3_SCL!R8G4!2!@baseboard_fab2_lib.baseboard_fab2(sch_1):page159_i229@mstr_discrete.res(chips)!RES_0402-20.0,1%,1/16W,CHIP,G2A!!!F927!B!!!!
S!SMB_VR_STBY_LVC3_SDA!R4D44!1!@baseboard_fab2_lib.baseboard_fab2(sch_1):page213_i38@mstr_discrete.res(chips)!RES_0402-20.0,1%,1/16W,CHIP,G2A!!!F952!A!!!!
S!SMB_VR_SDA_PVCCIO_CPU1!R4D44!2!@baseboard_fab2_lib.baseboard_fab2(sch_1):page213_i38@mstr_discrete.res(chips)!RES_0402-20.0,1%,1/16W,CHIP,G2A!!!F952!B!!!!
S!SMB_VR_SDA_VDDQ_ABC!R7F26!1!@baseboard_fab2_lib.baseboard_fab2(sch_1):page215_i304@mstr_discrete.res(chips)!RES_0402-20.0,1%,1/16W,CHIP,G2A!!!F944!A!!!!
S!SMB_VR_STBY_LVC3_SDA!R7F26!2!@baseboard_fab2_lib.baseboard_fab2(sch_1):page215_i304@mstr_discrete.res(chips)!RES_0402-20.0,1%,1/16W,CHIP,G2A!!!F944!B!!!!
S!SMB_VR_STBY_LVC3_SDA!R3P23!1!@baseboard_fab2_lib.baseboard_fab2(sch_1):page211_i47@mstr_discrete.res(chips)!RES_0402-20.0,1%,1/16W,CHIP,G2A!!!F957!A!!!!
S!SMB_VR_SDA_PVCCIO_CPU0!R3P23!2!@baseboard_fab2_lib.baseboard_fab2(sch_1):page211_i47@mstr_discrete.res(chips)!RES_0402-20.0,1%,1/16W,CHIP,G2A!!!F957!B!!!!
S!SMB_VR_STBY_LVC3_SCL!R4D43!1!@baseboard_fab2_lib.baseboard_fab2(sch_1):page213_i39@mstr_discrete.res(chips)!RES_0402-20.0,1%,1/16W,CHIP,G2A!!!F953!A!!!!
S!SMB_VR_SCL_PVCCIO_CPU1!R4D43!2!@baseboard_fab2_lib.baseboard_fab2(sch_1):page213_i39@mstr_discrete.res(chips)!RES_0402-20.0,1%,1/16W,CHIP,G2A!!!F953!B!!!!
S!SMB_VR_STBY_LVC3_SDA!R8A8!1!@baseboard_fab2_lib.baseboard_fab2(sch_1):page235_i172@mstr_discrete.res(chips)!RES_0402-20.0,1%,1/16W,CHIP,G2A!!!F941!A!!!!
S!SMB_VR_SDA_PVNN_PCH!R8A8!2!@baseboard_fab2_lib.baseboard_fab2(sch_1):page235_i172@mstr_discrete.res(chips)!RES_0402-20.0,1%,1/16W,CHIP,G2A!!!F941!B!!!!
S!SMB_VR_STBY_LVC3_SCL!R8A9!1!@baseboard_fab2_lib.baseboard_fab2(sch_1):page235_i173@mstr_discrete.res(chips)!RES_0402-20.0,1%,1/16W,CHIP,G2A!!!F940!A!!!!
S!SMB_VR_SCL_PVNN_PCH!R8A9!2!@baseboard_fab2_lib.baseboard_fab2(sch_1):page235_i173@mstr_discrete.res(chips)!RES_0402-20.0,1%,1/16W,CHIP,G2A!!!F940!B!!!!
S!SMB_DDR_DEF_VPP_SDA_R!R3R9!1!@baseboard_fab2_lib.baseboard_fab2(sch_1):page99_i34@mstr_discrete.res(chips)!RES_0402-20.0,1%,1/16W,CHIP,G2A!!!F954!A!!!!
S!SMB_DDR_DEF_VPP_SDA!R3R9!2!@baseboard_fab2_lib.baseboard_fab2(sch_1):page99_i34@mstr_discrete.res(chips)!RES_0402-20.0,1%,1/16W,CHIP,G2A!!!F954!B!!!!
S!SMB_DDR_DEF_VPP_SCL_R!R3R8!1!@baseboard_fab2_lib.baseboard_fab2(sch_1):page99_i35@mstr_discrete.res(chips)!RES_0402-20.0,1%,1/16W,CHIP,G2A!!!F955!A!!!!
S!SMB_DDR_DEF_VPP_SCL!R3R8!2!@baseboard_fab2_lib.baseboard_fab2(sch_1):page99_i35@mstr_discrete.res(chips)!RES_0402-20.0,1%,1/16W,CHIP,G2A!!!F955!B!!!!
S!SMB_DDR_GHJ_VPP_SDA_R!R6U14!1!@baseboard_fab2_lib.baseboard_fab2(sch_1):page99_i43@mstr_discrete.res(chips)!RES_0402-20.0,1%,1/16W,CHIP,G2A!!!F948!A!!!!
S!SMB_DDR_GHJ_VPP_SDA!R6U14!2!@baseboard_fab2_lib.baseboard_fab2(sch_1):page99_i43@mstr_discrete.res(chips)!RES_0402-20.0,1%,1/16W,CHIP,G2A!!!F948!B!!!!
S!SMB_DDR_GHJ_VPP_SCL_R!R6U13!1!@baseboard_fab2_lib.baseboard_fab2(sch_1):page99_i42@mstr_discrete.res(chips)!RES_0402-20.0,1%,1/16W,CHIP,G2A!!!F949!A!!!!
S!SMB_DDR_GHJ_VPP_SCL!R6U13!2!@baseboard_fab2_lib.baseboard_fab2(sch_1):page99_i42@mstr_discrete.res(chips)!RES_0402-20.0,1%,1/16W,CHIP,G2A!!!F949!B!!!!
S!SMB_DDR_ABC_VPP_SDA_R!R4T10!1!@baseboard_fab2_lib.baseboard_fab2(sch_1):page99_i10@mstr_discrete.res(chips)!RES_0402-20.0,1%,1/16W,CHIP,G2A!!!F950!A!!!!
S!SMB_DDR_ABC_VPP_SDA!R4T10!2!@baseboard_fab2_lib.baseboard_fab2(sch_1):page99_i10@mstr_discrete.res(chips)!RES_0402-20.0,1%,1/16W,CHIP,G2A!!!F950!B!!!!
S!SMB_DDR_KLM_VPP_SCL_R!R7M4!1!@baseboard_fab2_lib.baseboard_fab2(sch_1):page99_i56@mstr_discrete.res(chips)!RES_0402-20.0,1%,1/16W,CHIP,G2A!!!F943!A!!!!
S!SMB_DDR_KLM_VPP_SCL!R7M4!2!@baseboard_fab2_lib.baseboard_fab2(sch_1):page99_i56@mstr_discrete.res(chips)!RES_0402-20.0,1%,1/16W,CHIP,G2A!!!F943!B!!!!
S!SMB_DDR_KLM_VPP_SDA_R!R7M5!1!@baseboard_fab2_lib.baseboard_fab2(sch_1):page99_i55@mstr_discrete.res(chips)!RES_0402-20.0,1%,1/16W,CHIP,G2A!!!F942!A!!!!
S!SMB_DDR_KLM_VPP_SDA!R7M5!2!@baseboard_fab2_lib.baseboard_fab2(sch_1):page99_i55@mstr_discrete.res(chips)!RES_0402-20.0,1%,1/16W,CHIP,G2A!!!F942!B!!!!
S!SMB_DDR_ABC_VPP_SCL_R!R4T9!1!@baseboard_fab2_lib.baseboard_fab2(sch_1):page99_i9@mstr_discrete.res(chips)!RES_0402-20.0,1%,1/16W,CHIP,G2A!!!F951!A!!!!
S!SMB_DDR_ABC_VPP_SCL!R4T9!2!@baseboard_fab2_lib.baseboard_fab2(sch_1):page99_i9@mstr_discrete.res(chips)!RES_0402-20.0,1%,1/16W,CHIP,G2A!!!F951!B!!!!
S!PVCCIO_CPU0!R6D7!1!@baseboard_fab2_lib.baseboard_fab2(sch_1):page90_i31@mstr_discrete.res(chips)!RES_0402-240,1.0%,1/16W,CHIP,GA!!!F832!A!!!!
S!H_CPU0_BMCINIT!R6D7!2!@baseboard_fab2_lib.baseboard_fab2(sch_1):page90_i31@mstr_discrete.res(chips)!RES_0402-240,1.0%,1/16W,CHIP,GA!!!F832!B!!!!
S!PVCCIO_CPU0!R5D4!1!@baseboard_fab2_lib.baseboard_fab2(sch_1):page90_i32@mstr_discrete.res(chips)!RES_0402-240,1.0%,1/16W,CHIP,GA!!!F833!A!!!!
S!PU_CPU0_TXT_AGENT!R5D4!2!@baseboard_fab2_lib.baseboard_fab2(sch_1):page90_i32@mstr_discrete.res(chips)!RES_0402-240,1.0%,1/16W,CHIP,GA!!!F833!B!!!!
S!PVCCIO_CPU1!R9M19!1!@baseboard_fab2_lib.baseboard_fab2(sch_1):page163_i7@mstr_discrete.res(chips)!RES_0402-240,1.0%,1/16W,CHIP,GA!!!F825!A!!!!
S!SMB_CPU1_PE_HP_GTL_R_SCL!R9M19!2!@baseboard_fab2_lib.baseboard_fab2(sch_1):page163_i7@mstr_discrete.res(chips)!RES_0402-240,1.0%,1/16W,CHIP,GA!!!F825!B!!!!
S!PVCCIO_CPU1!R9M18!1!@baseboard_fab2_lib.baseboard_fab2(sch_1):page163_i6@mstr_discrete.res(chips)!RES_0402-240,1.0%,1/16W,CHIP,GA!!!F826!A!!!!
S!SMB_CPU1_PE_HP_GTL_R_SDA!R9M18!2!@baseboard_fab2_lib.baseboard_fab2(sch_1):page163_i6@mstr_discrete.res(chips)!RES_0402-240,1.0%,1/16W,CHIP,GA!!!F826!B!!!!
S!GND!R7P14!1!@baseboard_fab2_lib.baseboard_fab2(sch_1):page90_i70@mstr_discrete.res(chips)!RES_0402-240,1.0%,1/16W,CHIP,GA!!!F827!A!!!!
S!PD_CPU1_DMIMODE_OVERRIDE!R7P14!2!@baseboard_fab2_lib.baseboard_fab2(sch_1):page90_i70@mstr_discrete.res(chips)!RES_0402-240,1.0%,1/16W,CHIP,GA!!!F827!B!!!!
S!PVCCIO_CPU0!R4P14!1!@baseboard_fab2_lib.baseboard_fab2(sch_1):page90_i53@mstr_discrete.res(chips)!RES_0402-240,1.0%,1/16W,CHIP,GA!!!F838!A!!!!
S!PU_CPU0_LEGACY_SKT!R4P14!2!@baseboard_fab2_lib.baseboard_fab2(sch_1):page90_i53@mstr_discrete.res(chips)!RES_0402-240,1.0%,1/16W,CHIP,GA!!!F838!B!!!!
S!PVCCIO_CPU0!R4P21!1!@baseboard_fab2_lib.baseboard_fab2(sch_1):page97_i72@mstr_discrete.res(chips)!RES_0402-240,1.0%,1/16W,CHIP,GA!!!F837!A!!!!
S!PU_CPU0_TSC_SYNC!R4P21!2!@baseboard_fab2_lib.baseboard_fab2(sch_1):page97_i72@mstr_discrete.res(chips)!RES_0402-240,1.0%,1/16W,CHIP,GA!!!F837!B!!!!
S!PVCCIO_CPU1!R4C10!1!@baseboard_fab2_lib.baseboard_fab2(sch_1):page97_i76@mstr_discrete.res(chips)!RES_0402-240,1.0%,1/16W,CHIP,GA!!!F839!A!!!!
S!PU_CPU1_TSC_SYNC!R4C10!2!@baseboard_fab2_lib.baseboard_fab2(sch_1):page97_i76@mstr_discrete.res(chips)!RES_0402-240,1.0%,1/16W,CHIP,GA!!!F839!B!!!!
S!PVCCIO_CPU0!R3R13!1!@baseboard_fab2_lib.baseboard_fab2(sch_1):page99_i65@mstr_discrete.res(chips)!RES_0402-240,1.0%,1/16W,CHIP,GA!!!F840!A!!!!
S!SMB_DDR_DEF_SDA_G!R3R13!2!@baseboard_fab2_lib.baseboard_fab2(sch_1):page99_i65@mstr_discrete.res(chips)!RES_0402-240,1.0%,1/16W,CHIP,GA!!!F840!B!!!!
S!PVCCIO_CPU0!R3P60!1!@baseboard_fab2_lib.baseboard_fab2(sch_1):page99_i67@mstr_discrete.res(chips)!RES_0402-240,1.0%,1/16W,CHIP,GA!!!F841!A!!!!
S!SMB_DDR_DEF_SCL_G!R3P60!2!@baseboard_fab2_lib.baseboard_fab2(sch_1):page99_i67@mstr_discrete.res(chips)!RES_0402-240,1.0%,1/16W,CHIP,GA!!!F841!B!!!!
S!PVCCIO_CPU1!R6T2!1!@baseboard_fab2_lib.baseboard_fab2(sch_1):page99_i72@mstr_discrete.res(chips)!RES_0402-240,1.0%,1/16W,CHIP,GA!!!F830!A!!!!
S!SMB_DDR_GHJ_SCL_G!R6T2!2!@baseboard_fab2_lib.baseboard_fab2(sch_1):page99_i72@mstr_discrete.res(chips)!RES_0402-240,1.0%,1/16W,CHIP,GA!!!F830!B!!!!
S!PVCCIO_CPU1!R6T1!1!@baseboard_fab2_lib.baseboard_fab2(sch_1):page99_i70@mstr_discrete.res(chips)!RES_0402-240,1.0%,1/16W,CHIP,GA!!!F831!A!!!!
S!SMB_DDR_GHJ_SDA_G!R6T1!2!@baseboard_fab2_lib.baseboard_fab2(sch_1):page99_i70@mstr_discrete.res(chips)!RES_0402-240,1.0%,1/16W,CHIP,GA!!!F831!B!!!!
S!PVCCIO_CPU0!R4T5!1!@baseboard_fab2_lib.baseboard_fab2(sch_1):page99_i19@mstr_discrete.res(chips)!RES_0402-240,1.0%,1/16W,CHIP,GA!!!F836!A!!!!
S!SMB_DDR_ABC_SCL_G!R4T5!2!@baseboard_fab2_lib.baseboard_fab2(sch_1):page99_i19@mstr_discrete.res(chips)!RES_0402-240,1.0%,1/16W,CHIP,GA!!!F836!B!!!!
S!PVCCIO_CPU0!R5D3!1!@baseboard_fab2_lib.baseboard_fab2(sch_1):page90_i29@mstr_discrete.res(chips)!RES_0402-240,1.0%,1/16W,CHIP,GA!!!F834!A!!!!
S!PU_CPU0_FRMAGENT!R5D3!2!@baseboard_fab2_lib.baseboard_fab2(sch_1):page90_i29@mstr_discrete.res(chips)!RES_0402-240,1.0%,1/16W,CHIP,GA!!!F834!B!!!!
S!PVCCIO_CPU1!R7M2!1!@baseboard_fab2_lib.baseboard_fab2(sch_1):page99_i79@mstr_discrete.res(chips)!RES_0402-240,1.0%,1/16W,CHIP,GA!!!F829!A!!!!
S!SMB_DDR_KLM_SCL_G!R7M2!2!@baseboard_fab2_lib.baseboard_fab2(sch_1):page99_i79@mstr_discrete.res(chips)!RES_0402-240,1.0%,1/16W,CHIP,GA!!!F829!B!!!!
S!PVCCIO_CPU1!R7M7!1!@baseboard_fab2_lib.baseboard_fab2(sch_1):page99_i77@mstr_discrete.res(chips)!RES_0402-240,1.0%,1/16W,CHIP,GA!!!F828!A!!!!
S!SMB_DDR_KLM_SDA_G!R7M7!2!@baseboard_fab2_lib.baseboard_fab2(sch_1):page99_i77@mstr_discrete.res(chips)!RES_0402-240,1.0%,1/16W,CHIP,GA!!!F828!B!!!!
S!PVCCIO_CPU1!R3D24!1!@baseboard_fab2_lib.baseboard_fab2(sch_1):page90_i59@mstr_discrete.res(chips)!RES_0402-240,1.0%,1/16W,CHIP,GA!!!F842!A!!!!
S!PU_CPU1_SOCKET_ID_0!R3D24!2!@baseboard_fab2_lib.baseboard_fab2(sch_1):page90_i59@mstr_discrete.res(chips)!RES_0402-240,1.0%,1/16W,CHIP,GA!!!F842!B!!!!
S!A_M_BMC_ZQ!R1T27!1!@baseboard_fab2_lib.baseboard_fab2(sch_1):page151_i32@mstr_discrete.res(chips)!RES_0402-240,1.0%,1/16W,CHIP,GA!!!F843!A!!!!
S!GND!R1T27!2!@baseboard_fab2_lib.baseboard_fab2(sch_1):page151_i32@mstr_discrete.res(chips)!RES_0402-240,1.0%,1/16W,CHIP,GA!!!F843!B!!!!
S!PVCCIO_CPU0!R4T6!1!@baseboard_fab2_lib.baseboard_fab2(sch_1):page99_i17@mstr_discrete.res(chips)!RES_0402-240,1.0%,1/16W,CHIP,GA!!!F835!A!!!!
S!SMB_DDR_ABC_SDA_G!R4T6!2!@baseboard_fab2_lib.baseboard_fab2(sch_1):page99_i17@mstr_discrete.res(chips)!RES_0402-240,1.0%,1/16W,CHIP,GA!!!F835!B!!!!
S!GND!R6D6!1!@baseboard_fab2_lib.baseboard_fab2(sch_1):page90_i3@mstr_discrete.res(chips)!RES_0402-240,1.0%,1/16W,EMPTY,A!!!F814!A!!!!
S!PD_CPU0_TXT_PLTEN!R6D6!2!@baseboard_fab2_lib.baseboard_fab2(sch_1):page90_i3@mstr_discrete.res(chips)!RES_0402-240,1.0%,1/16W,EMPTY,A!!!F814!B!!!!
S!GND!R3D12!1!@baseboard_fab2_lib.baseboard_fab2(sch_1):page90_i11@mstr_discrete.res(chips)!RES_0402-240,1.0%,1/16W,EMPTY,A!!!F824!A!!!!
S!PD_CPU1_TXT_PLTEN!R3D12!2!@baseboard_fab2_lib.baseboard_fab2(sch_1):page90_i11@mstr_discrete.res(chips)!RES_0402-240,1.0%,1/16W,EMPTY,A!!!F824!B!!!!
S!PVCCIO_CPU1!R7P22!1!@baseboard_fab2_lib.baseboard_fab2(sch_1):page90_i76@mstr_discrete.res(chips)!RES_0402-240,1.0%,1/16W,EMPTY,A!!!F809!A!!!!
S!PU_CPU1_LEGACY_SKT!R7P22!2!@baseboard_fab2_lib.baseboard_fab2(sch_1):page90_i76@mstr_discrete.res(chips)!RES_0402-240,1.0%,1/16W,EMPTY,A!!!F809!B!!!!
S!PVCCIO_CPU1!R3D25!1!@baseboard_fab2_lib.baseboard_fab2(sch_1):page90_i66@mstr_discrete.res(chips)!RES_0402-240,1.0%,1/16W,EMPTY,A!!!F818!A!!!!
S!PU_CPU1_EAR_N!R3D25!2!@baseboard_fab2_lib.baseboard_fab2(sch_1):page90_i66@mstr_discrete.res(chips)!RES_0402-240,1.0%,1/16W,EMPTY,A!!!F818!B!!!!
S!PVCCIO_CPU0!R6D14!1!@baseboard_fab2_lib.baseboard_fab2(sch_1):page90_i52@mstr_discrete.res(chips)!RES_0402-240,1.0%,1/16W,EMPTY,A!!!F811!A!!!!
S!PU_CPU0_EAR_N!R6D14!2!@baseboard_fab2_lib.baseboard_fab2(sch_1):page90_i52@mstr_discrete.res(chips)!RES_0402-240,1.0%,1/16W,EMPTY,A!!!F811!B!!!!
S!GND!R4P6!1!@baseboard_fab2_lib.baseboard_fab2(sch_1):page90_i68@mstr_discrete.res(chips)!RES_0402-240,1.0%,1/16W,EMPTY,A!!!F815!A!!!!
S!PD_CPU0_DMIMODE_OVERRIDE!R4P6!2!@baseboard_fab2_lib.baseboard_fab2(sch_1):page90_i68@mstr_discrete.res(chips)!RES_0402-240,1.0%,1/16W,EMPTY,A!!!F815!B!!!!
S!PVCCIO_CPU0!R6D10!1!@baseboard_fab2_lib.baseboard_fab2(sch_1):page90_i49@mstr_discrete.res(chips)!RES_0402-240,1.0%,1/16W,EMPTY,A!!!F813!A!!!!
S!PU_CPU0_SOCKET_ID_1!R6D10!2!@baseboard_fab2_lib.baseboard_fab2(sch_1):page90_i49@mstr_discrete.res(chips)!RES_0402-240,1.0%,1/16W,EMPTY,A!!!F813!B!!!!
S!PVCCIO_CPU0!R6D13!1!@baseboard_fab2_lib.baseboard_fab2(sch_1):page90_i33@mstr_discrete.res(chips)!RES_0402-240,1.0%,1/16W,EMPTY,A!!!F812!A!!!!
S!PU_CPU0_SAFE_MODE_BOOT!R6D13!2!@baseboard_fab2_lib.baseboard_fab2(sch_1):page90_i33@mstr_discrete.res(chips)!RES_0402-240,1.0%,1/16W,EMPTY,A!!!F812!B!!!!
S!PVCCIO_CPU1!R3D26!1!@baseboard_fab2_lib.baseboard_fab2(sch_1):page90_i28@mstr_discrete.res(chips)!RES_0402-240,1.0%,1/16W,EMPTY,A!!!F817!A!!!!
S!PU_CPU1_SAFE_MODE_BOOT!R3D26!2!@baseboard_fab2_lib.baseboard_fab2(sch_1):page90_i28@mstr_discrete.res(chips)!RES_0402-240,1.0%,1/16W,EMPTY,A!!!F817!B!!!!
S!GND!R3D13!1!@baseboard_fab2_lib.baseboard_fab2(sch_1):page90_i12@mstr_discrete.res(chips)!RES_0402-240,1.0%,1/16W,EMPTY,A!!!F823!A!!!!
S!PD_CPU1_BIST_ENABLE!R3D13!2!@baseboard_fab2_lib.baseboard_fab2(sch_1):page90_i12@mstr_discrete.res(chips)!RES_0402-240,1.0%,1/16W,EMPTY,A!!!F823!B!!!!
S!PVCCIO_CPU1!R3D23!1!@baseboard_fab2_lib.baseboard_fab2(sch_1):page90_i25@mstr_discrete.res(chips)!RES_0402-240,1.0%,1/16W,EMPTY,A!!!F819!A!!!!
S!PU_CPU1_TXT_AGENT!R3D23!2!@baseboard_fab2_lib.baseboard_fab2(sch_1):page90_i25@mstr_discrete.res(chips)!RES_0402-240,1.0%,1/16W,EMPTY,A!!!F819!B!!!!
S!PVCCIO_CPU1!R3D16!1!@baseboard_fab2_lib.baseboard_fab2(sch_1):page90_i24@mstr_discrete.res(chips)!RES_0402-240,1.0%,1/16W,EMPTY,A!!!F822!A!!!!
S!H_CPU1_BMCINIT!R3D16!2!@baseboard_fab2_lib.baseboard_fab2(sch_1):page90_i24@mstr_discrete.res(chips)!RES_0402-240,1.0%,1/16W,EMPTY,A!!!F822!B!!!!
S!PVCCIO_CPU1!R3D22!1!@baseboard_fab2_lib.baseboard_fab2(sch_1):page90_i17@mstr_discrete.res(chips)!RES_0402-240,1.0%,1/16W,EMPTY,A!!!F820!A!!!!
S!PU_CPU1_FRMAGENT!R3D22!2!@baseboard_fab2_lib.baseboard_fab2(sch_1):page90_i17@mstr_discrete.res(chips)!RES_0402-240,1.0%,1/16W,EMPTY,A!!!F820!B!!!!
S!GND!R4P1!1!@baseboard_fab2_lib.baseboard_fab2(sch_1):page90_i4@mstr_discrete.res(chips)!RES_0402-240,1.0%,1/16W,EMPTY,A!!!F816!A!!!!
S!PD_CPU0_BIST_ENABLE!R4P1!2!@baseboard_fab2_lib.baseboard_fab2(sch_1):page90_i4@mstr_discrete.res(chips)!RES_0402-240,1.0%,1/16W,EMPTY,A!!!F816!B!!!!
S!PVCCIO_CPU1!R3D17!1!@baseboard_fab2_lib.baseboard_fab2(sch_1):page90_i60@mstr_discrete.res(chips)!RES_0402-240,1.0%,1/16W,EMPTY,A!!!F821!A!!!!
S!PU_CPU1_SOCKET_ID_1!R3D17!2!@baseboard_fab2_lib.baseboard_fab2(sch_1):page90_i60@mstr_discrete.res(chips)!RES_0402-240,1.0%,1/16W,EMPTY,A!!!F821!B!!!!
S!PVCCIO_CPU0!R6D15!1!@baseboard_fab2_lib.baseboard_fab2(sch_1):page90_i48@mstr_discrete.res(chips)!RES_0402-240,1.0%,1/16W,EMPTY,A!!!F810!A!!!!
S!PU_CPU0_SOCKET_ID_0!R6D15!2!@baseboard_fab2_lib.baseboard_fab2(sch_1):page90_i48@mstr_discrete.res(chips)!RES_0402-240,1.0%,1/16W,EMPTY,A!!!F810!B!!!!
S!RST_BMC_SRST_R2_N!R8D36!1!@baseboard_fab2_lib.baseboard_fab2(sch_1):page157_i388@mstr_discrete.res(chips)!RES_0402-33.2,1%,1/16W,CHIP,G2A!!!F667!A!!!!
S!RST_BMC_DDR3_BUF_IN_N!R8D36!2!@baseboard_fab2_lib.baseboard_fab2(sch_1):page157_i388@mstr_discrete.res(chips)!RES_0402-33.2,1%,1/16W,CHIP,G2A!!!F667!B!!!!
S!SMB_HOST_STBY_LVC3_SDA!R4D36!1!@baseboard_fab2_lib.baseboard_fab2(sch_1):page102_i82@mstr_discrete.res(chips)!RES_0402-33.2,1%,1/16W,CHIP,G2A!!!F713!A!!!!
S!SMB_HOST_STBY_LVC3_SDA_R2!R4D36!2!@baseboard_fab2_lib.baseboard_fab2(sch_1):page102_i82@mstr_discrete.res(chips)!RES_0402-33.2,1%,1/16W,CHIP,G2A!!!F713!B!!!!
S!SMB_HOST_STBY_LVC3_SCL!R4D37!1!@baseboard_fab2_lib.baseboard_fab2(sch_1):page102_i87@mstr_discrete.res(chips)!RES_0402-33.2,1%,1/16W,CHIP,G2A!!!F712!A!!!!
S!SMB_HOST_STBY_LVC3_SCL_R2!R4D37!2!@baseboard_fab2_lib.baseboard_fab2(sch_1):page102_i87@mstr_discrete.res(chips)!RES_0402-33.2,1%,1/16W,CHIP,G2A!!!F712!B!!!!
S!FM_PCH_PWRBTN_R_N!R2T28!1!@baseboard_fab2_lib.baseboard_fab2(sch_1):page156_i289@mstr_discrete.res(chips)!RES_0402-33.2,1%,1/16W,CHIP,G2A!!!F733!A!!!!
S!FM_PCH_PWRBTN_N!R2T28!2!@baseboard_fab2_lib.baseboard_fab2(sch_1):page156_i289@mstr_discrete.res(chips)!RES_0402-33.2,1%,1/16W,CHIP,G2A!!!F733!B!!!!
S!RST_BMC_SRST_R2_N!R8D22!1!@baseboard_fab2_lib.baseboard_fab2(sch_1):page157_i386@mstr_discrete.res(chips)!RES_0402-33.2,1%,1/16W,CHIP,G2A!!!F692!A!!!!
S!RST_BMC_SRST_N!R8D22!2!@baseboard_fab2_lib.baseboard_fab2(sch_1):page157_i386@mstr_discrete.res(chips)!RES_0402-33.2,1%,1/16W,CHIP,G2A!!!F692!B!!!!
S!IRQ_FORCE_NM_THROTTLE_R_N!R2P4!1!@baseboard_fab2_lib.baseboard_fab2(sch_1):page170_i74@mstr_discrete.res(chips)!RES_0402-33.2,1%,1/16W,CHIP,G2A!!!F738!A!!!!
S!IRQ_FORCE_NM_THROTTLE_N!R2P4!2!@baseboard_fab2_lib.baseboard_fab2(sch_1):page170_i74@mstr_discrete.res(chips)!RES_0402-33.2,1%,1/16W,CHIP,G2A!!!F738!B!!!!
S!RST_RSMRST_R_N!R2R2!1!@baseboard_fab2_lib.baseboard_fab2(sch_1):page190_i338@mstr_discrete.res(chips)!RES_0402-33.2,1%,1/16W,CHIP,G2A!!!F737!A!!!!
S!RST_RSMRST_N!R2R2!2!@baseboard_fab2_lib.baseboard_fab2(sch_1):page190_i338@mstr_discrete.res(chips)!RES_0402-33.2,1%,1/16W,CHIP,G2A!!!F737!B!!!!
S!RST_BMC_DDR3_R_N!R9F34!1!@baseboard_fab2_lib.baseboard_fab2(sch_1):page151_i70@mstr_discrete.res(chips)!RES_0402-33.2,1%,1/16W,CHIP,G2A!!!F672!A!!!!
S!RST_BMC_DDR3_N!R9F34!2!@baseboard_fab2_lib.baseboard_fab2(sch_1):page151_i70@mstr_discrete.res(chips)!RES_0402-33.2,1%,1/16W,CHIP,G2A!!!F672!B!!!!
S!IRQ_VM_INT_R_N!R1U40!1!@baseboard_fab2_lib.baseboard_fab2(sch_1):page165_i81@mstr_discrete.res(chips)!RES_0402-33.2,1%,1/16W,CHIP,G2A!!!F746!A!!!!
S!IRQ_VM_INT_N!R1U40!2!@baseboard_fab2_lib.baseboard_fab2(sch_1):page165_i81@mstr_discrete.res(chips)!RES_0402-33.2,1%,1/16W,CHIP,G2A!!!F746!B!!!!
S!IRQ_HSC_FAULT_R_N!R1D30!1!@baseboard_fab2_lib.baseboard_fab2(sch_1):page199_i110@mstr_discrete.res(chips)!RES_0402-33.2,1%,1/16W,CHIP,G2A!!!F754!A!!!!
S!IRQ_HSC_FAULT_N!R1D30!2!@baseboard_fab2_lib.baseboard_fab2(sch_1):page199_i110@mstr_discrete.res(chips)!RES_0402-33.2,1%,1/16W,CHIP,G2A!!!F754!B!!!!
S!IRQ_SML1_PMBUS_ALERT_R_N!R1D26!1!@baseboard_fab2_lib.baseboard_fab2(sch_1):page199_i109@mstr_discrete.res(chips)!RES_0402-33.2,1%,1/16W,CHIP,G2A!!!F755!A!!!!
S!IRQ_SML1_PMBUS_ALERT_N!R1D26!2!@baseboard_fab2_lib.baseboard_fab2(sch_1):page199_i109@mstr_discrete.res(chips)!RES_0402-33.2,1%,1/16W,CHIP,G2A!!!F755!B!!!!
S!IRQ_PVCCIN_CPU0_VRHOT_LVC3_R_N!R6P45!1!@baseboard_fab2_lib.baseboard_fab2(sch_1):page201_i128@mstr_discrete.res(chips)!RES_0402-33.2,1%,1/16W,CHIP,G2A!!!F708!A!!!!
S!IRQ_PVCCIN_CPU0_VRHOT_LVC3_N!R6P45!2!@baseboard_fab2_lib.baseboard_fab2(sch_1):page201_i128@mstr_discrete.res(chips)!RES_0402-33.2,1%,1/16W,CHIP,G2A!!!F708!B!!!!
S!PWRGD_PVSA_CPU0_R!R4D65!1!@baseboard_fab2_lib.baseboard_fab2(sch_1):page201_i127@mstr_discrete.res(chips)!RES_0402-33.2,1%,1/16W,CHIP,G2A!!!F711!A!!!!
S!PWRGD_PVSA_CPU0!R4D65!2!@baseboard_fab2_lib.baseboard_fab2(sch_1):page201_i127@mstr_discrete.res(chips)!RES_0402-33.2,1%,1/16W,CHIP,G2A!!!F711!B!!!!
S!IRQ_PVCCIN_CPU1_VRHOT_LVC3_R_N!R9P3!1!@baseboard_fab2_lib.baseboard_fab2(sch_1):page206_i117@mstr_discrete.res(chips)!RES_0402-33.2,1%,1/16W,CHIP,G2A!!!F668!A!!!!
S!IRQ_PVCCIN_CPU1_VRHOT_LVC3_N!R9P3!2!@baseboard_fab2_lib.baseboard_fab2(sch_1):page206_i117@mstr_discrete.res(chips)!RES_0402-33.2,1%,1/16W,CHIP,G2A!!!F668!B!!!!
S!PWRGD_PVSA_CPU1_R!R1D1!1!@baseboard_fab2_lib.baseboard_fab2(sch_1):page206_i116@mstr_discrete.res(chips)!RES_0402-33.2,1%,1/16W,CHIP,G2A!!!F756!A!!!!
S!PWRGD_PVSA_CPU1!R1D1!2!@baseboard_fab2_lib.baseboard_fab2(sch_1):page206_i116@mstr_discrete.res(chips)!RES_0402-33.2,1%,1/16W,CHIP,G2A!!!F756!B!!!!
S!PWRGD_PVTT_ABC_CPU0_R!R4G19!1!@baseboard_fab2_lib.baseboard_fab2(sch_1):page221_i54@mstr_discrete.res(chips)!RES_0402-33.2,1%,1/16W,CHIP,G2A!!!F709!A!!!!
S!PWRGD_PVTT_CPU0!R4G19!2!@baseboard_fab2_lib.baseboard_fab2(sch_1):page221_i54@mstr_discrete.res(chips)!RES_0402-33.2,1%,1/16W,CHIP,G2A!!!F709!B!!!!
S!PWRGD_PVTT_DEF_CPU0_R!R4A6!1!@baseboard_fab2_lib.baseboard_fab2(sch_1):page222_i51@mstr_discrete.res(chips)!RES_0402-33.2,1%,1/16W,CHIP,G2A!!!F714!A!!!!
S!PWRGD_PVTT_CPU0!R4A6!2!@baseboard_fab2_lib.baseboard_fab2(sch_1):page222_i51@mstr_discrete.res(chips)!RES_0402-33.2,1%,1/16W,CHIP,G2A!!!F714!B!!!!
S!IRQ_PVDDQ_GHJ_VRHOT_LVT3_R_N!R1G8!1!@baseboard_fab2_lib.baseboard_fab2(sch_1):page223_i82@mstr_discrete.res(chips)!RES_0402-33.2,1%,1/16W,CHIP,G2A!!!F752!A!!!!
S!IRQ_PVDDQ_GHJ_VRHOT_LVT3_N!R1G8!2!@baseboard_fab2_lib.baseboard_fab2(sch_1):page223_i82@mstr_discrete.res(chips)!RES_0402-33.2,1%,1/16W,CHIP,G2A!!!F752!B!!!!
S!IRQ_PVDDQ_KLM_VRHOT_LVT3_R_N!R1B4!1!@baseboard_fab2_lib.baseboard_fab2(sch_1):page226_i82@mstr_discrete.res(chips)!RES_0402-33.2,1%,1/16W,CHIP,G2A!!!F757!A!!!!
S!IRQ_PVDDQ_KLM_VRHOT_LVT3_N!R1B4!2!@baseboard_fab2_lib.baseboard_fab2(sch_1):page226_i82@mstr_discrete.res(chips)!RES_0402-33.2,1%,1/16W,CHIP,G2A!!!F757!B!!!!
S!PWRGD_PVTT_GHJ_CPU1_R!R4G15!1!@baseboard_fab2_lib.baseboard_fab2(sch_1):page229_i51@mstr_discrete.res(chips)!RES_0402-33.2,1%,1/16W,CHIP,G2A!!!F710!A!!!!
S!PWRGD_PVTT_CPU1!R4G15!2!@baseboard_fab2_lib.baseboard_fab2(sch_1):page229_i51@mstr_discrete.res(chips)!RES_0402-33.2,1%,1/16W,CHIP,G2A!!!F710!B!!!!
S!PWRGD_PVTT_KLM_CPU1_R!R4A4!1!@baseboard_fab2_lib.baseboard_fab2(sch_1):page230_i51@mstr_discrete.res(chips)!RES_0402-33.2,1%,1/16W,CHIP,G2A!!!F715!A!!!!
S!PWRGD_PVTT_CPU1!R4A4!2!@baseboard_fab2_lib.baseboard_fab2(sch_1):page230_i51@mstr_discrete.res(chips)!RES_0402-33.2,1%,1/16W,CHIP,G2A!!!F715!B!!!!
S!IRQ_PVDDQ_ABC_VRHOT_LVT3_R_N!R7F23!1!@baseboard_fab2_lib.baseboard_fab2(sch_1):page215_i297@mstr_discrete.res(chips)!RES_0402-33.2,1%,1/16W,CHIP,G2A!!!F696!A!!!!
S!IRQ_PVDDQ_ABC_VRHOT_LVT3_N!R7F23!2!@baseboard_fab2_lib.baseboard_fab2(sch_1):page215_i297@mstr_discrete.res(chips)!RES_0402-33.2,1%,1/16W,CHIP,G2A!!!F696!B!!!!
S!IRQ_PVDDQ_DEF_VRHOT_LVT3_R_N!R7B1!1!@baseboard_fab2_lib.baseboard_fab2(sch_1):page218_i12@mstr_discrete.res(chips)!RES_0402-33.2,1%,1/16W,CHIP,G2A!!!F707!A!!!!
S!IRQ_PVDDQ_DEF_VRHOT_LVT3_N!R7B1!2!@baseboard_fab2_lib.baseboard_fab2(sch_1):page218_i12@mstr_discrete.res(chips)!RES_0402-33.2,1%,1/16W,CHIP,G2A!!!F707!B!!!!
S!PWRGD_P12V_R!R1D33!1!@baseboard_fab2_lib.baseboard_fab2(sch_1):page199_i108@mstr_discrete.res(chips)!RES_0402-33.2,1%,1/16W,CHIP,G2A!!!F753!A!!!!
S!PWRGD_P12V_HSC!R1D33!2!@baseboard_fab2_lib.baseboard_fab2(sch_1):page199_i108@mstr_discrete.res(chips)!RES_0402-33.2,1%,1/16W,CHIP,G2A!!!F753!B!!!!
S!FM_DEBUG_RST_BTN_R1_N!R1L29!1!@baseboard_fab2_lib.baseboard_fab2(sch_1):page111_i68@mstr_discrete.res(chips)!RES_0402-33.2,1%,1/16W,CHIP,G2A!!!F750!A!!!!
S!FM_DEBUG_RST_BTN_N!R1L29!2!@baseboard_fab2_lib.baseboard_fab2(sch_1):page111_i68@mstr_discrete.res(chips)!RES_0402-33.2,1%,1/16W,CHIP,G2A!!!F750!B!!!!
S!FM_CPU1_FIVR_FAULT_LVT3_N!R9G10!1!@baseboard_fab2_lib.baseboard_fab2(sch_1):page145_i187@mstr_discrete.res(chips)!RES_0402-33.2,1%,1/16W,CHIP,G2A!!!F670!A!!!!
S!FM_CPU1_FIVR_FAULT_LVT3_R_N!R9G10!2!@baseboard_fab2_lib.baseboard_fab2(sch_1):page145_i187@mstr_discrete.res(chips)!RES_0402-33.2,1%,1/16W,CHIP,G2A!!!F670!B!!!!
S!FM_CPU0_FIVR_FAULT_LVT3_N!R9G16!1!@baseboard_fab2_lib.baseboard_fab2(sch_1):page145_i188@mstr_discrete.res(chips)!RES_0402-33.2,1%,1/16W,CHIP,G2A!!!F669!A!!!!
S!FM_CPU0_FIVR_FAULT_LVT3_R_N!R9G16!2!@baseboard_fab2_lib.baseboard_fab2(sch_1):page145_i188@mstr_discrete.res(chips)!RES_0402-33.2,1%,1/16W,CHIP,G2A!!!F669!B!!!!
S!FM_BIOS_TOP_SWAP_SPKR_R!R8E20!1!@baseboard_fab2_lib.baseboard_fab2(sch_1):page136_i126@mstr_discrete.res(chips)!RES_0402-33.2,1%,1/16W,CHIP,G2A!!!F686!A!!!!
S!FM_BIOS_TOP_SWAP_SPKR!R8E20!2!@baseboard_fab2_lib.baseboard_fab2(sch_1):page136_i126@mstr_discrete.res(chips)!RES_0402-33.2,1%,1/16W,CHIP,G2A!!!F686!B!!!!
S!IRQ_BMC_PCH_NMI_STBY_N!R8E24!1!@baseboard_fab2_lib.baseboard_fab2(sch_1):page156_i214@mstr_discrete.res(chips)!RES_0402-33.2,1%,1/16W,CHIP,G2A!!!F685!A!!!!
S!IRQ_BMC_PCH_NMI_STBY_R_N!R8E24!2!@baseboard_fab2_lib.baseboard_fab2(sch_1):page156_i214@mstr_discrete.res(chips)!RES_0402-33.2,1%,1/16W,CHIP,G2A!!!F685!B!!!!
S!SPI_BIOS_SOCKET_IO3!R7F3!1!@baseboard_fab2_lib.baseboard_fab2(sch_1):page153_i109@mstr_discrete.res(chips)!RES_0402-33.2,1%,1/16W,CHIP,G2A!!!F698!A!!!!
S!PU_BIOS_SPI_HOLD0_N!R7F3!2!@baseboard_fab2_lib.baseboard_fab2(sch_1):page153_i109@mstr_discrete.res(chips)!RES_0402-33.2,1%,1/16W,CHIP,G2A!!!F698!B!!!!
S!SPI_BIOS_SOCKET_IO3!R3T1!1!@baseboard_fab2_lib.baseboard_fab2(sch_1):page153_i157@mstr_discrete.res(chips)!RES_0402-33.2,1%,1/16W,CHIP,G2A!!!F719!A!!!!
S!PU_BIOS_SPI_HOLD1_N!R3T1!2!@baseboard_fab2_lib.baseboard_fab2(sch_1):page153_i157@mstr_discrete.res(chips)!RES_0402-33.2,1%,1/16W,CHIP,G2A!!!F719!B!!!!
S!SPI_SWITCH_MOSI!R7F29!1!@baseboard_fab2_lib.baseboard_fab2(sch_1):page153_i181@mstr_discrete.res(chips)!RES_0402-33.2,1%,1/16W,CHIP,G2A!!!F695!A!!!!
S!SPI_SWITCH_MOSI_R0!R7F29!2!@baseboard_fab2_lib.baseboard_fab2(sch_1):page153_i181@mstr_discrete.res(chips)!RES_0402-33.2,1%,1/16W,CHIP,G2A!!!F695!B!!!!
S!SPI_SWITCH_MOSI!R3T10!1!@baseboard_fab2_lib.baseboard_fab2(sch_1):page153_i184@mstr_discrete.res(chips)!RES_0402-33.2,1%,1/16W,CHIP,G2A!!!F717!A!!!!
S!SPI_SWITCH_MOSI_R1!R3T10!2!@baseboard_fab2_lib.baseboard_fab2(sch_1):page153_i184@mstr_discrete.res(chips)!RES_0402-33.2,1%,1/16W,CHIP,G2A!!!F717!B!!!!
S!SPI_BIOS_SOCKET_IO2!R7F37!1!@baseboard_fab2_lib.baseboard_fab2(sch_1):page153_i108@mstr_discrete.res(chips)!RES_0402-33.2,1%,1/16W,CHIP,G2A!!!F694!A!!!!
S!PU_BIOS_SPI_WP0_N!R7F37!2!@baseboard_fab2_lib.baseboard_fab2(sch_1):page153_i108@mstr_discrete.res(chips)!RES_0402-33.2,1%,1/16W,CHIP,G2A!!!F694!B!!!!
S!SPI_BIOS_SOCKET_IO2!R3U1!1!@baseboard_fab2_lib.baseboard_fab2(sch_1):page153_i156@mstr_discrete.res(chips)!RES_0402-33.2,1%,1/16W,CHIP,G2A!!!F716!A!!!!
S!PU_BIOS_SPI_WP1_N!R3U1!2!@baseboard_fab2_lib.baseboard_fab2(sch_1):page153_i156@mstr_discrete.res(chips)!RES_0402-33.2,1%,1/16W,CHIP,G2A!!!F716!B!!!!
S!SPI_PCH_CLK!R8E9!1!@baseboard_fab2_lib.baseboard_fab2(sch_1):page184_i88@mstr_discrete.res(chips)!RES_0402-33.2,1%,1/16W,CHIP,G2A!!!F690!A!!!!
S!SPI_PCH_TPM_CLK_R!R8E9!2!@baseboard_fab2_lib.baseboard_fab2(sch_1):page184_i88@mstr_discrete.res(chips)!RES_0402-33.2,1%,1/16W,CHIP,G2A!!!F690!B!!!!
S!SPI_PCH_MOSI!R8E10!1!@baseboard_fab2_lib.baseboard_fab2(sch_1):page184_i95@mstr_discrete.res(chips)!RES_0402-33.2,1%,1/16W,CHIP,G2A!!!F689!A!!!!
S!SPI_PCH_TPM_MOSI_R!R8E10!2!@baseboard_fab2_lib.baseboard_fab2(sch_1):page184_i95@mstr_discrete.res(chips)!RES_0402-33.2,1%,1/16W,CHIP,G2A!!!F689!B!!!!
S!SPI_PCH_MISO!R8E13!1!@baseboard_fab2_lib.baseboard_fab2(sch_1):page184_i93@mstr_discrete.res(chips)!RES_0402-33.2,1%,1/16W,CHIP,G2A!!!F688!A!!!!
S!SPI_PCH_TPM_MISO_R!R8E13!2!@baseboard_fab2_lib.baseboard_fab2(sch_1):page184_i93@mstr_discrete.res(chips)!RES_0402-33.2,1%,1/16W,CHIP,G2A!!!F688!B!!!!
S!RMII_PCH_SPRNGVLLE_ARB_OUT!R8D11!1!@baseboard_fab2_lib.baseboard_fab2(sch_1):page121_i68@mstr_discrete.res(chips)!RES_0402-33.2,1%,1/16W,CHIP,G2A!!!F693!A!!!!
S!RMII_PCH_SPRNGVLLE_ARB_OUT_R!R8D11!2!@baseboard_fab2_lib.baseboard_fab2(sch_1):page121_i68@mstr_discrete.res(chips)!RES_0402-33.2,1%,1/16W,CHIP,G2A!!!F693!B!!!!
S!RMII_BMC_PCH_SPRNGVLLE_RXER!R7C14!1!@baseboard_fab2_lib.baseboard_fab2(sch_1):page121_i69@mstr_discrete.res(chips)!RES_0402-33.2,1%,1/16W,CHIP,G2A!!!F706!A!!!!
S!RMII_BMC_PCH_SPRNGVLLE_RXER_R!R7C14!2!@baseboard_fab2_lib.baseboard_fab2(sch_1):page121_i69@mstr_discrete.res(chips)!RES_0402-33.2,1%,1/16W,CHIP,G2A!!!F706!B!!!!
S!RMII_PCH_SPRNGVLLE_ARB_IN_R!R9E16!1!@baseboard_fab2_lib.baseboard_fab2(sch_1):page139_i235@mstr_discrete.res(chips)!RES_0402-33.2,1%,1/16W,CHIP,G2A!!!F674!A!!!!
S!RMII_PCH_SPRNGVLLE_ARB_IN!R9E16!2!@baseboard_fab2_lib.baseboard_fab2(sch_1):page139_i235@mstr_discrete.res(chips)!RES_0402-33.2,1%,1/16W,CHIP,G2A!!!F674!B!!!!
S!CLK_25M_CPLD_R!R2T47!1!@baseboard_fab2_lib.baseboard_fab2(sch_1):page101_i130@mstr_discrete.res(chips)!RES_0402-33.2,1%,1/16W,CHIP,G2A!!!F729!A!!!!
S!CLK_25M_CPLD!R2T47!2!@baseboard_fab2_lib.baseboard_fab2(sch_1):page101_i130@mstr_discrete.res(chips)!RES_0402-33.2,1%,1/16W,CHIP,G2A!!!F729!B!!!!
S!CLK_50M_CKMNG_BMC_2_R!R8G1!1!@baseboard_fab2_lib.baseboard_fab2(sch_1):page101_i133@mstr_discrete.res(chips)!RES_0402-33.2,1%,1/16W,CHIP,G2A!!!F680!A!!!!
S!CLK_50M_CKMNG_BMC_2!R8G1!2!@baseboard_fab2_lib.baseboard_fab2(sch_1):page101_i133@mstr_discrete.res(chips)!RES_0402-33.2,1%,1/16W,CHIP,G2A!!!F680!B!!!!
S!LPC_LAD1_IO1!R3N28!1!@baseboard_fab2_lib.baseboard_fab2(sch_1):page144_i554@mstr_discrete.res(chips)!RES_0402-33.2,1%,1/16W,CHIP,G2A!!!F724!A!!!!
S!LPC_LAD1_IO1_R!R3N28!2!@baseboard_fab2_lib.baseboard_fab2(sch_1):page144_i554@mstr_discrete.res(chips)!RES_0402-33.2,1%,1/16W,CHIP,G2A!!!F724!B!!!!
S!LPC_LAD2_IO2!R3N24!1!@baseboard_fab2_lib.baseboard_fab2(sch_1):page144_i553@mstr_discrete.res(chips)!RES_0402-33.2,1%,1/16W,CHIP,G2A!!!F728!A!!!!
S!LPC_LAD2_IO2_R!R3N24!2!@baseboard_fab2_lib.baseboard_fab2(sch_1):page144_i553@mstr_discrete.res(chips)!RES_0402-33.2,1%,1/16W,CHIP,G2A!!!F728!B!!!!
S!LPC_LAD0_IO0!R3N26!1!@baseboard_fab2_lib.baseboard_fab2(sch_1):page144_i555@mstr_discrete.res(chips)!RES_0402-33.2,1%,1/16W,CHIP,G2A!!!F726!A!!!!
S!LPC_LAD0_IO0_R!R3N26!2!@baseboard_fab2_lib.baseboard_fab2(sch_1):page144_i555@mstr_discrete.res(chips)!RES_0402-33.2,1%,1/16W,CHIP,G2A!!!F726!B!!!!
S!CLK_50M_CKMNG_SPRVLLE_R!R1T31!1!@baseboard_fab2_lib.baseboard_fab2(sch_1):page101_i131@mstr_discrete.res(chips)!RES_0402-33.2,1%,1/16W,CHIP,G2A!!!F749!A!!!!
S!CLK_50M_CKMNG_SPRVLLE!R1T31!2!@baseboard_fab2_lib.baseboard_fab2(sch_1):page101_i131@mstr_discrete.res(chips)!RES_0402-33.2,1%,1/16W,CHIP,G2A!!!F749!B!!!!
S!CLK_50M_CKMNG_PCH_10GBE_R!R7D14!1!@baseboard_fab2_lib.baseboard_fab2(sch_1):page101_i132@mstr_discrete.res(chips)!RES_0402-33.2,1%,1/16W,CHIP,G2A!!!F704!A!!!!
S!CLK_50M_CKMNG_PCH_10GBE!R7D14!2!@baseboard_fab2_lib.baseboard_fab2(sch_1):page101_i132@mstr_discrete.res(chips)!RES_0402-33.2,1%,1/16W,CHIP,G2A!!!F704!B!!!!
S!LPC_LAD3_IO3!R3N25!1!@baseboard_fab2_lib.baseboard_fab2(sch_1):page144_i527@mstr_discrete.res(chips)!RES_0402-33.2,1%,1/16W,CHIP,G2A!!!F727!A!!!!
S!LPC_LAD3_IO3_R!R3N25!2!@baseboard_fab2_lib.baseboard_fab2(sch_1):page144_i527@mstr_discrete.res(chips)!RES_0402-33.2,1%,1/16W,CHIP,G2A!!!F727!B!!!!
S!FP_NMI_BTN_R_N!R2R10!1!@baseboard_fab2_lib.baseboard_fab2(sch_1):page157_i358@mstr_discrete.res(chips)!RES_0402-33.2,1%,1/16W,CHIP,G2A!!!F736!A!!!!
S!FP_NMI_BTN_N!R2R10!2!@baseboard_fab2_lib.baseboard_fab2(sch_1):page157_i358@mstr_discrete.res(chips)!RES_0402-33.2,1%,1/16W,CHIP,G2A!!!F736!B!!!!
S!FM_PCH_PLD_DATA_R!R2M3!1!@baseboard_fab2_lib.baseboard_fab2(sch_1):page119_i172@mstr_discrete.res(chips)!RES_0402-33.2,1%,1/16W,CHIP,G2A!!!F742!A!!!!
S!FM_PCH_PLD_DATA!R2M3!2!@baseboard_fab2_lib.baseboard_fab2(sch_1):page119_i172@mstr_discrete.res(chips)!RES_0402-33.2,1%,1/16W,CHIP,G2A!!!F742!B!!!!
S!FM_CPU_CATERR_DLY_LVT3_R_N!R2N1!1!@baseboard_fab2_lib.baseboard_fab2(sch_1):page119_i173@mstr_discrete.res(chips)!RES_0402-33.2,1%,1/16W,CHIP,G2A!!!F740!A!!!!
S!FM_CPU_CATERR_DLY_LVT3_N!R2N1!2!@baseboard_fab2_lib.baseboard_fab2(sch_1):page119_i173@mstr_discrete.res(chips)!RES_0402-33.2,1%,1/16W,CHIP,G2A!!!F740!B!!!!
S!FM_ADR_MODE_SEL_R!R2M7!1!@baseboard_fab2_lib.baseboard_fab2(sch_1):page119_i174@mstr_discrete.res(chips)!RES_0402-33.2,1%,1/16W,CHIP,G2A!!!F741!A!!!!
S!FM_ADR_MODE_SEL!R2M7!2!@baseboard_fab2_lib.baseboard_fab2(sch_1):page119_i174@mstr_discrete.res(chips)!RES_0402-33.2,1%,1/16W,CHIP,G2A!!!F741!B!!!!
S!FM_CPLD_ADR_TRIGGER_N!R2M1!1!@baseboard_fab2_lib.baseboard_fab2(sch_1):page120_i218@mstr_discrete.res(chips)!RES_0402-33.2,1%,1/16W,CHIP,G2A!!!F743!A!!!!
S!FM_CPLD_ADR_TRIGGER_R_N!R2M1!2!@baseboard_fab2_lib.baseboard_fab2(sch_1):page120_i218@mstr_discrete.res(chips)!RES_0402-33.2,1%,1/16W,CHIP,G2A!!!F743!B!!!!
S!FM_ADR_COMPLETE!R2N26!1!@baseboard_fab2_lib.baseboard_fab2(sch_1):page120_i219@mstr_discrete.res(chips)!RES_0402-33.2,1%,1/16W,CHIP,G2A!!!F739!A!!!!
S!FM_ADR_COMPLETE_R1!R2N26!2!@baseboard_fab2_lib.baseboard_fab2(sch_1):page120_i219@mstr_discrete.res(chips)!RES_0402-33.2,1%,1/16W,CHIP,G2A!!!F739!B!!!!
S!CLK_24M_BMC_LPC!R2T14!1!@baseboard_fab2_lib.baseboard_fab2(sch_1):page119_i189@mstr_discrete.res(chips)!RES_0402-33.2,1%,1/16W,CHIP,G2A!!!F735!A!!!!
S!CLK_24M_BMC_LPC_R!R2T14!2!@baseboard_fab2_lib.baseboard_fab2(sch_1):page119_i189@mstr_discrete.res(chips)!RES_0402-33.2,1%,1/16W,CHIP,G2A!!!F735!B!!!!
S!PWRGD_CPUPWRGD_R1!R3R3!1!@baseboard_fab2_lib.baseboard_fab2(sch_1):page92_i61@mstr_discrete.res(chips)!RES_0402-33.2,1%,1/16W,CHIP,G2A!!!F720!A!!!!
S!PWRGD_CPUPWRGD!R3R3!2!@baseboard_fab2_lib.baseboard_fab2(sch_1):page92_i61@mstr_discrete.res(chips)!RES_0402-33.2,1%,1/16W,CHIP,G2A!!!F720!B!!!!
S!FM_CPU_MSMI_LVT3_R_N!R7D25!1!@baseboard_fab2_lib.baseboard_fab2(sch_1):page92_i70@mstr_discrete.res(chips)!RES_0402-33.2,1%,1/16W,CHIP,G2A!!!F702!A!!!!
S!FM_CPU_MSMI_LVT3_N!R7D25!2!@baseboard_fab2_lib.baseboard_fab2(sch_1):page92_i70@mstr_discrete.res(chips)!RES_0402-33.2,1%,1/16W,CHIP,G2A!!!F702!B!!!!
S!FM_CPU1_PROCHOT_LVT3_K_N!R7D24!1!@baseboard_fab2_lib.baseboard_fab2(sch_1):page93_i62@mstr_discrete.res(chips)!RES_0402-33.2,1%,1/16W,CHIP,G2A!!!F703!A!!!!
S!FM_CPU1_PROCHOT_LVT3_N!R7D24!2!@baseboard_fab2_lib.baseboard_fab2(sch_1):page93_i62@mstr_discrete.res(chips)!RES_0402-33.2,1%,1/16W,CHIP,G2A!!!F703!B!!!!
S!FM_CPU1_THERMTRIP_LVT3_R_N!R3P42!1!@baseboard_fab2_lib.baseboard_fab2(sch_1):page92_i14@mstr_discrete.res(chips)!RES_0402-33.2,1%,1/16W,CHIP,G2A!!!F723!A!!!!
S!FM_CPU1_THERMTRIP_LVT3_N!R3P42!2!@baseboard_fab2_lib.baseboard_fab2(sch_1):page92_i14@mstr_discrete.res(chips)!RES_0402-33.2,1%,1/16W,CHIP,G2A!!!F723!B!!!!
S!FM_CPU_CATERR_LVT3_R2_N!R3P43!1!@baseboard_fab2_lib.baseboard_fab2(sch_1):page92_i13@mstr_discrete.res(chips)!RES_0402-33.2,1%,1/16W,CHIP,G2A!!!F722!A!!!!
S!FM_CPU_CATERR_LVT3_N!R3P43!2!@baseboard_fab2_lib.baseboard_fab2(sch_1):page92_i13@mstr_discrete.res(chips)!RES_0402-33.2,1%,1/16W,CHIP,G2A!!!F722!B!!!!
S!FM_CPU1_FIVR_FAULT_LVT3_R1_N!R3P46!1!@baseboard_fab2_lib.baseboard_fab2(sch_1):page92_i12@mstr_discrete.res(chips)!RES_0402-33.2,1%,1/16W,CHIP,G2A!!!F721!A!!!!
S!FM_CPU1_FIVR_FAULT_LVT3!R3P46!2!@baseboard_fab2_lib.baseboard_fab2(sch_1):page92_i12@mstr_discrete.res(chips)!RES_0402-33.2,1%,1/16W,CHIP,G2A!!!F721!B!!!!
S!FM_CPU0_THERMTRIP_LVT3_R_N!R7D34!1!@baseboard_fab2_lib.baseboard_fab2(sch_1):page92_i24@mstr_discrete.res(chips)!RES_0402-33.2,1%,1/16W,CHIP,G2A!!!F699!A!!!!
S!FM_CPU0_THERMTRIP_LVT3_N!R7D34!2!@baseboard_fab2_lib.baseboard_fab2(sch_1):page92_i24@mstr_discrete.res(chips)!RES_0402-33.2,1%,1/16W,CHIP,G2A!!!F699!B!!!!
S!FM_CPU_ERR2_LVT3_R_N!R7D31!1!@baseboard_fab2_lib.baseboard_fab2(sch_1):page92_i29@mstr_discrete.res(chips)!RES_0402-33.2,1%,1/16W,CHIP,G2A!!!F700!A!!!!
S!FM_CPU_ERR2_LVT3_N!R7D31!2!@baseboard_fab2_lib.baseboard_fab2(sch_1):page92_i29@mstr_discrete.res(chips)!RES_0402-33.2,1%,1/16W,CHIP,G2A!!!F700!B!!!!
S!FM_CPU0_FIVR_FAULT_LVT3_R2_N!R7D29!1!@baseboard_fab2_lib.baseboard_fab2(sch_1):page92_i30@mstr_discrete.res(chips)!RES_0402-33.2,1%,1/16W,CHIP,G2A!!!F701!A!!!!
S!FM_CPU0_FIVR_FAULT_LVT3!R7D29!2!@baseboard_fab2_lib.baseboard_fab2(sch_1):page92_i30@mstr_discrete.res(chips)!RES_0402-33.2,1%,1/16W,CHIP,G2A!!!F701!B!!!!
S!FM_CPU_ERR0_LVT3_K_N!R2T30!1!@baseboard_fab2_lib.baseboard_fab2(sch_1):page93_i42@mstr_discrete.res(chips)!RES_0402-33.2,1%,1/16W,CHIP,G2A!!!F732!A!!!!
S!FM_CPU_ERR0_LVT3_N!R2T30!2!@baseboard_fab2_lib.baseboard_fab2(sch_1):page93_i42@mstr_discrete.res(chips)!RES_0402-33.2,1%,1/16W,CHIP,G2A!!!F732!B!!!!
S!FM_CPU_ERR0_LVT3_K_N!R2T33!1!@baseboard_fab2_lib.baseboard_fab2(sch_1):page93_i40@mstr_discrete.res(chips)!RES_0402-33.2,1%,1/16W,CHIP,G2A!!!F731!A!!!!
S!FM_CPU_ERR1_LVT3_N!R2T33!2!@baseboard_fab2_lib.baseboard_fab2(sch_1):page93_i40@mstr_discrete.res(chips)!RES_0402-33.2,1%,1/16W,CHIP,G2A!!!F731!B!!!!
S!FM_CPU0_PROCHOT_LVT3_K_N!R2T38!1!@baseboard_fab2_lib.baseboard_fab2(sch_1):page93_i39@mstr_discrete.res(chips)!RES_0402-33.2,1%,1/16W,CHIP,G2A!!!F730!A!!!!
S!FM_CPU0_PROCHOT_LVT3_N!R2T38!2!@baseboard_fab2_lib.baseboard_fab2(sch_1):page93_i39@mstr_discrete.res(chips)!RES_0402-33.2,1%,1/16W,CHIP,G2A!!!F730!B!!!!
S!SPI_BMC_BT_DO_R!R9F41!1!@baseboard_fab2_lib.baseboard_fab2(sch_1):page146_i108@mstr_discrete.res(chips)!RES_0402-33.2,1%,1/16W,CHIP,G2A!!!F671!A!!!!
S!SPI_BMC_BT_DO!R9F41!2!@baseboard_fab2_lib.baseboard_fab2(sch_1):page146_i108@mstr_discrete.res(chips)!RES_0402-33.2,1%,1/16W,CHIP,G2A!!!F671!B!!!!
S!SPI_BMC_BT_CLK_R!R9F21!1!@baseboard_fab2_lib.baseboard_fab2(sch_1):page146_i109@mstr_discrete.res(chips)!RES_0402-33.2,1%,1/16W,CHIP,G2A!!!F673!A!!!!
S!SPI_BMC_BT_CLK!R9F21!2!@baseboard_fab2_lib.baseboard_fab2(sch_1):page146_i109@mstr_discrete.res(chips)!RES_0402-33.2,1%,1/16W,CHIP,G2A!!!F673!B!!!!
S!LPC_LFRAME_N_CS0_N!R3N27!1!@baseboard_fab2_lib.baseboard_fab2(sch_1):page144_i521@mstr_discrete.res(chips)!RES_0402-33.2,1%,1/16W,CHIP,G2A!!!F725!A!!!!
S!LPC_LFRAME_N_CS0_R_N!R3N27!2!@baseboard_fab2_lib.baseboard_fab2(sch_1):page144_i521@mstr_discrete.res(chips)!RES_0402-33.2,1%,1/16W,CHIP,G2A!!!F725!B!!!!
S!IRQ_LPC_SERIRQ_N!R2T24!1!@baseboard_fab2_lib.baseboard_fab2(sch_1):page144_i520@mstr_discrete.res(chips)!RES_0402-33.2,1%,1/16W,CHIP,G2A!!!F734!A!!!!
S!IRQ_LPC_SERIRQ_R!R2T24!2!@baseboard_fab2_lib.baseboard_fab2(sch_1):page144_i520@mstr_discrete.res(chips)!RES_0402-33.2,1%,1/16W,CHIP,G2A!!!F734!B!!!!
S!H_CPU0_MEMABC_MEMHOT_LVT3_K_N!R1U46!1!@baseboard_fab2_lib.baseboard_fab2(sch_1):page152_i6@mstr_discrete.res(chips)!RES_0402-33.2,1%,1/16W,CHIP,G2A!!!F744!A!!!!
S!H_CPU0_MEMABC_MEMHOT_LVT3_N!R1U46!2!@baseboard_fab2_lib.baseboard_fab2(sch_1):page152_i6@mstr_discrete.res(chips)!RES_0402-33.2,1%,1/16W,CHIP,G2A!!!F744!B!!!!
S!H_CPU0_MEMDEF_MEMHOT_LVT3_K_N!R9G31!1!@baseboard_fab2_lib.baseboard_fab2(sch_1):page152_i14@mstr_discrete.res(chips)!RES_0402-33.2,1%,1/16W,CHIP,G2A!!!F745!A!!!!
S!H_CPU0_MEMDEF_MEMHOT_LVT3_N!R9G31!2!@baseboard_fab2_lib.baseboard_fab2(sch_1):page152_i14@mstr_discrete.res(chips)!RES_0402-33.2,1%,1/16W,CHIP,G2A!!!F745!B!!!!
S!H_CPU1_MEMGHJ_MEMHOT_LVT3_K_N!R1U36!1!@baseboard_fab2_lib.baseboard_fab2(sch_1):page152_i15@mstr_discrete.res(chips)!RES_0402-33.2,1%,1/16W,CHIP,G2A!!!F747!A!!!!
S!H_CPU1_MEMGHJ_MEMHOT_LVT3_N!R1U36!2!@baseboard_fab2_lib.baseboard_fab2(sch_1):page152_i15@mstr_discrete.res(chips)!RES_0402-33.2,1%,1/16W,CHIP,G2A!!!F747!B!!!!
S!H_CPU1_MEMKLM_MEMHOT_LVT3_K_N!R1U34!1!@baseboard_fab2_lib.baseboard_fab2(sch_1):page152_i16@mstr_discrete.res(chips)!RES_0402-33.2,1%,1/16W,CHIP,G2A!!!F748!A!!!!
S!H_CPU1_MEMKLM_MEMHOT_LVT3_N!R1U34!2!@baseboard_fab2_lib.baseboard_fab2(sch_1):page152_i16@mstr_discrete.res(chips)!RES_0402-33.2,1%,1/16W,CHIP,G2A!!!F748!B!!!!
S!IRQ_LVC3_WAKE_R_N!R8E17!1!@baseboard_fab2_lib.baseboard_fab2(sch_1):page142_i2@mstr_discrete.res(chips)!RES_0402-33.2,1%,1/16W,CHIP,G2A!!!F687!A!!!!
S!IRQ_LVC3_WAKE_N!R8E17!2!@baseboard_fab2_lib.baseboard_fab2(sch_1):page142_i2@mstr_discrete.res(chips)!RES_0402-33.2,1%,1/16W,CHIP,G2A!!!F687!B!!!!
S!FM_PWR_BTN_R_N!R1L26!1!@baseboard_fab2_lib.baseboard_fab2(sch_1):page175_i13@mstr_discrete.res(chips)!RES_0402-33.2,1%,1/16W,CHIP,G2A!!!F751!A!!!!
S!FM_PWR_BTN_N!R1L26!2!@baseboard_fab2_lib.baseboard_fab2(sch_1):page175_i13@mstr_discrete.res(chips)!RES_0402-33.2,1%,1/16W,CHIP,G2A!!!F751!B!!!!
S!SPI_SWITCH_CLK!R8F7!1!@baseboard_fab2_lib.baseboard_fab2(sch_1):page153_i167@mstr_discrete.res(chips)!RES_0402-33.2,1%,1/16W,CHIP,G2A!!!F684!A!!!!
S!SPI_CLK_R1!R8F7!2!@baseboard_fab2_lib.baseboard_fab2(sch_1):page153_i167@mstr_discrete.res(chips)!RES_0402-33.2,1%,1/16W,CHIP,G2A!!!F684!B!!!!
S!FM_CTNR_PS_ON_R!R8E5!1!@baseboard_fab2_lib.baseboard_fab2(sch_1):page181_i218@mstr_discrete.res(chips)!RES_0402-33.2,1%,1/16W,CHIP,G2A!!!F691!A!!!!
S!FM_CTNR_PS_ON!R8E5!2!@baseboard_fab2_lib.baseboard_fab2(sch_1):page181_i218@mstr_discrete.res(chips)!RES_0402-33.2,1%,1/16W,CHIP,G2A!!!F691!B!!!!
S!SPI_SWITCH_MISO!R3T2!1!@baseboard_fab2_lib.baseboard_fab2(sch_1):page153_i155@mstr_discrete.res(chips)!RES_0402-33.2,1%,1/16W,CHIP,G2A!!!F718!A!!!!
S!SPI_MISO_R1!R3T2!2!@baseboard_fab2_lib.baseboard_fab2(sch_1):page153_i155@mstr_discrete.res(chips)!RES_0402-33.2,1%,1/16W,CHIP,G2A!!!F718!B!!!!
S!SPI_BMC_BT_DI!R8F12!1!@baseboard_fab2_lib.baseboard_fab2(sch_1):page162_i13@mstr_discrete.res(chips)!RES_0402-33.2,1%,1/16W,CHIP,G2A!!!F682!A!!!!
S!SPI_BMC_BT_DI_R!R8F12!2!@baseboard_fab2_lib.baseboard_fab2(sch_1):page162_i13@mstr_discrete.res(chips)!RES_0402-33.2,1%,1/16W,CHIP,G2A!!!F682!B!!!!
S!CLK_25M_BMC_R!R8F29!1!@baseboard_fab2_lib.baseboard_fab2(sch_1):page101_i20@mstr_discrete.res(chips)!RES_0402-33.2,1%,1/16W,CHIP,G2A!!!F681!A!!!!
S!CLK_25M_BMC!R8F29!2!@baseboard_fab2_lib.baseboard_fab2(sch_1):page101_i20@mstr_discrete.res(chips)!RES_0402-33.2,1%,1/16W,CHIP,G2A!!!F681!B!!!!
S!SPI_NIC_MISO_R!R9E6!1!@baseboard_fab2_lib.baseboard_fab2(sch_1):page140_i17@mstr_discrete.res(chips)!RES_0402-33.2,1%,1/16W,CHIP,G2A!!!F677!A!!!!
S!SPI_NIC_MISO!R9E6!2!@baseboard_fab2_lib.baseboard_fab2(sch_1):page140_i17@mstr_discrete.res(chips)!RES_0402-33.2,1%,1/16W,CHIP,G2A!!!F677!B!!!!
S!SPI_NIC_CS_R_N!R9E5!1!@baseboard_fab2_lib.baseboard_fab2(sch_1):page139_i129@mstr_discrete.res(chips)!RES_0402-33.2,1%,1/16W,CHIP,G2A!!!F678!A!!!!
S!SPI_NIC_CS_N!R9E5!2!@baseboard_fab2_lib.baseboard_fab2(sch_1):page139_i129@mstr_discrete.res(chips)!RES_0402-33.2,1%,1/16W,CHIP,G2A!!!F678!B!!!!
S!SPI_NIC_MOSI_R!R9E9!1!@baseboard_fab2_lib.baseboard_fab2(sch_1):page139_i128@mstr_discrete.res(chips)!RES_0402-33.2,1%,1/16W,CHIP,G2A!!!F675!A!!!!
S!SPI_NIC_MOSI!R9E9!2!@baseboard_fab2_lib.baseboard_fab2(sch_1):page139_i128@mstr_discrete.res(chips)!RES_0402-33.2,1%,1/16W,CHIP,G2A!!!F675!B!!!!
S!SPI_NIC_SCLK_R!R9E8!1!@baseboard_fab2_lib.baseboard_fab2(sch_1):page139_i130@mstr_discrete.res(chips)!RES_0402-33.2,1%,1/16W,CHIP,G2A!!!F676!A!!!!
S!SPI_NIC_SCLK!R9E8!2!@baseboard_fab2_lib.baseboard_fab2(sch_1):page139_i130@mstr_discrete.res(chips)!RES_0402-33.2,1%,1/16W,CHIP,G2A!!!F676!B!!!!
S!SPI_SWITCH_CLK!R8F8!1!@baseboard_fab2_lib.baseboard_fab2(sch_1):page153_i166@mstr_discrete.res(chips)!RES_0402-33.2,1%,1/16W,CHIP,G2A!!!F683!A!!!!
S!SPI_CLK_R0!R8F8!2!@baseboard_fab2_lib.baseboard_fab2(sch_1):page153_i166@mstr_discrete.res(chips)!RES_0402-33.2,1%,1/16W,CHIP,G2A!!!F683!B!!!!
S!SPI_PCH_CS0_R_N!R7C16!1!@baseboard_fab2_lib.baseboard_fab2(sch_1):page121_i33@mstr_discrete.res(chips)!RES_0402-33.2,1%,1/16W,CHIP,G2A!!!F705!A!!!!
S!SPI_PCH_CS0_N!R7C16!2!@baseboard_fab2_lib.baseboard_fab2(sch_1):page121_i33@mstr_discrete.res(chips)!RES_0402-33.2,1%,1/16W,CHIP,G2A!!!F705!B!!!!
S!FM_PCH_SATA_RAID_KEY_R!R9A13!1!@baseboard_fab2_lib.baseboard_fab2(sch_1):page134_i14@mstr_discrete.res(chips)!RES_0402-33.2,1%,1/16W,CHIP,G2A!!!F679!A!!!!
S!FM_PCH_SATA_RAID_KEY!R9A13!2!@baseboard_fab2_lib.baseboard_fab2(sch_1):page134_i14@mstr_discrete.res(chips)!RES_0402-33.2,1%,1/16W,CHIP,G2A!!!F679!B!!!!
S!SPI_SWITCH_MISO!R7F4!1!@baseboard_fab2_lib.baseboard_fab2(sch_1):page153_i98@mstr_discrete.res(chips)!RES_0402-33.2,1%,1/16W,CHIP,G2A!!!F697!A!!!!
S!SPI_MISO_R0!R7F4!2!@baseboard_fab2_lib.baseboard_fab2(sch_1):page153_i98@mstr_discrete.res(chips)!RES_0402-33.2,1%,1/16W,CHIP,G2A!!!F697!B!!!!
S!P3V3_STBY!R7D42!1!@baseboard_fab2_lib.baseboard_fab2(sch_1):page191_i193@mstr_discrete.res(chips)!RES_0402-4.75K,1%,1/16W,CHIP,GA!!!F529!A!!!!
S!PU_FAB2_MARKER_CPLD!R7D42!2!@baseboard_fab2_lib.baseboard_fab2(sch_1):page191_i193@mstr_discrete.res(chips)!RES_0402-4.75K,1%,1/16W,CHIP,GA!!!F529!B!!!!
S!P3V3_STBY!R1B21!1!@baseboard_fab2_lib.baseboard_fab2(sch_1):page161_i70@mstr_discrete.res(chips)!RES_0402-4.75K,1%,1/16W,CHIP,GA!!!F650!A!!!!
S!FAN_TACH2!R1B21!2!@baseboard_fab2_lib.baseboard_fab2(sch_1):page161_i70@mstr_discrete.res(chips)!RES_0402-4.75K,1%,1/16W,CHIP,GA!!!F650!B!!!!
S!P3V3_STBY!R1F1!1!@baseboard_fab2_lib.baseboard_fab2(sch_1):page161_i45@mstr_discrete.res(chips)!RES_0402-4.75K,1%,1/16W,CHIP,GA!!!F645!A!!!!
S!FAN_TACH0!R1F1!2!@baseboard_fab2_lib.baseboard_fab2(sch_1):page161_i45@mstr_discrete.res(chips)!RES_0402-4.75K,1%,1/16W,CHIP,GA!!!F645!B!!!!
S!P3V3_STBY!R2P17!1!@baseboard_fab2_lib.baseboard_fab2(sch_1):page135_i104@mstr_discrete.res(chips)!RES_0402-4.75K,1%,1/16W,CHIP,GA!!!F557!A!!!!
S!FM_PCH_BMC_THERMTRIP_N!R2P17!2!@baseboard_fab2_lib.baseboard_fab2(sch_1):page135_i104@mstr_discrete.res(chips)!RES_0402-4.75K,1%,1/16W,CHIP,GA!!!F557!B!!!!
S!P3V3!R7E21!1!@baseboard_fab2_lib.baseboard_fab2(sch_1):page108_i343@mstr_discrete.res(chips)!RES_0402-4.75K,1%,1/16W,CHIP,GA!!!F531!A!!!!
S!FM_PWRBRK_N!R7E21!2!@baseboard_fab2_lib.baseboard_fab2(sch_1):page108_i343@mstr_discrete.res(chips)!RES_0402-4.75K,1%,1/16W,CHIP,GA!!!F531!B!!!!
S!P3V3_STBY!R2U48!1!@baseboard_fab2_lib.baseboard_fab2(sch_1):page119_i213@mstr_discrete.res(chips)!RES_0402-4.75K,1%,1/16W,CHIP,GA!!!F530!A!!!!
S!FM_SLT_CFG2_R!R2U48!2!@baseboard_fab2_lib.baseboard_fab2(sch_1):page119_i213@mstr_discrete.res(chips)!RES_0402-4.75K,1%,1/16W,CHIP,GA!!!F530!B!!!!
S!PVCCIO_CPU0!R7C17!1!@baseboard_fab2_lib.baseboard_fab2(sch_1):page166_i28@mstr_discrete.res(chips)!RES_0402-4.75K,1%,1/16W,CHIP,GA!!!F600!A!!!!
S!PECI_BMC!R7C17!2!@baseboard_fab2_lib.baseboard_fab2(sch_1):page166_i28@mstr_discrete.res(chips)!RES_0402-4.75K,1%,1/16W,CHIP,GA!!!F600!B!!!!
S!P3V3_STBY!R7D3!1!@baseboard_fab2_lib.baseboard_fab2(sch_1):page133_i243@mstr_discrete.res(chips)!RES_0402-4.75K,1%,1/16W,CHIP,GA!!!F599!A!!!!
S!IRQ_LPC_SERIRQ_N!R7D3!2!@baseboard_fab2_lib.baseboard_fab2(sch_1):page133_i243@mstr_discrete.res(chips)!RES_0402-4.75K,1%,1/16W,CHIP,GA!!!F599!B!!!!
S!P3V3_STBY!R2N32!1!@baseboard_fab2_lib.baseboard_fab2(sch_1):page133_i341@mstr_discrete.res(chips)!RES_0402-4.75K,1%,1/16W,CHIP,GA!!!F590!A!!!!
S!FM_BIOS_SMI_ACTIVE_N!R2N32!2!@baseboard_fab2_lib.baseboard_fab2(sch_1):page133_i341@mstr_discrete.res(chips)!RES_0402-4.75K,1%,1/16W,CHIP,GA!!!F590!B!!!!
S!P3V3_STBY!R8D14!1!@baseboard_fab2_lib.baseboard_fab2(sch_1):page133_i301@mstr_discrete.res(chips)!RES_0402-4.75K,1%,1/16W,CHIP,GA!!!F573!A!!!!
S!FP_PWR_ID_LED_N!R8D14!2!@baseboard_fab2_lib.baseboard_fab2(sch_1):page133_i301@mstr_discrete.res(chips)!RES_0402-4.75K,1%,1/16W,CHIP,GA!!!F573!B!!!!
S!P3V3_STBY!R3P52!1!@baseboard_fab2_lib.baseboard_fab2(sch_1):page156_i340@mstr_discrete.res(chips)!RES_0402-4.75K,1%,1/16W,CHIP,GA!!!F532!A!!!!
S!FM_CPU_BMC_INIT!R3P52!2!@baseboard_fab2_lib.baseboard_fab2(sch_1):page156_i340@mstr_discrete.res(chips)!RES_0402-4.75K,1%,1/16W,CHIP,GA!!!F532!B!!!!
S!P3V3_STBY!R4C14!1!@baseboard_fab2_lib.baseboard_fab2(sch_1):page156_i294@mstr_discrete.res(chips)!RES_0402-4.75K,1%,1/16W,CHIP,GA!!!F535!A!!!!
S!FM_BMC_CPU_INIT_N!R4C14!2!@baseboard_fab2_lib.baseboard_fab2(sch_1):page156_i294@mstr_discrete.res(chips)!RES_0402-4.75K,1%,1/16W,CHIP,GA!!!F535!B!!!!
S!P1V05_PCH_STBY!R3P55!1!@baseboard_fab2_lib.baseboard_fab2(sch_1):page133_i356@mstr_discrete.res(chips)!RES_0402-4.75K,1%,1/16W,CHIP,GA!!!F534!A!!!!
S!FM_OCP_MEZZB_PRES_N!R3P55!2!@baseboard_fab2_lib.baseboard_fab2(sch_1):page133_i356@mstr_discrete.res(chips)!RES_0402-4.75K,1%,1/16W,CHIP,GA!!!F534!B!!!!
S!P1V05_PCH_STBY!R3P53!1!@baseboard_fab2_lib.baseboard_fab2(sch_1):page133_i357@mstr_discrete.res(chips)!RES_0402-4.75K,1%,1/16W,CHIP,GA!!!F533!A!!!!
S!FM_OCP_MEZZC_PRES_N!R3P53!2!@baseboard_fab2_lib.baseboard_fab2(sch_1):page133_i357@mstr_discrete.res(chips)!RES_0402-4.75K,1%,1/16W,CHIP,GA!!!F533!B!!!!
S!P3V3_STBY!R2N30!1!@baseboard_fab2_lib.baseboard_fab2(sch_1):page133_i349@mstr_discrete.res(chips)!RES_0402-4.75K,1%,1/16W,CHIP,GA!!!F537!A!!!!
S!FM_CPU0_RC_ERROR_N!R2N30!2!@baseboard_fab2_lib.baseboard_fab2(sch_1):page133_i349@mstr_discrete.res(chips)!RES_0402-4.75K,1%,1/16W,CHIP,GA!!!F537!B!!!!
S!P3V3_STBY!R2N29!1!@baseboard_fab2_lib.baseboard_fab2(sch_1):page133_i352@mstr_discrete.res(chips)!RES_0402-4.75K,1%,1/16W,CHIP,GA!!!F536!A!!!!
S!FM_CPU1_RC_ERROR_N!R2N29!2!@baseboard_fab2_lib.baseboard_fab2(sch_1):page133_i352@mstr_discrete.res(chips)!RES_0402-4.75K,1%,1/16W,CHIP,GA!!!F536!B!!!!
S!A_PG_P5V!R8D37!1!@baseboard_fab2_lib.baseboard_fab2(sch_1):page196_i115@mstr_discrete.res(chips)!RES_0402-4.75K,1%,1/16W,CHIP,GA!!!F538!A!!!!
S!GND!R8D37!2!@baseboard_fab2_lib.baseboard_fab2(sch_1):page196_i115@mstr_discrete.res(chips)!RES_0402-4.75K,1%,1/16W,CHIP,GA!!!F538!B!!!!
S!PVPP_ABC!R3R16!1!@baseboard_fab2_lib.baseboard_fab2(sch_1):page192_i48@mstr_discrete.res(chips)!RES_0402-4.75K,1%,1/16W,CHIP,GA!!!F629!A!!!!
S!RST_CD_CPU0_POR_N!R3R16!2!@baseboard_fab2_lib.baseboard_fab2(sch_1):page192_i48@mstr_discrete.res(chips)!RES_0402-4.75K,1%,1/16W,CHIP,GA!!!F629!B!!!!
S!PVPP_KLM!R6M9!1!@baseboard_fab2_lib.baseboard_fab2(sch_1):page192_i49@mstr_discrete.res(chips)!RES_0402-4.75K,1%,1/16W,CHIP,GA!!!F614!A!!!!
S!RST_CD_CPU1_POR_N!R6M9!2!@baseboard_fab2_lib.baseboard_fab2(sch_1):page192_i49@mstr_discrete.res(chips)!RES_0402-4.75K,1%,1/16W,CHIP,GA!!!F614!B!!!!
S!P3V3!R4D69!1!@baseboard_fab2_lib.baseboard_fab2(sch_1):page102_i93@mstr_discrete.res(chips)!RES_0402-4.75K,1%,1/16W,CHIP,GA!!!F604!A!!!!
S!FM_CPU1_MCP_CLK_EN_N!R4D69!2!@baseboard_fab2_lib.baseboard_fab2(sch_1):page102_i93@mstr_discrete.res(chips)!RES_0402-4.75K,1%,1/16W,CHIP,GA!!!F604!B!!!!
S!P3V3!R4D70!1!@baseboard_fab2_lib.baseboard_fab2(sch_1):page102_i94@mstr_discrete.res(chips)!RES_0402-4.75K,1%,1/16W,CHIP,GA!!!F601!A!!!!
S!FM_CPU0_MCP_CLK_EN_N!R4D70!2!@baseboard_fab2_lib.baseboard_fab2(sch_1):page102_i94@mstr_discrete.res(chips)!RES_0402-4.75K,1%,1/16W,CHIP,GA!!!F601!B!!!!
S!P3V3_STBY!R2T6!1!@baseboard_fab2_lib.baseboard_fab2(sch_1):page154_i127@mstr_discrete.res(chips)!RES_0402-4.75K,1%,1/16W,CHIP,GA!!!F625!A!!!!
S!FM_BACKUP_BIOS_SEL_N!R2T6!2!@baseboard_fab2_lib.baseboard_fab2(sch_1):page154_i127@mstr_discrete.res(chips)!RES_0402-4.75K,1%,1/16W,CHIP,GA!!!F625!B!!!!
S!P3V3_STBY!R4R5!1!@baseboard_fab2_lib.baseboard_fab2(sch_1):page21_i258@mstr_discrete.res(chips)!RES_0402-4.75K,1%,1/16W,CHIP,GA!!!F607!A!!!!
S!FM_CPU0_SKTOCC_LVT3_N!R4R5!2!@baseboard_fab2_lib.baseboard_fab2(sch_1):page21_i258@mstr_discrete.res(chips)!RES_0402-4.75K,1%,1/16W,CHIP,GA!!!F607!B!!!!
S!P3V3_STBY!R6P39!1!@baseboard_fab2_lib.baseboard_fab2(sch_1):page55_i181@mstr_discrete.res(chips)!RES_0402-4.75K,1%,1/16W,CHIP,GA!!!F602!A!!!!
S!FM_CPU1_SKTOCC_LVT3_N!R6P39!2!@baseboard_fab2_lib.baseboard_fab2(sch_1):page55_i181@mstr_discrete.res(chips)!RES_0402-4.75K,1%,1/16W,CHIP,GA!!!F602!B!!!!
S!P3V3_STBY!R8D26!1!@baseboard_fab2_lib.baseboard_fab2(sch_1):page170_i71@mstr_discrete.res(chips)!RES_0402-4.75K,1%,1/16W,CHIP,GA!!!F571!A!!!!
S!IRQ_SML1_PMBUS_ALERT_BUF_N!R8D26!2!@baseboard_fab2_lib.baseboard_fab2(sch_1):page170_i71@mstr_discrete.res(chips)!RES_0402-4.75K,1%,1/16W,CHIP,GA!!!F571!B!!!!
S!P3V3_STBY!R1R5!1!@baseboard_fab2_lib.baseboard_fab2(sch_1):page170_i73@mstr_discrete.res(chips)!RES_0402-4.75K,1%,1/16W,CHIP,GA!!!F641!A!!!!
S!FM_FAST_PROCHOT_THROTTLE_DLY_BU!R1R5!2!@baseboard_fab2_lib.baseboard_fab2(sch_1):page170_i73@mstr_discrete.res(chips)!RES_0402-4.75K,1%,1/16W,CHIP,GA!!!F641!B!!!!
S!P3V3_STBY!R8E32!1!@baseboard_fab2_lib.baseboard_fab2(sch_1):page157_i385@mstr_discrete.res(chips)!RES_0402-4.75K,1%,1/16W,CHIP,GA!!!F564!A!!!!
S!FP_NMI_BTN_OUT_R_N!R8E32!2!@baseboard_fab2_lib.baseboard_fab2(sch_1):page157_i385@mstr_discrete.res(chips)!RES_0402-4.75K,1%,1/16W,CHIP,GA!!!F564!B!!!!
S!P3V3_STBY!R9T5!1!@baseboard_fab2_lib.baseboard_fab2(sch_1):page161_i135@mstr_discrete.res(chips)!RES_0402-4.75K,1%,1/16W,CHIP,GA!!!F540!A!!!!
S!FAN_TACH1!R9T5!2!@baseboard_fab2_lib.baseboard_fab2(sch_1):page161_i135@mstr_discrete.res(chips)!RES_0402-4.75K,1%,1/16W,CHIP,GA!!!F540!B!!!!
S!P3V3_STBY!R1B24!1!@baseboard_fab2_lib.baseboard_fab2(sch_1):page161_i126@mstr_discrete.res(chips)!RES_0402-4.75K,1%,1/16W,CHIP,GA!!!F649!A!!!!
S!FAN_TACH3!R1B24!2!@baseboard_fab2_lib.baseboard_fab2(sch_1):page161_i126@mstr_discrete.res(chips)!RES_0402-4.75K,1%,1/16W,CHIP,GA!!!F649!B!!!!
S!P3V3_STBY!R8C25!1!@baseboard_fab2_lib.baseboard_fab2(sch_1):page133_i333@mstr_discrete.res(chips)!RES_0402-4.75K,1%,1/16W,CHIP,GA!!!F574!A!!!!
S!IRQ_PCH_NIC_ALERT_N!R8C25!2!@baseboard_fab2_lib.baseboard_fab2(sch_1):page133_i333@mstr_discrete.res(chips)!RES_0402-4.75K,1%,1/16W,CHIP,GA!!!F574!B!!!!
S!P3V3_STBY!R9F52!1!@baseboard_fab2_lib.baseboard_fab2(sch_1):page177_i82@mstr_discrete.res(chips)!RES_0402-4.75K,1%,1/16W,CHIP,GA!!!F543!A!!!!
S!FM_BMC_FAULT_LED!R9F52!2!@baseboard_fab2_lib.baseboard_fab2(sch_1):page177_i82@mstr_discrete.res(chips)!RES_0402-4.75K,1%,1/16W,CHIP,GA!!!F543!B!!!!
S!P3V3_STBY!R9F30!1!@baseboard_fab2_lib.baseboard_fab2(sch_1):page177_i76@mstr_discrete.res(chips)!RES_0402-4.75K,1%,1/16W,CHIP,GA!!!F547!A!!!!
S!FM_BMC_FAULT_LED_N!R9F30!2!@baseboard_fab2_lib.baseboard_fab2(sch_1):page177_i76@mstr_discrete.res(chips)!RES_0402-4.75K,1%,1/16W,CHIP,GA!!!F547!B!!!!
S!P3V3_STBY!R3P44!1!@baseboard_fab2_lib.baseboard_fab2(sch_1):page196_i59@mstr_discrete.res(chips)!RES_0402-4.75K,1%,1/16W,CHIP,GA!!!F613!A!!!!
S!PWRGD_DSW_PWROK!R3P44!2!@baseboard_fab2_lib.baseboard_fab2(sch_1):page196_i59@mstr_discrete.res(chips)!RES_0402-4.75K,1%,1/16W,CHIP,GA!!!F613!B!!!!
S!P3V3_STBY!R1L7!1!@baseboard_fab2_lib.baseboard_fab2(sch_1):page157_i382@mstr_discrete.res(chips)!RES_0402-4.75K,1%,1/16W,CHIP,GA!!!F644!A!!!!
S!FM_BMC_CPLD_MP_RST_N!R1L7!2!@baseboard_fab2_lib.baseboard_fab2(sch_1):page157_i382@mstr_discrete.res(chips)!RES_0402-4.75K,1%,1/16W,CHIP,GA!!!F644!B!!!!
S!P3V3_STBY!R1D21!1!@baseboard_fab2_lib.baseboard_fab2(sch_1):page200_i204@mstr_discrete.res(chips)!RES_0402-4.75K,1%,1/16W,CHIP,GA!!!F648!A!!!!
S!FM_OC_DETECT_EN!R1D21!2!@baseboard_fab2_lib.baseboard_fab2(sch_1):page200_i204@mstr_discrete.res(chips)!RES_0402-4.75K,1%,1/16W,CHIP,GA!!!F648!B!!!!
S!FM_BMC_DISABLE!R1R11!1!@baseboard_fab2_lib.baseboard_fab2(sch_1):page150_i66@mstr_discrete.res(chips)!RES_0402-4.75K,1%,1/16W,CHIP,GA!!!F640!A!!!!
S!P3V3_STBY!R1R11!2!@baseboard_fab2_lib.baseboard_fab2(sch_1):page150_i66@mstr_discrete.res(chips)!RES_0402-4.75K,1%,1/16W,CHIP,GA!!!F640!B!!!!
S!P3V3_STBY!R8D25!1!@baseboard_fab2_lib.baseboard_fab2(sch_1):page157_i335@mstr_discrete.res(chips)!RES_0402-4.75K,1%,1/16W,CHIP,GA!!!F572!A!!!!
S!RST_BMC_SRST_R2_N!R8D25!2!@baseboard_fab2_lib.baseboard_fab2(sch_1):page157_i335@mstr_discrete.res(chips)!RES_0402-4.75K,1%,1/16W,CHIP,GA!!!F572!B!!!!
S!P3V3_STBY!R7D30!1!@baseboard_fab2_lib.baseboard_fab2(sch_1):page134_i27@mstr_discrete.res(chips)!RES_0402-4.75K,1%,1/16W,CHIP,GA!!!F597!A!!!!
S!FM_CPLD_UART_CH_LOCK_N!R7D30!2!@baseboard_fab2_lib.baseboard_fab2(sch_1):page134_i27@mstr_discrete.res(chips)!RES_0402-4.75K,1%,1/16W,CHIP,GA!!!F597!B!!!!
S!JTAG_TCK_R!R8G23!1!@baseboard_fab2_lib.baseboard_fab2(sch_1):page189_i56@mstr_discrete.res(chips)!RES_0402-4.75K,1%,1/16W,CHIP,GA!!!F558!A!!!!
S!GND!R8G23!2!@baseboard_fab2_lib.baseboard_fab2(sch_1):page189_i56@mstr_discrete.res(chips)!RES_0402-4.75K,1%,1/16W,CHIP,GA!!!F558!B!!!!
S!P3V3!R6P48!1!@baseboard_fab2_lib.baseboard_fab2(sch_1):page102_i91@mstr_discrete.res(chips)!RES_0402-4.75K,1%,1/16W,CHIP,GA!!!F615!A!!!!
S!FM_DB1200ZL_BCLKS_EN_N!R6P48!2!@baseboard_fab2_lib.baseboard_fab2(sch_1):page102_i91@mstr_discrete.res(chips)!RES_0402-4.75K,1%,1/16W,CHIP,GA!!!F615!B!!!!
S!P3V3_STBY!R8E14!1!@baseboard_fab2_lib.baseboard_fab2(sch_1):page136_i133@mstr_discrete.res(chips)!RES_0402-4.75K,1%,1/16W,CHIP,GA!!!F568!A!!!!
S!RST_PLTRST_TOP_SWAP!R8E14!2!@baseboard_fab2_lib.baseboard_fab2(sch_1):page136_i133@mstr_discrete.res(chips)!RES_0402-4.75K,1%,1/16W,CHIP,GA!!!F568!B!!!!
S!P3V3_STBY!R8G2!1!@baseboard_fab2_lib.baseboard_fab2(sch_1):page156_i267@mstr_discrete.res(chips)!RES_0402-4.75K,1%,1/16W,CHIP,GA!!!F559!A!!!!
S!FM_PCH_PWRBTN_OUT_N!R8G2!2!@baseboard_fab2_lib.baseboard_fab2(sch_1):page156_i267@mstr_discrete.res(chips)!RES_0402-4.75K,1%,1/16W,CHIP,GA!!!F559!B!!!!
S!P3V3_STBY!R2U2!1!@baseboard_fab2_lib.baseboard_fab2(sch_1):page156_i265@mstr_discrete.res(chips)!RES_0402-4.75K,1%,1/16W,CHIP,GA!!!F621!A!!!!
S!RST_PCH_SYSRST_BTN_OUT_N!R2U2!2!@baseboard_fab2_lib.baseboard_fab2(sch_1):page156_i265@mstr_discrete.res(chips)!RES_0402-4.75K,1%,1/16W,CHIP,GA!!!F621!B!!!!
S!P3V3_STBY!R2U4!1!@baseboard_fab2_lib.baseboard_fab2(sch_1):page157_i367@mstr_discrete.res(chips)!RES_0402-4.75K,1%,1/16W,CHIP,GA!!!F620!A!!!!
S!FM_CPLD_BMC_PWRDN_N!R2U4!2!@baseboard_fab2_lib.baseboard_fab2(sch_1):page157_i367@mstr_discrete.res(chips)!RES_0402-4.75K,1%,1/16W,CHIP,GA!!!F620!B!!!!
S!P3V3_STBY!R8E19!1!@baseboard_fab2_lib.baseboard_fab2(sch_1):page157_i361@mstr_discrete.res(chips)!RES_0402-4.75K,1%,1/16W,CHIP,GA!!!F567!A!!!!
S!FM_BIOS_TOP_SWAP!R8E19!2!@baseboard_fab2_lib.baseboard_fab2(sch_1):page157_i361@mstr_discrete.res(chips)!RES_0402-4.75K,1%,1/16W,CHIP,GA!!!F567!B!!!!
S!P3V3_STBY!R1D35!1!@baseboard_fab2_lib.baseboard_fab2(sch_1):page126_i12@mstr_discrete.res(chips)!RES_0402-4.75K,1%,1/16W,CHIP,GA!!!F647!A!!!!
S!FM_OC_DETECT_EN_N!R1D35!2!@baseboard_fab2_lib.baseboard_fab2(sch_1):page126_i12@mstr_discrete.res(chips)!RES_0402-4.75K,1%,1/16W,CHIP,GA!!!F647!B!!!!
S!P3V3_STBY!R2P13!1!@baseboard_fab2_lib.baseboard_fab2(sch_1):page170_i61@mstr_discrete.res(chips)!RES_0402-4.75K,1%,1/16W,CHIP,GA!!!F628!A!!!!
S!FM_PMBUS_ALERT_BUF_EN_N!R2P13!2!@baseboard_fab2_lib.baseboard_fab2(sch_1):page170_i61@mstr_discrete.res(chips)!RES_0402-4.75K,1%,1/16W,CHIP,GA!!!F628!B!!!!
S!P3V3_STBY!R9F3!1!@baseboard_fab2_lib.baseboard_fab2(sch_1):page170_i65@mstr_discrete.res(chips)!RES_0402-4.75K,1%,1/16W,CHIP,GA!!!F553!A!!!!
S!FM_FAST_PROCHOT_EN!R9F3!2!@baseboard_fab2_lib.baseboard_fab2(sch_1):page170_i65@mstr_discrete.res(chips)!RES_0402-4.75K,1%,1/16W,CHIP,GA!!!F553!B!!!!
S!P3V3_STBY!R9A21!1!@baseboard_fab2_lib.baseboard_fab2(sch_1):page119_i186@mstr_discrete.res(chips)!RES_0402-4.75K,1%,1/16W,CHIP,GA!!!F555!A!!!!
S!FM_PWR_LED_N!R9A21!2!@baseboard_fab2_lib.baseboard_fab2(sch_1):page119_i186@mstr_discrete.res(chips)!RES_0402-4.75K,1%,1/16W,CHIP,GA!!!F555!B!!!!
S!P3V3_STBY!R9A18!1!@baseboard_fab2_lib.baseboard_fab2(sch_1):page119_i183@mstr_discrete.res(chips)!RES_0402-4.75K,1%,1/16W,CHIP,GA!!!F556!A!!!!
S!FM_PWR_LED!R9A18!2!@baseboard_fab2_lib.baseboard_fab2(sch_1):page119_i183@mstr_discrete.res(chips)!RES_0402-4.75K,1%,1/16W,CHIP,GA!!!F556!B!!!!
S!P3V3_STBY!R8B25!1!@baseboard_fab2_lib.baseboard_fab2(sch_1):page147_i140@mstr_discrete.res(chips)!RES_0402-4.75K,1%,1/16W,CHIP,GA!!!F581!A!!!!
S!FM_BMC_HEARTBEAT_N!R8B25!2!@baseboard_fab2_lib.baseboard_fab2(sch_1):page147_i140@mstr_discrete.res(chips)!RES_0402-4.75K,1%,1/16W,CHIP,GA!!!F581!B!!!!
S!P3V3_STBY!R2M5!1!@baseboard_fab2_lib.baseboard_fab2(sch_1):page157_i348@mstr_discrete.res(chips)!RES_0402-4.75K,1%,1/16W,CHIP,GA!!!F635!A!!!!
S!FM_BMC_CPLD_GPO!R2M5!2!@baseboard_fab2_lib.baseboard_fab2(sch_1):page157_i348@mstr_discrete.res(chips)!RES_0402-4.75K,1%,1/16W,CHIP,GA!!!F635!B!!!!
S!P3V3_STBY!R2T3!1!@baseboard_fab2_lib.baseboard_fab2(sch_1):page170_i54@mstr_discrete.res(chips)!RES_0402-4.75K,1%,1/16W,CHIP,GA!!!F626!A!!!!
S!FM_FAST_PROCHOT_EN_N!R2T3!2!@baseboard_fab2_lib.baseboard_fab2(sch_1):page170_i54@mstr_discrete.res(chips)!RES_0402-4.75K,1%,1/16W,CHIP,GA!!!F626!B!!!!
S!P3V3_STBY!R2P5!1!@baseboard_fab2_lib.baseboard_fab2(sch_1):page170_i56@mstr_discrete.res(chips)!RES_0402-4.75K,1%,1/16W,CHIP,GA!!!F631!A!!!!
S!FM_PMBUS_ALERT_BUF_EN!R2P5!2!@baseboard_fab2_lib.baseboard_fab2(sch_1):page170_i56@mstr_discrete.res(chips)!RES_0402-4.75K,1%,1/16W,CHIP,GA!!!F631!B!!!!
S!P3V3_STBY!R8C1!1!@baseboard_fab2_lib.baseboard_fab2(sch_1):page133_i326@mstr_discrete.res(chips)!RES_0402-4.75K,1%,1/16W,CHIP,GA!!!F579!A!!!!
S!FM_SLT_CFG1!R8C1!2!@baseboard_fab2_lib.baseboard_fab2(sch_1):page133_i326@mstr_discrete.res(chips)!RES_0402-4.75K,1%,1/16W,CHIP,GA!!!F579!B!!!!
S!P3V3_STBY!R8C7!1!@baseboard_fab2_lib.baseboard_fab2(sch_1):page133_i327@mstr_discrete.res(chips)!RES_0402-4.75K,1%,1/16W,CHIP,GA!!!F576!A!!!!
S!FM_SLT_CFG0!R8C7!2!@baseboard_fab2_lib.baseboard_fab2(sch_1):page133_i327@mstr_discrete.res(chips)!RES_0402-4.75K,1%,1/16W,CHIP,GA!!!F576!B!!!!
S!P3V3_STBY!R8C9!1!@baseboard_fab2_lib.baseboard_fab2(sch_1):page126_i20@mstr_discrete.res(chips)!RES_0402-4.75K,1%,1/16W,CHIP,GA!!!F575!A!!!!
S!IRQ_SML0_ALERT_N!R8C9!2!@baseboard_fab2_lib.baseboard_fab2(sch_1):page126_i20@mstr_discrete.res(chips)!RES_0402-4.75K,1%,1/16W,CHIP,GA!!!F575!B!!!!
S!P3V3_STBY!R2T34!1!@baseboard_fab2_lib.baseboard_fab2(sch_1):page156_i206@mstr_discrete.res(chips)!RES_0402-4.75K,1%,1/16W,CHIP,GA!!!F623!A!!!!
S!FM_BMC_PWRBTN_OUT_N!R2T34!2!@baseboard_fab2_lib.baseboard_fab2(sch_1):page156_i206@mstr_discrete.res(chips)!RES_0402-4.75K,1%,1/16W,CHIP,GA!!!F623!B!!!!
S!P3V3_STBY!R2T35!1!@baseboard_fab2_lib.baseboard_fab2(sch_1):page156_i207@mstr_discrete.res(chips)!RES_0402-4.75K,1%,1/16W,CHIP,GA!!!F622!A!!!!
S!RST_BMC_SYSRST_BTN_OUT_N!R2T35!2!@baseboard_fab2_lib.baseboard_fab2(sch_1):page156_i207@mstr_discrete.res(chips)!RES_0402-4.75K,1%,1/16W,CHIP,GA!!!F622!B!!!!
S!P3V3_DB1200!R4D41!1!@baseboard_fab2_lib.baseboard_fab2(sch_1):page102_i53@mstr_discrete.res(chips)!RES_0402-4.75K,1%,1/16W,CHIP,GA!!!F608!A!!!!
S!FM_HBW_BYPASS_LOWBW_N!R4D41!2!@baseboard_fab2_lib.baseboard_fab2(sch_1):page102_i53@mstr_discrete.res(chips)!RES_0402-4.75K,1%,1/16W,CHIP,GA!!!F608!B!!!!
S!P3V3_STBY!R2N7!1!@baseboard_fab2_lib.baseboard_fab2(sch_1):page133_i309@mstr_discrete.res(chips)!RES_0402-4.75K,1%,1/16W,CHIP,GA!!!F634!A!!!!
S!IRQ_BOARD_BMC_ALERT_N!R2N7!2!@baseboard_fab2_lib.baseboard_fab2(sch_1):page133_i309@mstr_discrete.res(chips)!RES_0402-4.75K,1%,1/16W,CHIP,GA!!!F634!B!!!!
S!P5V_STBY!R1E12!1!@baseboard_fab2_lib.baseboard_fab2(sch_1):page161_i51@mstr_discrete.res(chips)!RES_0402-4.75K,1%,1/16W,CHIP,GA!!!F646!A!!!!
S!FAN_PWM_OUT_SYS0_R!R1E12!2!@baseboard_fab2_lib.baseboard_fab2(sch_1):page161_i51@mstr_discrete.res(chips)!RES_0402-4.75K,1%,1/16W,CHIP,GA!!!F646!B!!!!
S!P5V_STBY!R7F33!1!@baseboard_fab2_lib.baseboard_fab2(sch_1):page161_i65@mstr_discrete.res(chips)!RES_0402-4.75K,1%,1/16W,CHIP,GA!!!F592!A!!!!
S!FAN_PWM_OUT_SYS1_R!R7F33!2!@baseboard_fab2_lib.baseboard_fab2(sch_1):page161_i65@mstr_discrete.res(chips)!RES_0402-4.75K,1%,1/16W,CHIP,GA!!!F592!B!!!!
S!P3V3_STBY!R7D6!1!@baseboard_fab2_lib.baseboard_fab2(sch_1):page133_i306@mstr_discrete.res(chips)!RES_0402-4.75K,1%,1/16W,CHIP,GA!!!F598!A!!!!
S!FM_BMC_READY_N!R7D6!2!@baseboard_fab2_lib.baseboard_fab2(sch_1):page133_i306@mstr_discrete.res(chips)!RES_0402-4.75K,1%,1/16W,CHIP,GA!!!F598!B!!!!
S!P3V3_STBY!R8C6!1!@baseboard_fab2_lib.baseboard_fab2(sch_1):page133_i303@mstr_discrete.res(chips)!RES_0402-4.75K,1%,1/16W,CHIP,GA!!!F577!A!!!!
S!FM_BIOS_POST_CMPLT_N!R8C6!2!@baseboard_fab2_lib.baseboard_fab2(sch_1):page133_i303@mstr_discrete.res(chips)!RES_0402-4.75K,1%,1/16W,CHIP,GA!!!F577!B!!!!
S!P3V3_STBY!R8C2!1!@baseboard_fab2_lib.baseboard_fab2(sch_1):page133_i304@mstr_discrete.res(chips)!RES_0402-4.75K,1%,1/16W,CHIP,GA!!!F578!A!!!!
S!IRQ_BMC_PCH_SCI_LPC_N!R8C2!2!@baseboard_fab2_lib.baseboard_fab2(sch_1):page133_i304@mstr_discrete.res(chips)!RES_0402-4.75K,1%,1/16W,CHIP,GA!!!F578!B!!!!
S!P3V3_STBY!R8B31!1!@baseboard_fab2_lib.baseboard_fab2(sch_1):page133_i307@mstr_discrete.res(chips)!RES_0402-4.75K,1%,1/16W,CHIP,GA!!!F580!A!!!!
S!FM_THROTTLE_N!R8B31!2!@baseboard_fab2_lib.baseboard_fab2(sch_1):page133_i307@mstr_discrete.res(chips)!RES_0402-4.75K,1%,1/16W,CHIP,GA!!!F580!B!!!!
S!P3V3_STBY!R2P3!1!@baseboard_fab2_lib.baseboard_fab2(sch_1):page170_i2@mstr_discrete.res(chips)!RES_0402-4.75K,1%,1/16W,CHIP,GA!!!F632!A!!!!
S!IRQ_FORCE_NM_THROTTLE_R_N!R2P3!2!@baseboard_fab2_lib.baseboard_fab2(sch_1):page170_i2@mstr_discrete.res(chips)!RES_0402-4.75K,1%,1/16W,CHIP,GA!!!F632!B!!!!
S!P3V3_STBY!R2M2!1!@baseboard_fab2_lib.baseboard_fab2(sch_1):page157_i346@mstr_discrete.res(chips)!RES_0402-4.75K,1%,1/16W,CHIP,GA!!!F636!A!!!!
S!FM_ADR_SMI_GPIO_N!R2M2!2!@baseboard_fab2_lib.baseboard_fab2(sch_1):page157_i346@mstr_discrete.res(chips)!RES_0402-4.75K,1%,1/16W,CHIP,GA!!!F636!B!!!!
S!P3V3_STBY!R9E21!1!@baseboard_fab2_lib.baseboard_fab2(sch_1):page147_i137@mstr_discrete.res(chips)!RES_0402-4.75K,1%,1/16W,CHIP,GA!!!F554!A!!!!
S!FM_HEARTBEAT_LED!R9E21!2!@baseboard_fab2_lib.baseboard_fab2(sch_1):page147_i137@mstr_discrete.res(chips)!RES_0402-4.75K,1%,1/16W,CHIP,GA!!!F554!B!!!!
S!P3V3_STBY!R3N12!1!@baseboard_fab2_lib.baseboard_fab2(sch_1):page157_i342@mstr_discrete.res(chips)!RES_0402-4.75K,1%,1/16W,CHIP,GA!!!F617!A!!!!
S!FM_MP_PS_FAIL_N!R3N12!2!@baseboard_fab2_lib.baseboard_fab2(sch_1):page157_i342@mstr_discrete.res(chips)!RES_0402-4.75K,1%,1/16W,CHIP,GA!!!F617!B!!!!
S!P3V3_STBY!R3N11!1!@baseboard_fab2_lib.baseboard_fab2(sch_1):page157_i344@mstr_discrete.res(chips)!RES_0402-4.75K,1%,1/16W,CHIP,GA!!!F618!A!!!!
S!FM_MP_PS_REDUNDANT_LOST_N!R3N11!2!@baseboard_fab2_lib.baseboard_fab2(sch_1):page157_i344@mstr_discrete.res(chips)!RES_0402-4.75K,1%,1/16W,CHIP,GA!!!F618!B!!!!
S!P3V3_STBY!R2P8!1!@baseboard_fab2_lib.baseboard_fab2(sch_1):page170_i52@mstr_discrete.res(chips)!RES_0402-4.75K,1%,1/16W,CHIP,GA!!!F630!A!!!!
S!IRQ_SML1_PMBUS_ALERT_N!R2P8!2!@baseboard_fab2_lib.baseboard_fab2(sch_1):page170_i52@mstr_discrete.res(chips)!RES_0402-4.75K,1%,1/16W,CHIP,GA!!!F630!B!!!!
S!P3V3_STBY!R2R7!1!@baseboard_fab2_lib.baseboard_fab2(sch_1):page191_i172@mstr_discrete.res(chips)!RES_0402-4.75K,1%,1/16W,CHIP,GA!!!F627!A!!!!
S!FM_FORCE_ADR_N!R2R7!2!@baseboard_fab2_lib.baseboard_fab2(sch_1):page191_i172@mstr_discrete.res(chips)!RES_0402-4.75K,1%,1/16W,CHIP,GA!!!F627!B!!!!
S!P12V_PSU!R9T9!1!@baseboard_fab2_lib.baseboard_fab2(sch_1):page181_i177@mstr_discrete.res(chips)!RES_0402-4.75K,1%,1/16W,CHIP,GA!!!F539!A!!!!
S!FM_MATED_IN_N!R9T9!2!@baseboard_fab2_lib.baseboard_fab2(sch_1):page181_i177@mstr_discrete.res(chips)!RES_0402-4.75K,1%,1/16W,CHIP,GA!!!F539!B!!!!
S!P3V3!R7E7!1!@baseboard_fab2_lib.baseboard_fab2(sch_1):page95_i106@mstr_discrete.res(chips)!RES_0402-4.75K,1%,1/16W,CHIP,GA!!!F596!A!!!!
S!FM_SYS_THROTTLE_LVC3!R7E7!2!@baseboard_fab2_lib.baseboard_fab2(sch_1):page95_i106@mstr_discrete.res(chips)!RES_0402-4.75K,1%,1/16W,CHIP,GA!!!F596!B!!!!
S!FM_ROMA<15>!R9F35!1!@baseboard_fab2_lib.baseboard_fab2(sch_1):page150_i51@mstr_discrete.res(chips)!RES_0402-4.75K,1%,1/16W,CHIP,GA!!!F546!A!!!!
S!P3V3_STBY!R9F35!2!@baseboard_fab2_lib.baseboard_fab2(sch_1):page150_i51@mstr_discrete.res(chips)!RES_0402-4.75K,1%,1/16W,CHIP,GA!!!F546!B!!!!
S!P3V3_STBY!R2U30!1!@baseboard_fab2_lib.baseboard_fab2(sch_1):page125_i76@mstr_discrete.res(chips)!RES_0402-4.75K,1%,1/16W,CHIP,GA!!!F619!A!!!!
S!FM_UV_ADR_TRIGGER_EN!R2U30!2!@baseboard_fab2_lib.baseboard_fab2(sch_1):page125_i76@mstr_discrete.res(chips)!RES_0402-4.75K,1%,1/16W,CHIP,GA!!!F619!B!!!!
S!P3V3_STBY!R9F47!1!@baseboard_fab2_lib.baseboard_fab2(sch_1):page183_i4@mstr_discrete.res(chips)!RES_0402-4.75K,1%,1/16W,CHIP,GA!!!F544!A!!!!
S!PU_PI7C9X1172_I2C_SPI_N!R9F47!2!@baseboard_fab2_lib.baseboard_fab2(sch_1):page183_i4@mstr_discrete.res(chips)!RES_0402-4.75K,1%,1/16W,CHIP,GA!!!F544!B!!!!
S!P3V3_STBY!R9F55!1!@baseboard_fab2_lib.baseboard_fab2(sch_1):page183_i30@mstr_discrete.res(chips)!RES_0402-4.75K,1%,1/16W,CHIP,GA!!!F542!A!!!!
S!FM_UART_ALERT_N!R9F55!2!@baseboard_fab2_lib.baseboard_fab2(sch_1):page183_i30@mstr_discrete.res(chips)!RES_0402-4.75K,1%,1/16W,CHIP,GA!!!F542!B!!!!
S!P3V3_STBY!R8D29!1!@baseboard_fab2_lib.baseboard_fab2(sch_1):page89_i26@mstr_discrete.res(chips)!RES_0402-4.75K,1%,1/16W,CHIP,GA!!!F570!A!!!!
S!IRQ_DIMM_SAVE_LVT3!R8D29!2!@baseboard_fab2_lib.baseboard_fab2(sch_1):page89_i26@mstr_discrete.res(chips)!RES_0402-4.75K,1%,1/16W,CHIP,GA!!!F570!B!!!!
S!P3V3_STBY!R8D31!1!@baseboard_fab2_lib.baseboard_fab2(sch_1):page89_i27@mstr_discrete.res(chips)!RES_0402-4.75K,1%,1/16W,CHIP,GA!!!F569!A!!!!
S!IRQ_DIMM_SAVE_LVT3_N!R8D31!2!@baseboard_fab2_lib.baseboard_fab2(sch_1):page89_i27@mstr_discrete.res(chips)!RES_0402-4.75K,1%,1/16W,CHIP,GA!!!F569!B!!!!
S!PVPP_ABC!R8B3!1!@baseboard_fab2_lib.baseboard_fab2(sch_1):page91_i24@mstr_discrete.res(chips)!RES_0402-4.75K,1%,1/16W,CHIP,GA!!!F589!A!!!!
S!FM_MODPRST_HFI0_CPU0_LVT2_N!R8B3!2!@baseboard_fab2_lib.baseboard_fab2(sch_1):page91_i24@mstr_discrete.res(chips)!RES_0402-4.75K,1%,1/16W,CHIP,GA!!!F589!B!!!!
S!PVPP_ABC!R8B5!1!@baseboard_fab2_lib.baseboard_fab2(sch_1):page91_i22@mstr_discrete.res(chips)!RES_0402-4.75K,1%,1/16W,CHIP,GA!!!F588!A!!!!
S!LED_HFI0_CPU0_N!R8B5!2!@baseboard_fab2_lib.baseboard_fab2(sch_1):page91_i22@mstr_discrete.res(chips)!RES_0402-4.75K,1%,1/16W,CHIP,GA!!!F588!B!!!!
S!PVPP_ABC!R8B19!1!@baseboard_fab2_lib.baseboard_fab2(sch_1):page91_i21@mstr_discrete.res(chips)!RES_0402-4.75K,1%,1/16W,CHIP,GA!!!F582!A!!!!
S!FM_MODPRST_HFI1_CPU0_LVT2_N!R8B19!2!@baseboard_fab2_lib.baseboard_fab2(sch_1):page91_i21@mstr_discrete.res(chips)!RES_0402-4.75K,1%,1/16W,CHIP,GA!!!F582!B!!!!
S!PVPP_ABC!R8B18!1!@baseboard_fab2_lib.baseboard_fab2(sch_1):page91_i20@mstr_discrete.res(chips)!RES_0402-4.75K,1%,1/16W,CHIP,GA!!!F583!A!!!!
S!LED_HFI1_CPU0_N!R8B18!2!@baseboard_fab2_lib.baseboard_fab2(sch_1):page91_i20@mstr_discrete.res(chips)!RES_0402-4.75K,1%,1/16W,CHIP,GA!!!F583!B!!!!
S!PVPP_ABC!R8B17!1!@baseboard_fab2_lib.baseboard_fab2(sch_1):page91_i18@mstr_discrete.res(chips)!RES_0402-4.75K,1%,1/16W,CHIP,GA!!!F584!A!!!!
S!IRQ_HFI1_CPU0_LVT2_N!R8B17!2!@baseboard_fab2_lib.baseboard_fab2(sch_1):page91_i18@mstr_discrete.res(chips)!RES_0402-4.75K,1%,1/16W,CHIP,GA!!!F584!B!!!!
S!PVPP_ABC!R8B16!1!@baseboard_fab2_lib.baseboard_fab2(sch_1):page91_i17@mstr_discrete.res(chips)!RES_0402-4.75K,1%,1/16W,CHIP,GA!!!F585!A!!!!
S!RST_HFI1_CPU0_LVT2_N!R8B16!2!@baseboard_fab2_lib.baseboard_fab2(sch_1):page91_i17@mstr_discrete.res(chips)!RES_0402-4.75K,1%,1/16W,CHIP,GA!!!F585!B!!!!
S!PVPP_ABC!R8B10!1!@baseboard_fab2_lib.baseboard_fab2(sch_1):page91_i16@mstr_discrete.res(chips)!RES_0402-4.75K,1%,1/16W,CHIP,GA!!!F586!A!!!!
S!IRQ_HFI0_CPU0_LVT2_N!R8B10!2!@baseboard_fab2_lib.baseboard_fab2(sch_1):page91_i16@mstr_discrete.res(chips)!RES_0402-4.75K,1%,1/16W,CHIP,GA!!!F586!B!!!!
S!PVPP_ABC!R8B8!1!@baseboard_fab2_lib.baseboard_fab2(sch_1):page91_i14@mstr_discrete.res(chips)!RES_0402-4.75K,1%,1/16W,CHIP,GA!!!F587!A!!!!
S!RST_HFI0_CPU0_LVT2_N!R8B8!2!@baseboard_fab2_lib.baseboard_fab2(sch_1):page91_i14@mstr_discrete.res(chips)!RES_0402-4.75K,1%,1/16W,CHIP,GA!!!F587!B!!!!
S!FM_ROMA<19>!R9F14!1!@baseboard_fab2_lib.baseboard_fab2(sch_1):page150_i47@mstr_discrete.res(chips)!RES_0402-4.75K,1%,1/16W,CHIP,GA!!!F551!A!!!!
S!P3V3_STBY!R9F14!2!@baseboard_fab2_lib.baseboard_fab2(sch_1):page150_i47@mstr_discrete.res(chips)!RES_0402-4.75K,1%,1/16W,CHIP,GA!!!F551!B!!!!
S!FM_ROMA<14>!R9F9!1!@baseboard_fab2_lib.baseboard_fab2(sch_1):page150_i52@mstr_discrete.res(chips)!RES_0402-4.75K,1%,1/16W,CHIP,GA!!!F552!A!!!!
S!P3V3_STBY!R9F9!2!@baseboard_fab2_lib.baseboard_fab2(sch_1):page150_i52@mstr_discrete.res(chips)!RES_0402-4.75K,1%,1/16W,CHIP,GA!!!F552!B!!!!
S!FM_ROMA<12>!R1T14!1!@baseboard_fab2_lib.baseboard_fab2(sch_1):page150_i54@mstr_discrete.res(chips)!RES_0402-4.75K,1%,1/16W,CHIP,GA!!!F639!A!!!!
S!P3V3_STBY!R1T14!2!@baseboard_fab2_lib.baseboard_fab2(sch_1):page150_i54@mstr_discrete.res(chips)!RES_0402-4.75K,1%,1/16W,CHIP,GA!!!F639!B!!!!
S!FM_ROMA<10>!R9F16!1!@baseboard_fab2_lib.baseboard_fab2(sch_1):page150_i56@mstr_discrete.res(chips)!RES_0402-4.75K,1%,1/16W,CHIP,GA!!!F549!A!!!!
S!P3V3_STBY!R9F16!2!@baseboard_fab2_lib.baseboard_fab2(sch_1):page150_i56@mstr_discrete.res(chips)!RES_0402-4.75K,1%,1/16W,CHIP,GA!!!F549!B!!!!
S!FM_ROMA<1>!R9F40!1!@baseboard_fab2_lib.baseboard_fab2(sch_1):page150_i65@mstr_discrete.res(chips)!RES_0402-4.75K,1%,1/16W,CHIP,GA!!!F545!A!!!!
S!P3V3_STBY!R9F40!2!@baseboard_fab2_lib.baseboard_fab2(sch_1):page150_i65@mstr_discrete.res(chips)!RES_0402-4.75K,1%,1/16W,CHIP,GA!!!F545!B!!!!
S!P3V3!R7E10!1!@baseboard_fab2_lib.baseboard_fab2(sch_1):page95_i62@mstr_discrete.res(chips)!RES_0402-4.75K,1%,1/16W,CHIP,GA!!!F595!A!!!!
S!IRQ_CPU0_VRHOT!R7E10!2!@baseboard_fab2_lib.baseboard_fab2(sch_1):page95_i62@mstr_discrete.res(chips)!RES_0402-4.75K,1%,1/16W,CHIP,GA!!!F595!B!!!!
S!P3V3!R7E11!1!@baseboard_fab2_lib.baseboard_fab2(sch_1):page95_i72@mstr_discrete.res(chips)!RES_0402-4.75K,1%,1/16W,CHIP,GA!!!F594!A!!!!
S!IRQ_CPU1_VRHOT!R7E11!2!@baseboard_fab2_lib.baseboard_fab2(sch_1):page95_i72@mstr_discrete.res(chips)!RES_0402-4.75K,1%,1/16W,CHIP,GA!!!F594!B!!!!
S!P3V3_STBY!R3N13!1!@baseboard_fab2_lib.baseboard_fab2(sch_1):page118_i71@mstr_discrete.res(chips)!RES_0402-4.75K,1%,1/16W,CHIP,GA!!!F616!A!!!!
S!IRQ_LVC3_WAKE_N!R3N13!2!@baseboard_fab2_lib.baseboard_fab2(sch_1):page118_i71@mstr_discrete.res(chips)!RES_0402-4.75K,1%,1/16W,CHIP,GA!!!F616!B!!!!
S!FM_ROMA<8>!R9F15!1!@baseboard_fab2_lib.baseboard_fab2(sch_1):page150_i111@mstr_discrete.res(chips)!RES_0402-4.75K,1%,1/16W,CHIP,GA!!!F550!A!!!!
S!P3V3_STBY!R9F15!2!@baseboard_fab2_lib.baseboard_fab2(sch_1):page150_i111@mstr_discrete.res(chips)!RES_0402-4.75K,1%,1/16W,CHIP,GA!!!F550!B!!!!
S!P3V3_STBY!R2T11!1!@baseboard_fab2_lib.baseboard_fab2(sch_1):page154_i105@mstr_discrete.res(chips)!RES_0402-4.75K,1%,1/16W,CHIP,GA!!!F624!A!!!!
S!FM_DUAL_BIOS_SEL_N!R2T11!2!@baseboard_fab2_lib.baseboard_fab2(sch_1):page154_i105@mstr_discrete.res(chips)!RES_0402-4.75K,1%,1/16W,CHIP,GA!!!F624!B!!!!
S!PU_TRI_STATE_EN!R8E23!1!@baseboard_fab2_lib.baseboard_fab2(sch_1):page142_i3@mstr_discrete.res(chips)!RES_0402-4.75K,1%,1/16W,CHIP,GA!!!F565!A!!!!
S!P3V3_STBY!R8E23!2!@baseboard_fab2_lib.baseboard_fab2(sch_1):page142_i3@mstr_discrete.res(chips)!RES_0402-4.75K,1%,1/16W,CHIP,GA!!!F565!B!!!!
S!P3V3_STBY!R8E22!1!@baseboard_fab2_lib.baseboard_fab2(sch_1):page156_i215@mstr_discrete.res(chips)!RES_0402-4.75K,1%,1/16W,CHIP,GA!!!F566!A!!!!
S!IRQ_BMC_PCH_NMI_STBY_N!R8E22!2!@baseboard_fab2_lib.baseboard_fab2(sch_1):page156_i215@mstr_discrete.res(chips)!RES_0402-4.75K,1%,1/16W,CHIP,GA!!!F566!B!!!!
S!P3V3_DB1200!R4D40!1!@baseboard_fab2_lib.baseboard_fab2(sch_1):page102_i45@mstr_discrete.res(chips)!RES_0402-4.75K,1%,1/16W,CHIP,GA!!!F609!A!!!!
S!FM_100M_N!R4D40!2!@baseboard_fab2_lib.baseboard_fab2(sch_1):page102_i45@mstr_discrete.res(chips)!RES_0402-4.75K,1%,1/16W,CHIP,GA!!!F609!B!!!!
S!P3V3_STBY!R1L27!1!@baseboard_fab2_lib.baseboard_fab2(sch_1):page175_i5@mstr_discrete.res(chips)!RES_0402-4.75K,1%,1/16W,CHIP,GA!!!F643!A!!!!
S!FP_PWR_BTN_R_N!R1L27!2!@baseboard_fab2_lib.baseboard_fab2(sch_1):page175_i5@mstr_discrete.res(chips)!RES_0402-4.75K,1%,1/16W,CHIP,GA!!!F643!B!!!!
S!FM_ADC128_A1!R1U48!1!@baseboard_fab2_lib.baseboard_fab2(sch_1):page165_i56@mstr_discrete.res(chips)!RES_0402-4.75K,1%,1/16W,CHIP,GA!!!F637!A!!!!
S!GND!R1U48!2!@baseboard_fab2_lib.baseboard_fab2(sch_1):page165_i56@mstr_discrete.res(chips)!RES_0402-4.75K,1%,1/16W,CHIP,GA!!!F637!B!!!!
S!FM_ADC128_A0!R1U45!1!@baseboard_fab2_lib.baseboard_fab2(sch_1):page165_i55@mstr_discrete.res(chips)!RES_0402-4.75K,1%,1/16W,CHIP,GA!!!F638!A!!!!
S!GND!R1U45!2!@baseboard_fab2_lib.baseboard_fab2(sch_1):page165_i55@mstr_discrete.res(chips)!RES_0402-4.75K,1%,1/16W,CHIP,GA!!!F638!B!!!!
S!P3V3_STBY!R9G21!1!@baseboard_fab2_lib.baseboard_fab2(sch_1):page165_i69@mstr_discrete.res(chips)!RES_0402-4.75K,1%,1/16W,CHIP,GA!!!F541!A!!!!
S!IRQ_VM_INT_R_N!R9G21!2!@baseboard_fab2_lib.baseboard_fab2(sch_1):page165_i69@mstr_discrete.res(chips)!RES_0402-4.75K,1%,1/16W,CHIP,GA!!!F541!B!!!!
S!PVPP_ABC!R4U3!1!@baseboard_fab2_lib.baseboard_fab2(sch_1):page94_i94@mstr_discrete.res(chips)!RES_0402-4.75K,1%,1/16W,CHIP,GA!!!F605!A!!!!
S!FM_DIMM_EVENT_FET!R4U3!2!@baseboard_fab2_lib.baseboard_fab2(sch_1):page94_i94@mstr_discrete.res(chips)!RES_0402-4.75K,1%,1/16W,CHIP,GA!!!F605!B!!!!
S!P3V3_STBY!R4U1!1!@baseboard_fab2_lib.baseboard_fab2(sch_1):page94_i91@mstr_discrete.res(chips)!RES_0402-4.75K,1%,1/16W,CHIP,GA!!!F606!A!!!!
S!FM_MEM_THERM_EVENT_LVT3_N!R4U1!2!@baseboard_fab2_lib.baseboard_fab2(sch_1):page94_i91@mstr_discrete.res(chips)!RES_0402-4.75K,1%,1/16W,CHIP,GA!!!F606!B!!!!
S!P3V3_STBY!R8F24!1!@baseboard_fab2_lib.baseboard_fab2(sch_1):page157_i316@mstr_discrete.res(chips)!RES_0402-4.75K,1%,1/16W,CHIP,GA!!!F561!A!!!!
S!FP_NMI_BTN_N!R8F24!2!@baseboard_fab2_lib.baseboard_fab2(sch_1):page157_i316@mstr_discrete.res(chips)!RES_0402-4.75K,1%,1/16W,CHIP,GA!!!F561!B!!!!
S!P3V3_STBY!R3T5!1!@baseboard_fab2_lib.baseboard_fab2(sch_1):page153_i152@mstr_discrete.res(chips)!RES_0402-4.75K,1%,1/16W,CHIP,GA!!!F610!A!!!!
S!SPI_CS0_SECONDARY_R_N!R3T5!2!@baseboard_fab2_lib.baseboard_fab2(sch_1):page153_i152@mstr_discrete.res(chips)!RES_0402-4.75K,1%,1/16W,CHIP,GA!!!F610!B!!!!
S!P3V3_STBY!R8F14!1!@baseboard_fab2_lib.baseboard_fab2(sch_1):page162_i9@mstr_discrete.res(chips)!RES_0402-4.75K,1%,1/16W,CHIP,GA!!!F562!A!!!!
S!PU_SPI_BMC_BT_HOLD_N!R8F14!2!@baseboard_fab2_lib.baseboard_fab2(sch_1):page162_i9@mstr_discrete.res(chips)!RES_0402-4.75K,1%,1/16W,CHIP,GA!!!F562!B!!!!
S!P3V3_STBY!R8F13!1!@baseboard_fab2_lib.baseboard_fab2(sch_1):page162_i23@mstr_discrete.res(chips)!RES_0402-4.75K,1%,1/16W,CHIP,GA!!!F563!A!!!!
S!SPI_BMC_BT_CS_N!R8F13!2!@baseboard_fab2_lib.baseboard_fab2(sch_1):page162_i23@mstr_discrete.res(chips)!RES_0402-4.75K,1%,1/16W,CHIP,GA!!!F563!B!!!!
S!P3V3_STBY!R8F34!1!@baseboard_fab2_lib.baseboard_fab2(sch_1):page162_i22@mstr_discrete.res(chips)!RES_0402-4.75K,1%,1/16W,CHIP,GA!!!F560!A!!!!
S!PU_SPI_BMC_BT_WP_N!R8F34!2!@baseboard_fab2_lib.baseboard_fab2(sch_1):page162_i22@mstr_discrete.res(chips)!RES_0402-4.75K,1%,1/16W,CHIP,GA!!!F560!B!!!!
S!P3V3_STBY!R7F5!1!@baseboard_fab2_lib.baseboard_fab2(sch_1):page153_i94@mstr_discrete.res(chips)!RES_0402-4.75K,1%,1/16W,CHIP,GA!!!F593!A!!!!
S!SPI_CS0_PRIMARY_R_N!R7F5!2!@baseboard_fab2_lib.baseboard_fab2(sch_1):page153_i94@mstr_discrete.res(chips)!RES_0402-4.75K,1%,1/16W,CHIP,GA!!!F593!B!!!!
S!P3V3_STBY!R1L28!1!@baseboard_fab2_lib.baseboard_fab2(sch_1):page111_i66@mstr_discrete.res(chips)!RES_0402-4.75K,1%,1/16W,CHIP,GA!!!F642!A!!!!
S!FM_DEBUG_RST_BTN_R1_N!R1L28!2!@baseboard_fab2_lib.baseboard_fab2(sch_1):page111_i66@mstr_discrete.res(chips)!RES_0402-4.75K,1%,1/16W,CHIP,GA!!!F642!B!!!!
S!P1V538_BMC_STBY!R9F29!1!@baseboard_fab2_lib.baseboard_fab2(sch_1):page151_i71@mstr_discrete.res(chips)!RES_0402-4.75K,1%,1/16W,CHIP,GA!!!F548!A!!!!
S!RST_BMC_DDR3_R_N!R9F29!2!@baseboard_fab2_lib.baseboard_fab2(sch_1):page151_i71@mstr_discrete.res(chips)!RES_0402-4.75K,1%,1/16W,CHIP,GA!!!F548!B!!!!
S!P3V3!R7G7!1!@baseboard_fab2_lib.baseboard_fab2(sch_1):page94_i51@mstr_discrete.res(chips)!RES_0402-4.75K,1%,1/16W,CHIP,GA!!!F591!A!!!!
S!H_CPU0_MEMABC_MEMHOT!R7G7!2!@baseboard_fab2_lib.baseboard_fab2(sch_1):page94_i51@mstr_discrete.res(chips)!RES_0402-4.75K,1%,1/16W,CHIP,GA!!!F591!B!!!!
S!P3V3!R3R4!1!@baseboard_fab2_lib.baseboard_fab2(sch_1):page94_i66@mstr_discrete.res(chips)!RES_0402-4.75K,1%,1/16W,CHIP,GA!!!F612!A!!!!
S!H_CPU0_MEMDEF_MEMHOT!R3R4!2!@baseboard_fab2_lib.baseboard_fab2(sch_1):page94_i66@mstr_discrete.res(chips)!RES_0402-4.75K,1%,1/16W,CHIP,GA!!!F612!B!!!!
S!P3V3!R3R10!1!@baseboard_fab2_lib.baseboard_fab2(sch_1):page94_i79@mstr_discrete.res(chips)!RES_0402-4.75K,1%,1/16W,CHIP,GA!!!F611!A!!!!
S!H_CPU1_MEMGHJ_MEMHOT!R3R10!2!@baseboard_fab2_lib.baseboard_fab2(sch_1):page94_i79@mstr_discrete.res(chips)!RES_0402-4.75K,1%,1/16W,CHIP,GA!!!F611!B!!!!
S!P3V3!R6M4!1!@baseboard_fab2_lib.baseboard_fab2(sch_1):page94_i82@mstr_discrete.res(chips)!RES_0402-4.75K,1%,1/16W,CHIP,GA!!!F603!A!!!!
S!H_CPU1_MEMKLM_MEMHOT!R6M4!2!@baseboard_fab2_lib.baseboard_fab2(sch_1):page94_i82@mstr_discrete.res(chips)!RES_0402-4.75K,1%,1/16W,CHIP,GA!!!F603!B!!!!
S!P3V3!R2N27!1!@baseboard_fab2_lib.baseboard_fab2(sch_1):page157_i97@mstr_discrete.res(chips)!RES_0402-4.75K,1%,1/16W,CHIP,GA!!!F633!A!!!!
S!FM_BMC_NMI_N!R2N27!2!@baseboard_fab2_lib.baseboard_fab2(sch_1):page157_i97@mstr_discrete.res(chips)!RES_0402-4.75K,1%,1/16W,CHIP,GA!!!F633!B!!!!
S!H_CPU_ERR0_GTL_R_N!R2T16!1!@baseboard_fab2_lib.baseboard_fab2(sch_1):page93_i67@mstr_discrete.res(chips)!RES_0402-75,1.0%,1/16W,CHIP,G2A!!!F304!A!!!!
S!H_CPU_ERR0_GTL_N!R2T16!2!@baseboard_fab2_lib.baseboard_fab2(sch_1):page93_i67@mstr_discrete.res(chips)!RES_0402-75,1.0%,1/16W,CHIP,G2A!!!F304!B!!!!
S!H_CPU_ERR1_GTL_R_N!R2T31!1!@baseboard_fab2_lib.baseboard_fab2(sch_1):page93_i68@mstr_discrete.res(chips)!RES_0402-75,1.0%,1/16W,CHIP,G2A!!!F303!A!!!!
S!H_CPU_ERR1_GTL_N!R2T31!2!@baseboard_fab2_lib.baseboard_fab2(sch_1):page93_i68@mstr_discrete.res(chips)!RES_0402-75,1.0%,1/16W,CHIP,G2A!!!F303!B!!!!
S!SPI_CS0_SECONDARY_N!R2T9!1!@baseboard_fab2_lib.baseboard_fab2(sch_1):page154_i62@mstr_discrete.res(chips)!RES_0402-75,1.0%,1/16W,CHIP,G2A!!!F305!A!!!!
S!SPI_CS0_SECONDARY_R_N!R2T9!2!@baseboard_fab2_lib.baseboard_fab2(sch_1):page154_i62@mstr_discrete.res(chips)!RES_0402-75,1.0%,1/16W,CHIP,G2A!!!F305!B!!!!
S!PVCCIO_CPU1!R3P41!1!@baseboard_fab2_lib.baseboard_fab2(sch_1):page92_i9@mstr_discrete.res(chips)!RES_0402-75,1.0%,1/16W,CHIP,G2A!!!F301!A!!!!
S!H_CPU1_THERMTRIP_G_N!R3P41!2!@baseboard_fab2_lib.baseboard_fab2(sch_1):page92_i9@mstr_discrete.res(chips)!RES_0402-75,1.0%,1/16W,CHIP,G2A!!!F301!B!!!!
S!H_CPU_ERR2_G_R_N!R2T43!1!@baseboard_fab2_lib.baseboard_fab2(sch_1):page92_i96@mstr_discrete.res(chips)!RES_0402-75,1.0%,1/16W,CHIP,G2A!!!F302!A!!!!
S!H_CPU_ERR2_GTL_N!R2T43!2!@baseboard_fab2_lib.baseboard_fab2(sch_1):page92_i96@mstr_discrete.res(chips)!RES_0402-75,1.0%,1/16W,CHIP,G2A!!!F302!B!!!!
S!PVCCIO_CPU0!R7E2!1!@baseboard_fab2_lib.baseboard_fab2(sch_1):page92_i19@mstr_discrete.res(chips)!RES_0402-75,1.0%,1/16W,CHIP,G2A!!!F300!A!!!!
S!H_CPU0_THERMTRIP_G_N!R7E2!2!@baseboard_fab2_lib.baseboard_fab2(sch_1):page92_i19@mstr_discrete.res(chips)!RES_0402-75,1.0%,1/16W,CHIP,G2A!!!F300!B!!!!
S!M_BMC_DDR3_MA<0>!U9F5!N3!@baseboard_fab2_lib.baseboard_fab2(sch_1):page151_i1@mstr_memory.k4b1g16(chips)!K4B1G16_BGA1-IC,G38649-001!!!F2056!A0!!!!
S!M_BMC_DDR3_MA<1>!U9F5!P7!@baseboard_fab2_lib.baseboard_fab2(sch_1):page151_i1@mstr_memory.k4b1g16(chips)!K4B1G16_BGA1-IC,G38649-001!!!F2056!A1!!!!
S!M_BMC_DDR3_MA<10>!U9F5!L7!@baseboard_fab2_lib.baseboard_fab2(sch_1):page151_i1@mstr_memory.k4b1g16(chips)!K4B1G16_BGA1-IC,G38649-001!!!F2056!A10_AP!!!!
S!M_BMC_DDR3_MA<11>!U9F5!R7!@baseboard_fab2_lib.baseboard_fab2(sch_1):page151_i1@mstr_memory.k4b1g16(chips)!K4B1G16_BGA1-IC,G38649-001!!!F2056!A11!!!!
S!M_BMC_DDR3_MA<12>!U9F5!N7!@baseboard_fab2_lib.baseboard_fab2(sch_1):page151_i1@mstr_memory.k4b1g16(chips)!K4B1G16_BGA1-IC,G38649-001!!!F2056!\a12/bc_n\!!!!
S!M_BMC_DDR3_MA<2>!U9F5!P3!@baseboard_fab2_lib.baseboard_fab2(sch_1):page151_i1@mstr_memory.k4b1g16(chips)!K4B1G16_BGA1-IC,G38649-001!!!F2056!A2!!!!
S!M_BMC_DDR3_MA<3>!U9F5!N2!@baseboard_fab2_lib.baseboard_fab2(sch_1):page151_i1@mstr_memory.k4b1g16(chips)!K4B1G16_BGA1-IC,G38649-001!!!F2056!A3!!!!
S!M_BMC_DDR3_MA<4>!U9F5!P8!@baseboard_fab2_lib.baseboard_fab2(sch_1):page151_i1@mstr_memory.k4b1g16(chips)!K4B1G16_BGA1-IC,G38649-001!!!F2056!A4!!!!
S!M_BMC_DDR3_MA<5>!U9F5!P2!@baseboard_fab2_lib.baseboard_fab2(sch_1):page151_i1@mstr_memory.k4b1g16(chips)!K4B1G16_BGA1-IC,G38649-001!!!F2056!A5!!!!
S!M_BMC_DDR3_MA<6>!U9F5!R8!@baseboard_fab2_lib.baseboard_fab2(sch_1):page151_i1@mstr_memory.k4b1g16(chips)!K4B1G16_BGA1-IC,G38649-001!!!F2056!A6!!!!
S!M_BMC_DDR3_MA<7>!U9F5!R2!@baseboard_fab2_lib.baseboard_fab2(sch_1):page151_i1@mstr_memory.k4b1g16(chips)!K4B1G16_BGA1-IC,G38649-001!!!F2056!A7!!!!
S!M_BMC_DDR3_MA<8>!U9F5!T8!@baseboard_fab2_lib.baseboard_fab2(sch_1):page151_i1@mstr_memory.k4b1g16(chips)!K4B1G16_BGA1-IC,G38649-001!!!F2056!A8!!!!
S!M_BMC_DDR3_MA<9>!U9F5!R3!@baseboard_fab2_lib.baseboard_fab2(sch_1):page151_i1@mstr_memory.k4b1g16(chips)!K4B1G16_BGA1-IC,G38649-001!!!F2056!A9!!!!
S!M_BMC_DDR3_MBA_0!U9F5!M2!@baseboard_fab2_lib.baseboard_fab2(sch_1):page151_i1@mstr_memory.k4b1g16(chips)!K4B1G16_BGA1-IC,G38649-001!!!F2056!BA0!!!!
S!M_BMC_DDR3_MBA_1!U9F5!N8!@baseboard_fab2_lib.baseboard_fab2(sch_1):page151_i1@mstr_memory.k4b1g16(chips)!K4B1G16_BGA1-IC,G38649-001!!!F2056!BA1!!!!
S!M_BMC_DDR3_MBA_2!U9F5!M3!@baseboard_fab2_lib.baseboard_fab2(sch_1):page151_i1@mstr_memory.k4b1g16(chips)!K4B1G16_BGA1-IC,G38649-001!!!F2056!BA2!!!!
S!M_BMC_DDR3_MCAS_N!U9F5!K3!@baseboard_fab2_lib.baseboard_fab2(sch_1):page151_i1@mstr_memory.k4b1g16(chips)!K4B1G16_BGA1-IC,G38649-001!!!F2056!CAS_N!!!!
S!M_BMC_DDR3_MCK_P!U9F5!J7!@baseboard_fab2_lib.baseboard_fab2(sch_1):page151_i1@mstr_memory.k4b1g16(chips)!K4B1G16_BGA1-IC,G38649-001!!!F2056!CK!!!!
S!M_BMC_DDR3_MCKE!U9F5!K9!@baseboard_fab2_lib.baseboard_fab2(sch_1):page151_i1@mstr_memory.k4b1g16(chips)!K4B1G16_BGA1-IC,G38649-001!!!F2056!CKE!!!!
S!M_BMC_DDR3_MCK_N!U9F5!K7!@baseboard_fab2_lib.baseboard_fab2(sch_1):page151_i1@mstr_memory.k4b1g16(chips)!K4B1G16_BGA1-IC,G38649-001!!!F2056!CK_N!!!!
S!M_BMC_DDR3_MCS_N!U9F5!L2!@baseboard_fab2_lib.baseboard_fab2(sch_1):page151_i1@mstr_memory.k4b1g16(chips)!K4B1G16_BGA1-IC,G38649-001!!!F2056!CS_N!!!!
S!M_BMC_DDR3_MDM_0!U9F5!E7!@baseboard_fab2_lib.baseboard_fab2(sch_1):page151_i1@mstr_memory.k4b1g16(chips)!K4B1G16_BGA1-IC,G38649-001!!!F2056!DML!!!!
S!M_BMC_DDR3_MDM_1!U9F5!D3!@baseboard_fab2_lib.baseboard_fab2(sch_1):page151_i1@mstr_memory.k4b1g16(chips)!K4B1G16_BGA1-IC,G38649-001!!!F2056!DMU!!!!
S!M_BMC_DDR3_DQ<7>!U9F5!E3!@baseboard_fab2_lib.baseboard_fab2(sch_1):page151_i1@mstr_memory.k4b1g16(chips)!K4B1G16_BGA1-IC,G38649-001!!!F2056!DQL0!!!!
S!M_BMC_DDR3_DQ<3>!U9F5!F7!@baseboard_fab2_lib.baseboard_fab2(sch_1):page151_i1@mstr_memory.k4b1g16(chips)!K4B1G16_BGA1-IC,G38649-001!!!F2056!DQL1!!!!
S!M_BMC_DDR3_DQ<4>!U9F5!F2!@baseboard_fab2_lib.baseboard_fab2(sch_1):page151_i1@mstr_memory.k4b1g16(chips)!K4B1G16_BGA1-IC,G38649-001!!!F2056!DQL2!!!!
S!M_BMC_DDR3_DQ<2>!U9F5!F8!@baseboard_fab2_lib.baseboard_fab2(sch_1):page151_i1@mstr_memory.k4b1g16(chips)!K4B1G16_BGA1-IC,G38649-001!!!F2056!DQL3!!!!
S!M_BMC_DDR3_DQ<1>!U9F5!H3!@baseboard_fab2_lib.baseboard_fab2(sch_1):page151_i1@mstr_memory.k4b1g16(chips)!K4B1G16_BGA1-IC,G38649-001!!!F2056!DQL4!!!!
S!M_BMC_DDR3_DQ<6>!U9F5!H8!@baseboard_fab2_lib.baseboard_fab2(sch_1):page151_i1@mstr_memory.k4b1g16(chips)!K4B1G16_BGA1-IC,G38649-001!!!F2056!DQL5!!!!
S!M_BMC_DDR3_DQ<5>!U9F5!G2!@baseboard_fab2_lib.baseboard_fab2(sch_1):page151_i1@mstr_memory.k4b1g16(chips)!K4B1G16_BGA1-IC,G38649-001!!!F2056!DQL6!!!!
S!M_BMC_DDR3_DQ<0>!U9F5!H7!@baseboard_fab2_lib.baseboard_fab2(sch_1):page151_i1@mstr_memory.k4b1g16(chips)!K4B1G16_BGA1-IC,G38649-001!!!F2056!DQL7!!!!
S!M_BMC_DDR3_MDQS_0_DP!U9F5!F3!@baseboard_fab2_lib.baseboard_fab2(sch_1):page151_i1@mstr_memory.k4b1g16(chips)!K4B1G16_BGA1-IC,G38649-001!!!F2056!DQSL!!!!
S!M_BMC_DDR3_MDQS_0_DN!U9F5!G3!@baseboard_fab2_lib.baseboard_fab2(sch_1):page151_i1@mstr_memory.k4b1g16(chips)!K4B1G16_BGA1-IC,G38649-001!!!F2056!DQSL_N!!!!
S!M_BMC_DDR3_MDQS_1_DP!U9F5!C7!@baseboard_fab2_lib.baseboard_fab2(sch_1):page151_i1@mstr_memory.k4b1g16(chips)!K4B1G16_BGA1-IC,G38649-001!!!F2056!DQSU!!!!
S!M_BMC_DDR3_MDQS_1_DN!U9F5!B7!@baseboard_fab2_lib.baseboard_fab2(sch_1):page151_i1@mstr_memory.k4b1g16(chips)!K4B1G16_BGA1-IC,G38649-001!!!F2056!DQSU_N!!!!
S!M_BMC_DDR3_DQ<8>!U9F5!D7!@baseboard_fab2_lib.baseboard_fab2(sch_1):page151_i1@mstr_memory.k4b1g16(chips)!K4B1G16_BGA1-IC,G38649-001!!!F2056!DQU0!!!!
S!M_BMC_DDR3_DQ<11>!U9F5!C3!@baseboard_fab2_lib.baseboard_fab2(sch_1):page151_i1@mstr_memory.k4b1g16(chips)!K4B1G16_BGA1-IC,G38649-001!!!F2056!DQU1!!!!
S!M_BMC_DDR3_DQ<13>!U9F5!C8!@baseboard_fab2_lib.baseboard_fab2(sch_1):page151_i1@mstr_memory.k4b1g16(chips)!K4B1G16_BGA1-IC,G38649-001!!!F2056!DQU2!!!!
S!M_BMC_DDR3_DQ<12>!U9F5!C2!@baseboard_fab2_lib.baseboard_fab2(sch_1):page151_i1@mstr_memory.k4b1g16(chips)!K4B1G16_BGA1-IC,G38649-001!!!F2056!DQU3!!!!
S!M_BMC_DDR3_DQ<10>!U9F5!A7!@baseboard_fab2_lib.baseboard_fab2(sch_1):page151_i1@mstr_memory.k4b1g16(chips)!K4B1G16_BGA1-IC,G38649-001!!!F2056!DQU4!!!!
S!M_BMC_DDR3_DQ<15>!U9F5!A2!@baseboard_fab2_lib.baseboard_fab2(sch_1):page151_i1@mstr_memory.k4b1g16(chips)!K4B1G16_BGA1-IC,G38649-001!!!F2056!DQU5!!!!
S!M_BMC_DDR3_DQ<9>!U9F5!B8!@baseboard_fab2_lib.baseboard_fab2(sch_1):page151_i1@mstr_memory.k4b1g16(chips)!K4B1G16_BGA1-IC,G38649-001!!!F2056!DQU6!!!!
S!M_BMC_DDR3_DQ<14>!U9F5!A3!@baseboard_fab2_lib.baseboard_fab2(sch_1):page151_i1@mstr_memory.k4b1g16(chips)!K4B1G16_BGA1-IC,G38649-001!!!F2056!DQU7!!!!
S!TP_K4B1G16_BMC_NC0!U9F5!J1!@baseboard_fab2_lib.baseboard_fab2(sch_1):page151_i1@mstr_memory.k4b1g16(chips)!K4B1G16_BGA1-IC,G38649-001!!!F2056!NC(0)!!!!
S!TP_K4B1G16_BMC_NC1!U9F5!J9!@baseboard_fab2_lib.baseboard_fab2(sch_1):page151_i1@mstr_memory.k4b1g16(chips)!K4B1G16_BGA1-IC,G38649-001!!!F2056!NC(1)!!!!
S!TP_K4B1G16_BMC_NC2!U9F5!L1!@baseboard_fab2_lib.baseboard_fab2(sch_1):page151_i1@mstr_memory.k4b1g16(chips)!K4B1G16_BGA1-IC,G38649-001!!!F2056!NC(2)!!!!
S!TP_K4B1G16_BMC_NC3!U9F5!L9!@baseboard_fab2_lib.baseboard_fab2(sch_1):page151_i1@mstr_memory.k4b1g16(chips)!K4B1G16_BGA1-IC,G38649-001!!!F2056!NC(3)!!!!
S!TP_K4B1G16_BMC_NC4!U9F5!M7!@baseboard_fab2_lib.baseboard_fab2(sch_1):page151_i1@mstr_memory.k4b1g16(chips)!K4B1G16_BGA1-IC,G38649-001!!!F2056!NC(4)!!!!
S!M_BMC_DDR3_MA<13>!U9F5!T3!@baseboard_fab2_lib.baseboard_fab2(sch_1):page151_i1@mstr_memory.k4b1g16(chips)!K4B1G16_BGA1-IC,G38649-001!!!F2056!NC(5)!!!!
S!M_BMC_DDR3_MA<14>!U9F5!T7!@baseboard_fab2_lib.baseboard_fab2(sch_1):page151_i1@mstr_memory.k4b1g16(chips)!K4B1G16_BGA1-IC,G38649-001!!!F2056!NC(6)!!!!
S!M_BMC_DDR3_MODT!U9F5!K1!@baseboard_fab2_lib.baseboard_fab2(sch_1):page151_i1@mstr_memory.k4b1g16(chips)!K4B1G16_BGA1-IC,G38649-001!!!F2056!ODT!!!!
S!M_BMC_DDR3_MRAS_N!U9F5!J3!@baseboard_fab2_lib.baseboard_fab2(sch_1):page151_i1@mstr_memory.k4b1g16(chips)!K4B1G16_BGA1-IC,G38649-001!!!F2056!RAS_N!!!!
S!RST_BMC_DDR3_N!U9F5!T2!@baseboard_fab2_lib.baseboard_fab2(sch_1):page151_i1@mstr_memory.k4b1g16(chips)!K4B1G16_BGA1-IC,G38649-001!!!F2056!RESET_N!!!!
S!P1V538_BMC_STBY!U9F5!B2!@baseboard_fab2_lib.baseboard_fab2(sch_1):page151_i1@mstr_memory.k4b1g16(chips)!K4B1G16_BGA1-IC,G38649-001!!!F2056!VDD(0)!!!!
S!P1V538_BMC_STBY!U9F5!D9!@baseboard_fab2_lib.baseboard_fab2(sch_1):page151_i1@mstr_memory.k4b1g16(chips)!K4B1G16_BGA1-IC,G38649-001!!!F2056!VDD(1)!!!!
S!P1V538_BMC_STBY!U9F5!G7!@baseboard_fab2_lib.baseboard_fab2(sch_1):page151_i1@mstr_memory.k4b1g16(chips)!K4B1G16_BGA1-IC,G38649-001!!!F2056!VDD(2)!!!!
S!P1V538_BMC_STBY!U9F5!K2!@baseboard_fab2_lib.baseboard_fab2(sch_1):page151_i1@mstr_memory.k4b1g16(chips)!K4B1G16_BGA1-IC,G38649-001!!!F2056!VDD(3)!!!!
S!P1V538_BMC_STBY!U9F5!K8!@baseboard_fab2_lib.baseboard_fab2(sch_1):page151_i1@mstr_memory.k4b1g16(chips)!K4B1G16_BGA1-IC,G38649-001!!!F2056!VDD(4)!!!!
S!P1V538_BMC_STBY!U9F5!N1!@baseboard_fab2_lib.baseboard_fab2(sch_1):page151_i1@mstr_memory.k4b1g16(chips)!K4B1G16_BGA1-IC,G38649-001!!!F2056!VDD(5)!!!!
S!P1V538_BMC_STBY!U9F5!N9!@baseboard_fab2_lib.baseboard_fab2(sch_1):page151_i1@mstr_memory.k4b1g16(chips)!K4B1G16_BGA1-IC,G38649-001!!!F2056!VDD(6)!!!!
S!P1V538_BMC_STBY!U9F5!R1!@baseboard_fab2_lib.baseboard_fab2(sch_1):page151_i1@mstr_memory.k4b1g16(chips)!K4B1G16_BGA1-IC,G38649-001!!!F2056!VDD(7)!!!!
S!P1V538_BMC_STBY!U9F5!R9!@baseboard_fab2_lib.baseboard_fab2(sch_1):page151_i1@mstr_memory.k4b1g16(chips)!K4B1G16_BGA1-IC,G38649-001!!!F2056!VDD(8)!!!!
S!P1V538_BMC_STBY!U9F5!A1!@baseboard_fab2_lib.baseboard_fab2(sch_1):page151_i1@mstr_memory.k4b1g16(chips)!K4B1G16_BGA1-IC,G38649-001!!!F2056!VDDQ(0)!!!!
S!P1V538_BMC_STBY!U9F5!A8!@baseboard_fab2_lib.baseboard_fab2(sch_1):page151_i1@mstr_memory.k4b1g16(chips)!K4B1G16_BGA1-IC,G38649-001!!!F2056!VDDQ(1)!!!!
S!P1V538_BMC_STBY!U9F5!C1!@baseboard_fab2_lib.baseboard_fab2(sch_1):page151_i1@mstr_memory.k4b1g16(chips)!K4B1G16_BGA1-IC,G38649-001!!!F2056!VDDQ(2)!!!!
S!P1V538_BMC_STBY!U9F5!C9!@baseboard_fab2_lib.baseboard_fab2(sch_1):page151_i1@mstr_memory.k4b1g16(chips)!K4B1G16_BGA1-IC,G38649-001!!!F2056!VDDQ(3)!!!!
S!P1V538_BMC_STBY!U9F5!D2!@baseboard_fab2_lib.baseboard_fab2(sch_1):page151_i1@mstr_memory.k4b1g16(chips)!K4B1G16_BGA1-IC,G38649-001!!!F2056!VDDQ(4)!!!!
S!P1V538_BMC_STBY!U9F5!E9!@baseboard_fab2_lib.baseboard_fab2(sch_1):page151_i1@mstr_memory.k4b1g16(chips)!K4B1G16_BGA1-IC,G38649-001!!!F2056!VDDQ(5)!!!!
S!P1V538_BMC_STBY!U9F5!F1!@baseboard_fab2_lib.baseboard_fab2(sch_1):page151_i1@mstr_memory.k4b1g16(chips)!K4B1G16_BGA1-IC,G38649-001!!!F2056!VDDQ(6)!!!!
S!P1V538_BMC_STBY!U9F5!H2!@baseboard_fab2_lib.baseboard_fab2(sch_1):page151_i1@mstr_memory.k4b1g16(chips)!K4B1G16_BGA1-IC,G38649-001!!!F2056!VDDQ(7)!!!!
S!P1V538_BMC_STBY!U9F5!H9!@baseboard_fab2_lib.baseboard_fab2(sch_1):page151_i1@mstr_memory.k4b1g16(chips)!K4B1G16_BGA1-IC,G38649-001!!!F2056!VDDQ(8)!!!!
S!M_BMC_DDR3_MVREF!U9F5!M8!@baseboard_fab2_lib.baseboard_fab2(sch_1):page151_i1@mstr_memory.k4b1g16(chips)!K4B1G16_BGA1-IC,G38649-001!!!F2056!VREFCA!!!!
S!M_BMC_DDR3_MVREF!U9F5!H1!@baseboard_fab2_lib.baseboard_fab2(sch_1):page151_i1@mstr_memory.k4b1g16(chips)!K4B1G16_BGA1-IC,G38649-001!!!F2056!VREFDQ!!!!
S!GND!U9F5!A9!@baseboard_fab2_lib.baseboard_fab2(sch_1):page151_i1@mstr_memory.k4b1g16(chips)!K4B1G16_BGA1-IC,G38649-001!!!F2056!VSS(0)!!!!
S!GND!U9F5!T1!@baseboard_fab2_lib.baseboard_fab2(sch_1):page151_i1@mstr_memory.k4b1g16(chips)!K4B1G16_BGA1-IC,G38649-001!!!F2056!VSS(10)!!!!
S!GND!U9F5!T9!@baseboard_fab2_lib.baseboard_fab2(sch_1):page151_i1@mstr_memory.k4b1g16(chips)!K4B1G16_BGA1-IC,G38649-001!!!F2056!VSS(11)!!!!
S!GND!U9F5!B3!@baseboard_fab2_lib.baseboard_fab2(sch_1):page151_i1@mstr_memory.k4b1g16(chips)!K4B1G16_BGA1-IC,G38649-001!!!F2056!VSS(1)!!!!
S!GND!U9F5!E1!@baseboard_fab2_lib.baseboard_fab2(sch_1):page151_i1@mstr_memory.k4b1g16(chips)!K4B1G16_BGA1-IC,G38649-001!!!F2056!VSS(2)!!!!
S!GND!U9F5!G8!@baseboard_fab2_lib.baseboard_fab2(sch_1):page151_i1@mstr_memory.k4b1g16(chips)!K4B1G16_BGA1-IC,G38649-001!!!F2056!VSS(3)!!!!
S!GND!U9F5!J2!@baseboard_fab2_lib.baseboard_fab2(sch_1):page151_i1@mstr_memory.k4b1g16(chips)!K4B1G16_BGA1-IC,G38649-001!!!F2056!VSS(4)!!!!
S!GND!U9F5!J8!@baseboard_fab2_lib.baseboard_fab2(sch_1):page151_i1@mstr_memory.k4b1g16(chips)!K4B1G16_BGA1-IC,G38649-001!!!F2056!VSS(5)!!!!
S!GND!U9F5!M1!@baseboard_fab2_lib.baseboard_fab2(sch_1):page151_i1@mstr_memory.k4b1g16(chips)!K4B1G16_BGA1-IC,G38649-001!!!F2056!VSS(6)!!!!
S!GND!U9F5!M9!@baseboard_fab2_lib.baseboard_fab2(sch_1):page151_i1@mstr_memory.k4b1g16(chips)!K4B1G16_BGA1-IC,G38649-001!!!F2056!VSS(7)!!!!
S!GND!U9F5!P1!@baseboard_fab2_lib.baseboard_fab2(sch_1):page151_i1@mstr_memory.k4b1g16(chips)!K4B1G16_BGA1-IC,G38649-001!!!F2056!VSS(8)!!!!
S!GND!U9F5!P9!@baseboard_fab2_lib.baseboard_fab2(sch_1):page151_i1@mstr_memory.k4b1g16(chips)!K4B1G16_BGA1-IC,G38649-001!!!F2056!VSS(9)!!!!
S!GND!U9F5!B1!@baseboard_fab2_lib.baseboard_fab2(sch_1):page151_i1@mstr_memory.k4b1g16(chips)!K4B1G16_BGA1-IC,G38649-001!!!F2056!VSSQ(0)!!!!
S!GND!U9F5!B9!@baseboard_fab2_lib.baseboard_fab2(sch_1):page151_i1@mstr_memory.k4b1g16(chips)!K4B1G16_BGA1-IC,G38649-001!!!F2056!VSSQ(1)!!!!
S!GND!U9F5!D1!@baseboard_fab2_lib.baseboard_fab2(sch_1):page151_i1@mstr_memory.k4b1g16(chips)!K4B1G16_BGA1-IC,G38649-001!!!F2056!VSSQ(2)!!!!
S!GND!U9F5!D8!@baseboard_fab2_lib.baseboard_fab2(sch_1):page151_i1@mstr_memory.k4b1g16(chips)!K4B1G16_BGA1-IC,G38649-001!!!F2056!VSSQ(3)!!!!
S!GND!U9F5!E2!@baseboard_fab2_lib.baseboard_fab2(sch_1):page151_i1@mstr_memory.k4b1g16(chips)!K4B1G16_BGA1-IC,G38649-001!!!F2056!VSSQ(4)!!!!
S!GND!U9F5!E8!@baseboard_fab2_lib.baseboard_fab2(sch_1):page151_i1@mstr_memory.k4b1g16(chips)!K4B1G16_BGA1-IC,G38649-001!!!F2056!VSSQ(5)!!!!
S!GND!U9F5!F9!@baseboard_fab2_lib.baseboard_fab2(sch_1):page151_i1@mstr_memory.k4b1g16(chips)!K4B1G16_BGA1-IC,G38649-001!!!F2056!VSSQ(6)!!!!
S!GND!U9F5!G1!@baseboard_fab2_lib.baseboard_fab2(sch_1):page151_i1@mstr_memory.k4b1g16(chips)!K4B1G16_BGA1-IC,G38649-001!!!F2056!VSSQ(7)!!!!
S!GND!U9F5!G9!@baseboard_fab2_lib.baseboard_fab2(sch_1):page151_i1@mstr_memory.k4b1g16(chips)!K4B1G16_BGA1-IC,G38649-001!!!F2056!VSSQ(8)!!!!
S!M_BMC_DDR3_MWE_N!U9F5!L3!@baseboard_fab2_lib.baseboard_fab2(sch_1):page151_i1@mstr_memory.k4b1g16(chips)!K4B1G16_BGA1-IC,G38649-001!!!F2056!WE_N!!!!
S!A_M_BMC_ZQ!U9F5!L8!@baseboard_fab2_lib.baseboard_fab2(sch_1):page151_i1@mstr_memory.k4b1g16(chips)!K4B1G16_BGA1-IC,G38649-001!!!F2056!ZQ!!!!
S!SPA_MID_DBG_RX!R9F25!1!@baseboard_fab2_lib.baseboard_fab2(sch_1):page158_i86@mstr_discrete.res(chips)!RES_0402-100.0,1%,1/16W,CHIP,GA!!!F1173!A!!!!
S!UART_MUX_IN_R!R9F25!2!@baseboard_fab2_lib.baseboard_fab2(sch_1):page158_i86@mstr_discrete.res(chips)!RES_0402-100.0,1%,1/16W,CHIP,GA!!!F1173!B!!!!
S!GND!R9B7!1!@baseboard_fab2_lib.baseboard_fab2(sch_1):page186_i222@mstr_discrete.res(chips)!RES_0402-100.0,1%,1/16W,CHIP,GA!!!F1174!A!!!!
S!FM_MEZZA_PRSNT1_N!R9B7!2!@baseboard_fab2_lib.baseboard_fab2(sch_1):page186_i222@mstr_discrete.res(chips)!RES_0402-100.0,1%,1/16W,CHIP,GA!!!F1174!B!!!!
S!FM_MEZZ_PRSNTB1_N!R2R8!1!@baseboard_fab2_lib.baseboard_fab2(sch_1):page187_i18@mstr_discrete.res(chips)!RES_0402-100.0,1%,1/16W,CHIP,GA!!!F1208!A!!!!
S!GND!R2R8!2!@baseboard_fab2_lib.baseboard_fab2(sch_1):page187_i18@mstr_discrete.res(chips)!RES_0402-100.0,1%,1/16W,CHIP,GA!!!F1208!B!!!!
S!PWRGD_P12V_MAIN_R!R8D42!1!@baseboard_fab2_lib.baseboard_fab2(sch_1):page196_i106@mstr_discrete.res(chips)!RES_0402-100.0,1%,1/16W,CHIP,GA!!!F1168!A!!!!
S!PWRGD_P12V_MAIN!R8D42!2!@baseboard_fab2_lib.baseboard_fab2(sch_1):page196_i106@mstr_discrete.res(chips)!RES_0402-100.0,1%,1/16W,CHIP,GA!!!F1168!B!!!!
S!P1V05_PCH_STBY!R1L39!1!@baseboard_fab2_lib.baseboard_fab2(sch_1):page112_i76@mstr_discrete.res(chips)!RES_0402-100.0,1%,1/16W,CHIP,GA!!!F1213!A!!!!
S!XDP_PRDY_N!R1L39!2!@baseboard_fab2_lib.baseboard_fab2(sch_1):page112_i76@mstr_discrete.res(chips)!RES_0402-100.0,1%,1/16W,CHIP,GA!!!F1213!B!!!!
S!PVCCIO_CPU0!R1M3!1!@baseboard_fab2_lib.baseboard_fab2(sch_1):page112_i51@mstr_discrete.res(chips)!RES_0402-100.0,1%,1/16W,CHIP,GA!!!F1211!A!!!!
S!XDP_CPU_PRDY_N!R1M3!2!@baseboard_fab2_lib.baseboard_fab2(sch_1):page112_i51@mstr_discrete.res(chips)!RES_0402-100.0,1%,1/16W,CHIP,GA!!!F1211!B!!!!
S!FAN_TACH1!R9T7!1!@baseboard_fab2_lib.baseboard_fab2(sch_1):page161_i134@mstr_discrete.res(chips)!RES_0402-100.0,1%,1/16W,CHIP,GA!!!F1170!A!!!!
S!FAN_TACH1_CPU1_D2!R9T7!2!@baseboard_fab2_lib.baseboard_fab2(sch_1):page161_i134@mstr_discrete.res(chips)!RES_0402-100.0,1%,1/16W,CHIP,GA!!!F1170!B!!!!
S!FAN_TACH3!R1B23!1!@baseboard_fab2_lib.baseboard_fab2(sch_1):page161_i124@mstr_discrete.res(chips)!RES_0402-100.0,1%,1/16W,CHIP,GA!!!F1219!A!!!!
S!FAN_TACH3_CPU1_D2!R1B23!2!@baseboard_fab2_lib.baseboard_fab2(sch_1):page161_i124@mstr_discrete.res(chips)!RES_0402-100.0,1%,1/16W,CHIP,GA!!!F1219!B!!!!
S!VSENSE_PVNN_PCH_STBY_AVSP!R7A13!1!@baseboard_fab2_lib.baseboard_fab2(sch_1):page236_i90@mstr_discrete.res(chips)!RES_0402-100.0,1%,1/16W,CHIP,GA!!!F1182!A!!!!
S!PVNN_PCH_STBY!R7A13!2!@baseboard_fab2_lib.baseboard_fab2(sch_1):page236_i90@mstr_discrete.res(chips)!RES_0402-100.0,1%,1/16W,CHIP,GA!!!F1182!B!!!!
S!PVCCIO_CPU0!R1M4!1!@baseboard_fab2_lib.baseboard_fab2(sch_1):page112_i54@mstr_discrete.res(chips)!RES_0402-100.0,1%,1/16W,CHIP,GA!!!F1210!A!!!!
S!XDP_CPU_PREQ_N!R1M4!2!@baseboard_fab2_lib.baseboard_fab2(sch_1):page112_i54@mstr_discrete.res(chips)!RES_0402-100.0,1%,1/16W,CHIP,GA!!!F1210!B!!!!
S!PVCCIO_CPU0!R3U2!1!@baseboard_fab2_lib.baseboard_fab2(sch_1):page215_i295@mstr_discrete.res(chips)!RES_0402-100.0,1%,1/16W,CHIP,GA!!!F1197!A!!!!
S!SVID_DIO1_CPU0_R!R3U2!2!@baseboard_fab2_lib.baseboard_fab2(sch_1):page215_i295@mstr_discrete.res(chips)!RES_0402-100.0,1%,1/16W,CHIP,GA!!!F1197!B!!!!
S!PVCCIO_CPU0!R4P12!1!@baseboard_fab2_lib.baseboard_fab2(sch_1):page112_i57@mstr_discrete.res(chips)!RES_0402-100.0,1%,1/16W,CHIP,GA!!!F1190!A!!!!
S!XDP_CPU_MBP0_N!R4P12!2!@baseboard_fab2_lib.baseboard_fab2(sch_1):page112_i57@mstr_discrete.res(chips)!RES_0402-100.0,1%,1/16W,CHIP,GA!!!F1190!B!!!!
S!PVCCIO_CPU0!R4P15!1!@baseboard_fab2_lib.baseboard_fab2(sch_1):page112_i53@mstr_discrete.res(chips)!RES_0402-100.0,1%,1/16W,CHIP,GA!!!F1189!A!!!!
S!XDP_CPU_MBP1_N!R4P15!2!@baseboard_fab2_lib.baseboard_fab2(sch_1):page112_i53@mstr_discrete.res(chips)!RES_0402-100.0,1%,1/16W,CHIP,GA!!!F1189!B!!!!
S!PVCCIO_CPU1!R9U3!1!@baseboard_fab2_lib.baseboard_fab2(sch_1):page223_i8@mstr_discrete.res(chips)!RES_0402-100.0,1%,1/16W,CHIP,GA!!!F1169!A!!!!
S!SVID_DIO1_CPU1_R!R9U3!2!@baseboard_fab2_lib.baseboard_fab2(sch_1):page223_i8@mstr_discrete.res(chips)!RES_0402-100.0,1%,1/16W,CHIP,GA!!!F1169!B!!!!
S!PWRGD_P5V_R!R2P20!1!@baseboard_fab2_lib.baseboard_fab2(sch_1):page196_i65@mstr_discrete.res(chips)!RES_0402-100.0,1%,1/16W,CHIP,GA!!!F1176!A!!!!
S!PWRGD_P5V!R2P20!2!@baseboard_fab2_lib.baseboard_fab2(sch_1):page196_i65@mstr_discrete.res(chips)!RES_0402-100.0,1%,1/16W,CHIP,GA!!!F1176!B!!!!
S!P1V05_PCH_STBY!R1L41!1!@baseboard_fab2_lib.baseboard_fab2(sch_1):page112_i77@mstr_discrete.res(chips)!RES_0402-100.0,1%,1/16W,CHIP,GA!!!F1212!A!!!!
S!XDP_PREQ_N!R1L41!2!@baseboard_fab2_lib.baseboard_fab2(sch_1):page112_i77@mstr_discrete.res(chips)!RES_0402-100.0,1%,1/16W,CHIP,GA!!!F1212!B!!!!
S!RST_SYSTEM_BTN_BUF_N!R9A9!1!@baseboard_fab2_lib.baseboard_fab2(sch_1):page175_i35@mstr_discrete.res(chips)!RES_0402-100.0,1%,1/16W,CHIP,GA!!!F1175!A!!!!
S!RST_SYSTEM_BTN_N!R9A9!2!@baseboard_fab2_lib.baseboard_fab2(sch_1):page175_i35@mstr_discrete.res(chips)!RES_0402-100.0,1%,1/16W,CHIP,GA!!!F1175!B!!!!
S!P0V7_GTL2014_2!R1U37!1!@baseboard_fab2_lib.baseboard_fab2(sch_1):page152_i26@mstr_discrete.res(chips)!RES_0402-100.0,1%,1/16W,CHIP,GA!!!F1209!A!!!!
S!GND!R1U37!2!@baseboard_fab2_lib.baseboard_fab2(sch_1):page152_i26@mstr_discrete.res(chips)!RES_0402-100.0,1%,1/16W,CHIP,GA!!!F1209!B!!!!
S!FAN_TACH0!R1F2!1!@baseboard_fab2_lib.baseboard_fab2(sch_1):page161_i43@mstr_discrete.res(chips)!RES_0402-100.0,1%,1/16W,CHIP,GA!!!F1214!A!!!!
S!FAN_TACH0_CPU0_D2!R1F2!2!@baseboard_fab2_lib.baseboard_fab2(sch_1):page161_i43@mstr_discrete.res(chips)!RES_0402-100.0,1%,1/16W,CHIP,GA!!!F1214!B!!!!
S!FAN_TACH2!R1B22!1!@baseboard_fab2_lib.baseboard_fab2(sch_1):page161_i67@mstr_discrete.res(chips)!RES_0402-100.0,1%,1/16W,CHIP,GA!!!F1220!A!!!!
S!FAN_TACH2_CPU1_D2!R1B22!2!@baseboard_fab2_lib.baseboard_fab2(sch_1):page161_i67@mstr_discrete.res(chips)!RES_0402-100.0,1%,1/16W,CHIP,GA!!!F1220!B!!!!
S!VSENSE_PVCCIO_CPU1_AVSN!R3D28!1!@baseboard_fab2_lib.baseboard_fab2(sch_1):page214_i101@mstr_discrete.res(chips)!RES_0402-100.0,1%,1/16W,CHIP,GA!!!F1204!A!!!!
S!GND!R3D28!2!@baseboard_fab2_lib.baseboard_fab2(sch_1):page214_i101@mstr_discrete.res(chips)!RES_0402-100.0,1%,1/16W,CHIP,GA!!!F1204!B!!!!
S!VSENSE_PVCCIO_CPU0_AVSP!R3N21!1!@baseboard_fab2_lib.baseboard_fab2(sch_1):page212_i74@mstr_discrete.res(chips)!RES_0402-100.0,1%,1/16W,CHIP,GA!!!F1199!A!!!!
S!PVCCIO_CPU0!R3N21!2!@baseboard_fab2_lib.baseboard_fab2(sch_1):page212_i74@mstr_discrete.res(chips)!RES_0402-100.0,1%,1/16W,CHIP,GA!!!F1199!B!!!!
S!VSENSE_PVCCIO_CPU1_AVSP!R3E1!1!@baseboard_fab2_lib.baseboard_fab2(sch_1):page214_i105@mstr_discrete.res(chips)!RES_0402-100.0,1%,1/16W,CHIP,GA!!!F1203!A!!!!
S!PVCCIO_CPU1!R3E1!2!@baseboard_fab2_lib.baseboard_fab2(sch_1):page214_i105@mstr_discrete.res(chips)!RES_0402-100.0,1%,1/16W,CHIP,GA!!!F1203!B!!!!
S!VSENSE_PVCCIO_CPU0_AVSN!R3N20!1!@baseboard_fab2_lib.baseboard_fab2(sch_1):page212_i68@mstr_discrete.res(chips)!RES_0402-100.0,1%,1/16W,CHIP,GA!!!F1200!A!!!!
S!GND!R3N20!2!@baseboard_fab2_lib.baseboard_fab2(sch_1):page212_i68@mstr_discrete.res(chips)!RES_0402-100.0,1%,1/16W,CHIP,GA!!!F1200!B!!!!
S!VSENSE_PVCCIN_CPU1_P!R1E4!1!@baseboard_fab2_lib.baseboard_fab2(sch_1):page209_i15@mstr_discrete.res(chips)!RES_0402-100.0,1%,1/16W,CHIP,GA!!!F1216!A!!!!
S!PVCCIN_CPU1!R1E4!2!@baseboard_fab2_lib.baseboard_fab2(sch_1):page209_i15@mstr_discrete.res(chips)!RES_0402-100.0,1%,1/16W,CHIP,GA!!!F1216!B!!!!
S!VSENSE_PVCCIN_CPU1_N!R1E8!1!@baseboard_fab2_lib.baseboard_fab2(sch_1):page209_i9@mstr_discrete.res(chips)!RES_0402-100.0,1%,1/16W,CHIP,GA!!!F1215!A!!!!
S!GND!R1E8!2!@baseboard_fab2_lib.baseboard_fab2(sch_1):page209_i9@mstr_discrete.res(chips)!RES_0402-100.0,1%,1/16W,CHIP,GA!!!F1215!B!!!!
S!P0V7_GTL2104_5_VREF!R2T39!1!@baseboard_fab2_lib.baseboard_fab2(sch_1):page93_i98@mstr_discrete.res(chips)!RES_0402-100.0,1%,1/16W,CHIP,GA!!!F1207!A!!!!
S!GND!R2T39!2!@baseboard_fab2_lib.baseboard_fab2(sch_1):page93_i98@mstr_discrete.res(chips)!RES_0402-100.0,1%,1/16W,CHIP,GA!!!F1207!B!!!!
S!A_PCIEUP_RCOMP_P!R3M12!1!@baseboard_fab2_lib.baseboard_fab2(sch_1):page116_i181@mstr_discrete.res(chips)!RES_0402-100.0,1%,1/16W,CHIP,GA!!!F1201!A!!!!
S!A_PCIEUP_RCOMP_N!R3M12!2!@baseboard_fab2_lib.baseboard_fab2(sch_1):page116_i181@mstr_discrete.res(chips)!RES_0402-100.0,1%,1/16W,CHIP,GA!!!F1201!B!!!!
S!GND!R8D10!1!@baseboard_fab2_lib.baseboard_fab2(sch_1):page121_i35@mstr_discrete.res(chips)!RES_0402-100.0,1%,1/16W,CHIP,GA!!!F1177!A!!!!
S!A_1P8_3P3_RCOMP!R8D10!2!@baseboard_fab2_lib.baseboard_fab2(sch_1):page121_i35@mstr_discrete.res(chips)!RES_0402-100.0,1%,1/16W,CHIP,GA!!!F1177!B!!!!
S!A_RCOMP_3P3!R8C21!1!@baseboard_fab2_lib.baseboard_fab2(sch_1):page120_i148@mstr_discrete.res(chips)!RES_0402-100.0,1%,1/16W,CHIP,GA!!!F1178!A!!!!
S!GND!R8C21!2!@baseboard_fab2_lib.baseboard_fab2(sch_1):page120_i148@mstr_discrete.res(chips)!RES_0402-100.0,1%,1/16W,CHIP,GA!!!F1178!B!!!!
S!PVCCIO_CPU0!R7P30!1!@baseboard_fab2_lib.baseboard_fab2(sch_1):page112_i50@mstr_discrete.res(chips)!RES_0402-100.0,1%,1/16W,CHIP,GA!!!F1179!A!!!!
S!XDP_CPU_MBP0_N!R7P30!2!@baseboard_fab2_lib.baseboard_fab2(sch_1):page112_i50@mstr_discrete.res(chips)!RES_0402-100.0,1%,1/16W,CHIP,GA!!!F1179!B!!!!
S!PVCCIO_CPU0!R6P46!1!@baseboard_fab2_lib.baseboard_fab2(sch_1):page112_i49@mstr_discrete.res(chips)!RES_0402-100.0,1%,1/16W,CHIP,GA!!!F1185!A!!!!
S!XDP_CPU_MBP1_N!R6P46!2!@baseboard_fab2_lib.baseboard_fab2(sch_1):page112_i49@mstr_discrete.res(chips)!RES_0402-100.0,1%,1/16W,CHIP,GA!!!F1185!B!!!!
S!PVCCIO_CPU0!R6T8!1!@baseboard_fab2_lib.baseboard_fab2(sch_1):page112_i121@mstr_discrete.res(chips)!RES_0402-100.0,1%,1/16W,CHIP,GA!!!F1184!A!!!!
S!XDP_CPU_OBSFN_B0_MBP6_N!R6T8!2!@baseboard_fab2_lib.baseboard_fab2(sch_1):page112_i121@mstr_discrete.res(chips)!RES_0402-100.0,1%,1/16W,CHIP,GA!!!F1184!B!!!!
S!PVCCIO_CPU0!R6T9!1!@baseboard_fab2_lib.baseboard_fab2(sch_1):page112_i120@mstr_discrete.res(chips)!RES_0402-100.0,1%,1/16W,CHIP,GA!!!F1183!A!!!!
S!XDP_CPU_OBSFN_B1_MBP7_N!R6T9!2!@baseboard_fab2_lib.baseboard_fab2(sch_1):page112_i120@mstr_discrete.res(chips)!RES_0402-100.0,1%,1/16W,CHIP,GA!!!F1183!B!!!!
S!VSENSE_PVSA_CPU0_P!R4C5!1!@baseboard_fab2_lib.baseboard_fab2(sch_1):page205_i24@mstr_discrete.res(chips)!RES_0402-100.0,1%,1/16W,CHIP,GA!!!F1195!A!!!!
S!PVSA_CPU0!R4C5!2!@baseboard_fab2_lib.baseboard_fab2(sch_1):page205_i24@mstr_discrete.res(chips)!RES_0402-100.0,1%,1/16W,CHIP,GA!!!F1195!B!!!!
S!VSENSE_PVCCIN_CPU0_P!R4E14!1!@baseboard_fab2_lib.baseboard_fab2(sch_1):page204_i60@mstr_discrete.res(chips)!RES_0402-100.0,1%,1/16W,CHIP,GA!!!F1193!A!!!!
S!PVCCIN_CPU0!R4E14!2!@baseboard_fab2_lib.baseboard_fab2(sch_1):page204_i60@mstr_discrete.res(chips)!RES_0402-100.0,1%,1/16W,CHIP,GA!!!F1193!B!!!!
S!VSENSE_PVCCIN_CPU0_N!R4E18!1!@baseboard_fab2_lib.baseboard_fab2(sch_1):page204_i64@mstr_discrete.res(chips)!RES_0402-100.0,1%,1/16W,CHIP,GA!!!F1192!A!!!!
S!GND!R4E18!2!@baseboard_fab2_lib.baseboard_fab2(sch_1):page204_i64@mstr_discrete.res(chips)!RES_0402-100.0,1%,1/16W,CHIP,GA!!!F1192!B!!!!
S!PVCCIO_CPU0!R6B2!1!@baseboard_fab2_lib.baseboard_fab2(sch_1):page21_i159@mstr_discrete.res(chips)!RES_0402-100.0,1%,1/16W,CHIP,GA!!!F1188!A!!!!
S!SVID_DIO1_CPU0_R!R6B2!2!@baseboard_fab2_lib.baseboard_fab2(sch_1):page21_i159@mstr_discrete.res(chips)!RES_0402-100.0,1%,1/16W,CHIP,GA!!!F1188!B!!!!
S!SVID_DIO0_CPU0_R!R6N2!1!@baseboard_fab2_lib.baseboard_fab2(sch_1):page21_i163@mstr_discrete.res(chips)!RES_0402-100.0,1%,1/16W,CHIP,GA!!!F1186!A!!!!
S!PVCCIO_CPU0!R6N2!2!@baseboard_fab2_lib.baseboard_fab2(sch_1):page21_i163@mstr_discrete.res(chips)!RES_0402-100.0,1%,1/16W,CHIP,GA!!!F1186!B!!!!
S!PVCCIO_CPU1!R9N2!1!@baseboard_fab2_lib.baseboard_fab2(sch_1):page55_i7@mstr_discrete.res(chips)!RES_0402-100.0,1%,1/16W,CHIP,GA!!!F1172!A!!!!
S!SVID_DIO1_CPU1_R!R9N2!2!@baseboard_fab2_lib.baseboard_fab2(sch_1):page55_i7@mstr_discrete.res(chips)!RES_0402-100.0,1%,1/16W,CHIP,GA!!!F1172!B!!!!
S!SVID_DIO0_CPU1_R!R3B4!1!@baseboard_fab2_lib.baseboard_fab2(sch_1):page55_i21@mstr_discrete.res(chips)!RES_0402-100.0,1%,1/16W,CHIP,GA!!!F1206!A!!!!
S!PVCCIO_CPU1!R3B4!2!@baseboard_fab2_lib.baseboard_fab2(sch_1):page55_i21@mstr_discrete.res(chips)!RES_0402-100.0,1%,1/16W,CHIP,GA!!!F1206!B!!!!
S!PVCCIO_CPU0!R4E10!1!@baseboard_fab2_lib.baseboard_fab2(sch_1):page201_i20@mstr_discrete.res(chips)!RES_0402-100.0,1%,1/16W,CHIP,GA!!!F1194!A!!!!
S!SVID_DIO0_CPU0_R!R4E10!2!@baseboard_fab2_lib.baseboard_fab2(sch_1):page201_i20@mstr_discrete.res(chips)!RES_0402-100.0,1%,1/16W,CHIP,GA!!!F1194!B!!!!
S!PVCCIO_CPU1!R9P1!1!@baseboard_fab2_lib.baseboard_fab2(sch_1):page206_i4@mstr_discrete.res(chips)!RES_0402-100.0,1%,1/16W,CHIP,GA!!!F1171!A!!!!
S!SVID_DIO0_CPU1_R!R9P1!2!@baseboard_fab2_lib.baseboard_fab2(sch_1):page206_i4@mstr_discrete.res(chips)!RES_0402-100.0,1%,1/16W,CHIP,GA!!!F1171!B!!!!
S!VSENSE_PVSA_CPU1_P!R1C12!1!@baseboard_fab2_lib.baseboard_fab2(sch_1):page210_i29@mstr_discrete.res(chips)!RES_0402-100.0,1%,1/16W,CHIP,GA!!!F1217!A!!!!
S!PVSA_CPU1!R1C12!2!@baseboard_fab2_lib.baseboard_fab2(sch_1):page210_i29@mstr_discrete.res(chips)!RES_0402-100.0,1%,1/16W,CHIP,GA!!!F1217!B!!!!
S!VSENSE_PVSA_CPU1_N!R1C4!1!@baseboard_fab2_lib.baseboard_fab2(sch_1):page210_i33@mstr_discrete.res(chips)!RES_0402-100.0,1%,1/16W,CHIP,GA!!!F1218!A!!!!
S!GND!R1C4!2!@baseboard_fab2_lib.baseboard_fab2(sch_1):page210_i33@mstr_discrete.res(chips)!RES_0402-100.0,1%,1/16W,CHIP,GA!!!F1218!B!!!!
S!VSENSE_PVSA_CPU0_N!R4C1!1!@baseboard_fab2_lib.baseboard_fab2(sch_1):page205_i29@mstr_discrete.res(chips)!RES_0402-100.0,1%,1/16W,CHIP,GA!!!F1196!A!!!!
S!GND!R4C1!2!@baseboard_fab2_lib.baseboard_fab2(sch_1):page205_i29@mstr_discrete.res(chips)!RES_0402-100.0,1%,1/16W,CHIP,GA!!!F1196!B!!!!
S!A_PCIE_RCOMP_P!R3M11!1!@baseboard_fab2_lib.baseboard_fab2(sch_1):page116_i108@mstr_discrete.res(chips)!RES_0402-100.0,1%,1/16W,CHIP,GA!!!F1202!A!!!!
S!A_PCIE_RCOMP_N!R3M11!2!@baseboard_fab2_lib.baseboard_fab2(sch_1):page116_i108@mstr_discrete.res(chips)!RES_0402-100.0,1%,1/16W,CHIP,GA!!!F1202!B!!!!
S!P0V7_GTL2104_VREF_1!R3P49!1!@baseboard_fab2_lib.baseboard_fab2(sch_1):page92_i38@mstr_discrete.res(chips)!RES_0402-100.0,1%,1/16W,CHIP,GA!!!F1198!A!!!!
S!GND!R3P49!2!@baseboard_fab2_lib.baseboard_fab2(sch_1):page92_i38@mstr_discrete.res(chips)!RES_0402-100.0,1%,1/16W,CHIP,GA!!!F1198!B!!!!
S!P0V7_GTL2104_VREF_0!R7D32!1!@baseboard_fab2_lib.baseboard_fab2(sch_1):page92_i48@mstr_discrete.res(chips)!RES_0402-100.0,1%,1/16W,CHIP,GA!!!F1181!A!!!!
S!GND!R7D32!2!@baseboard_fab2_lib.baseboard_fab2(sch_1):page92_i48@mstr_discrete.res(chips)!RES_0402-100.0,1%,1/16W,CHIP,GA!!!F1181!B!!!!
S!A_CPU0_ABC_RCOMP2!R4P11!1!@baseboard_fab2_lib.baseboard_fab2(sch_1):page21_i182@mstr_discrete.res(chips)!RES_0402-100.0,1%,1/16W,CHIP,GA!!!F1191!A!!!!
S!GND!R4P11!2!@baseboard_fab2_lib.baseboard_fab2(sch_1):page21_i182@mstr_discrete.res(chips)!RES_0402-100.0,1%,1/16W,CHIP,GA!!!F1191!B!!!!
S!A_CPU0_DEF_RCOMP2!R6D1!1!@baseboard_fab2_lib.baseboard_fab2(sch_1):page21_i179@mstr_discrete.res(chips)!RES_0402-100.0,1%,1/16W,CHIP,GA!!!F1187!A!!!!
S!GND!R6D1!2!@baseboard_fab2_lib.baseboard_fab2(sch_1):page21_i179@mstr_discrete.res(chips)!RES_0402-100.0,1%,1/16W,CHIP,GA!!!F1187!B!!!!
S!A_CPU1_GHJ_RCOMP2!R7P19!1!@baseboard_fab2_lib.baseboard_fab2(sch_1):page55_i115@mstr_discrete.res(chips)!RES_0402-100.0,1%,1/16W,CHIP,GA!!!F1180!A!!!!
S!GND!R7P19!2!@baseboard_fab2_lib.baseboard_fab2(sch_1):page55_i115@mstr_discrete.res(chips)!RES_0402-100.0,1%,1/16W,CHIP,GA!!!F1180!B!!!!
S!A_CPU1_KLM_RCOMP2!R3D3!1!@baseboard_fab2_lib.baseboard_fab2(sch_1):page55_i118@mstr_discrete.res(chips)!RES_0402-100.0,1%,1/16W,CHIP,GA!!!F1205!A!!!!
S!GND!R3D3!2!@baseboard_fab2_lib.baseboard_fab2(sch_1):page55_i118@mstr_discrete.res(chips)!RES_0402-100.0,1%,1/16W,CHIP,GA!!!F1205!B!!!!
S!GND!R4P7!1!@baseboard_fab2_lib.baseboard_fab2(sch_1):page90_i72@mstr_discrete.res(chips)!RES_0402-49.9,1%,1/16W,CHIP,G2A!!!F446!A!!!!
S!PD_CPU0_KSFC_DIS!R4P7!2!@baseboard_fab2_lib.baseboard_fab2(sch_1):page90_i72@mstr_discrete.res(chips)!RES_0402-49.9,1%,1/16W,CHIP,G2A!!!F446!B!!!!
S!GND!R7P15!1!@baseboard_fab2_lib.baseboard_fab2(sch_1):page90_i74@mstr_discrete.res(chips)!RES_0402-49.9,1%,1/16W,CHIP,G2A!!!F420!A!!!!
S!PD_CPU1_KSFC_DIS!R7P15!2!@baseboard_fab2_lib.baseboard_fab2(sch_1):page90_i74@mstr_discrete.res(chips)!RES_0402-49.9,1%,1/16W,CHIP,G2A!!!F420!B!!!!
S!JTAG_MCP_CPU0_TDI_R!R4R6!1!@baseboard_fab2_lib.baseboard_fab2(sch_1):page113_i134@mstr_discrete.res(chips)!RES_0402-49.9,1%,1/16W,CHIP,G2A!!!F445!A!!!!
S!JTAG_MCP_CPU0_TDI!R4R6!2!@baseboard_fab2_lib.baseboard_fab2(sch_1):page113_i134@mstr_discrete.res(chips)!RES_0402-49.9,1%,1/16W,CHIP,G2A!!!F445!B!!!!
S!JTAG_MCP_TCK!R9B10!1!@baseboard_fab2_lib.baseboard_fab2(sch_1):page113_i180@mstr_discrete.res(chips)!RES_0402-49.9,1%,1/16W,CHIP,G2A!!!F428!A!!!!
S!JTAG_MCP_TCK_R!R9B10!2!@baseboard_fab2_lib.baseboard_fab2(sch_1):page113_i180@mstr_discrete.res(chips)!RES_0402-49.9,1%,1/16W,CHIP,G2A!!!F428!B!!!!
S!JTAG_MCP_TMS_R1!R1M22!1!@baseboard_fab2_lib.baseboard_fab2(sch_1):page113_i195@mstr_discrete.res(chips)!RES_0402-49.9,1%,1/16W,CHIP,G2A!!!F427!A!!!!
S!JTAG_MCP_TMS!R1M22!2!@baseboard_fab2_lib.baseboard_fab2(sch_1):page113_i195@mstr_discrete.res(chips)!RES_0402-49.9,1%,1/16W,CHIP,G2A!!!F427!B!!!!
S!JTAG_MCP_CPU1_TDI_R!R6M8!1!@baseboard_fab2_lib.baseboard_fab2(sch_1):page113_i188@mstr_discrete.res(chips)!RES_0402-49.9,1%,1/16W,CHIP,G2A!!!F426!A!!!!
S!JTAG_MCP_CPU1_TDI!R6M8!2!@baseboard_fab2_lib.baseboard_fab2(sch_1):page113_i188@mstr_discrete.res(chips)!RES_0402-49.9,1%,1/16W,CHIP,G2A!!!F426!B!!!!
S!RST_BMC_SYSRST_BTN_OUT_B_R_N!R2T18!1!@baseboard_fab2_lib.baseboard_fab2(sch_1):page156_i288@mstr_discrete.res(chips)!RES_0402-49.9,1%,1/16W,CHIP,G2A!!!F461!A!!!!
S!RST_BMC_SYSRST_BTN_OUT_B_N!R2T18!2!@baseboard_fab2_lib.baseboard_fab2(sch_1):page156_i288@mstr_discrete.res(chips)!RES_0402-49.9,1%,1/16W,CHIP,G2A!!!F461!B!!!!
S!PWRGD_P3V3_R1!R1L16!1!@baseboard_fab2_lib.baseboard_fab2(sch_1):page196_i68@mstr_discrete.res(chips)!RES_0402-49.9,1%,1/16W,CHIP,G2A!!!F465!A!!!!
S!PWRGD_P3V3!R1L16!2!@baseboard_fab2_lib.baseboard_fab2(sch_1):page196_i68@mstr_discrete.res(chips)!RES_0402-49.9,1%,1/16W,CHIP,G2A!!!F465!B!!!!
S!PD_CPU0_TEST14!R5P2!1!@baseboard_fab2_lib.baseboard_fab2(sch_1):page90_i79@mstr_discrete.res(chips)!RES_0402-49.9,1%,1/16W,CHIP,G2A!!!F442!A!!!!
S!GND!R5P2!2!@baseboard_fab2_lib.baseboard_fab2(sch_1):page90_i79@mstr_discrete.res(chips)!RES_0402-49.9,1%,1/16W,CHIP,G2A!!!F442!B!!!!
S!PD_CPU0_TEST13!R5P3!1!@baseboard_fab2_lib.baseboard_fab2(sch_1):page90_i80@mstr_discrete.res(chips)!RES_0402-49.9,1%,1/16W,CHIP,G2A!!!F441!A!!!!
S!GND!R5P3!2!@baseboard_fab2_lib.baseboard_fab2(sch_1):page90_i80@mstr_discrete.res(chips)!RES_0402-49.9,1%,1/16W,CHIP,G2A!!!F441!B!!!!
S!PD_CPU0_TEST12!R6D5!1!@baseboard_fab2_lib.baseboard_fab2(sch_1):page90_i81@mstr_discrete.res(chips)!RES_0402-49.9,1%,1/16W,CHIP,G2A!!!F436!A!!!!
S!GND!R6D5!2!@baseboard_fab2_lib.baseboard_fab2(sch_1):page90_i81@mstr_discrete.res(chips)!RES_0402-49.9,1%,1/16W,CHIP,G2A!!!F436!B!!!!
S!PD_CPU1_TEST14!R8P1!1!@baseboard_fab2_lib.baseboard_fab2(sch_1):page90_i85@mstr_discrete.res(chips)!RES_0402-49.9,1%,1/16W,CHIP,G2A!!!F414!A!!!!
S!GND!R8P1!2!@baseboard_fab2_lib.baseboard_fab2(sch_1):page90_i85@mstr_discrete.res(chips)!RES_0402-49.9,1%,1/16W,CHIP,G2A!!!F414!B!!!!
S!PD_CPU1_TEST13!R8P2!1!@baseboard_fab2_lib.baseboard_fab2(sch_1):page90_i86@mstr_discrete.res(chips)!RES_0402-49.9,1%,1/16W,CHIP,G2A!!!F413!A!!!!
S!GND!R8P2!2!@baseboard_fab2_lib.baseboard_fab2(sch_1):page90_i86@mstr_discrete.res(chips)!RES_0402-49.9,1%,1/16W,CHIP,G2A!!!F413!B!!!!
S!PD_CPU1_TEST12!R3D9!1!@baseboard_fab2_lib.baseboard_fab2(sch_1):page90_i88@mstr_discrete.res(chips)!RES_0402-49.9,1%,1/16W,CHIP,G2A!!!F457!A!!!!
S!GND!R3D9!2!@baseboard_fab2_lib.baseboard_fab2(sch_1):page90_i88@mstr_discrete.res(chips)!RES_0402-49.9,1%,1/16W,CHIP,G2A!!!F457!B!!!!
S!PD_CPU0_RSVD_TEST_2!R5P4!1!@baseboard_fab2_lib.baseboard_fab2(sch_1):page22_i190@mstr_discrete.res(chips)!RES_0402-49.9,1%,1/16W,CHIP,G2A!!!F440!A!!!!
S!GND!R5P4!2!@baseboard_fab2_lib.baseboard_fab2(sch_1):page22_i190@mstr_discrete.res(chips)!RES_0402-49.9,1%,1/16W,CHIP,G2A!!!F440!B!!!!
S!PD_CPU0_RSVD_TEST_1!R5R1!1!@baseboard_fab2_lib.baseboard_fab2(sch_1):page22_i188@mstr_discrete.res(chips)!RES_0402-49.9,1%,1/16W,CHIP,G2A!!!F439!A!!!!
S!GND!R5R1!2!@baseboard_fab2_lib.baseboard_fab2(sch_1):page22_i188@mstr_discrete.res(chips)!RES_0402-49.9,1%,1/16W,CHIP,G2A!!!F439!B!!!!
S!PD_CPU1_RSVD_TEST_2!R8P3!1!@baseboard_fab2_lib.baseboard_fab2(sch_1):page56_i173@mstr_discrete.res(chips)!RES_0402-49.9,1%,1/16W,CHIP,G2A!!!F412!A!!!!
S!GND!R8P3!2!@baseboard_fab2_lib.baseboard_fab2(sch_1):page56_i173@mstr_discrete.res(chips)!RES_0402-49.9,1%,1/16W,CHIP,G2A!!!F412!B!!!!
S!PD_CPU1_RSVD_TEST_1!R8R1!1!@baseboard_fab2_lib.baseboard_fab2(sch_1):page56_i174@mstr_discrete.res(chips)!RES_0402-49.9,1%,1/16W,CHIP,G2A!!!F411!A!!!!
S!GND!R8R1!2!@baseboard_fab2_lib.baseboard_fab2(sch_1):page56_i174@mstr_discrete.res(chips)!RES_0402-49.9,1%,1/16W,CHIP,G2A!!!F411!B!!!!
S!SGPIO_PCH_SATA_LOAD!R8D20!1!@baseboard_fab2_lib.baseboard_fab2(sch_1):page178_i1@mstr_discrete.res(chips)!RES_0402-49.9,1%,1/16W,CHIP,G2A!!!F415!A!!!!
S!SGPIO_PCH_SATA_LOAD_R!R8D20!2!@baseboard_fab2_lib.baseboard_fab2(sch_1):page178_i1@mstr_discrete.res(chips)!RES_0402-49.9,1%,1/16W,CHIP,G2A!!!F415!B!!!!
S!SGPIO_PCH_SATA_DOUT0!R8D19!1!@baseboard_fab2_lib.baseboard_fab2(sch_1):page178_i8@mstr_discrete.res(chips)!RES_0402-49.9,1%,1/16W,CHIP,G2A!!!F416!A!!!!
S!SGPIO_PCH_SATA_DOUT0_R!R8D19!2!@baseboard_fab2_lib.baseboard_fab2(sch_1):page178_i8@mstr_discrete.res(chips)!RES_0402-49.9,1%,1/16W,CHIP,G2A!!!F416!B!!!!
S!SGPIO_PCH_SATA_CLOCK!R2N31!1!@baseboard_fab2_lib.baseboard_fab2(sch_1):page178_i11@mstr_discrete.res(chips)!RES_0402-49.9,1%,1/16W,CHIP,G2A!!!F452!A!!!!
S!SGPIO_PCH_SATA_CLOCK_R!R2N31!2!@baseboard_fab2_lib.baseboard_fab2(sch_1):page178_i11@mstr_discrete.res(chips)!RES_0402-49.9,1%,1/16W,CHIP,G2A!!!F452!B!!!!
S!SGPIO_PCH_SSATA_LOAD!R2N19!1!@baseboard_fab2_lib.baseboard_fab2(sch_1):page178_i22@mstr_discrete.res(chips)!RES_0402-49.9,1%,1/16W,CHIP,G2A!!!F463!A!!!!
S!SGPIO_PCH_SSATA_LOAD_R!R2N19!2!@baseboard_fab2_lib.baseboard_fab2(sch_1):page178_i22@mstr_discrete.res(chips)!RES_0402-49.9,1%,1/16W,CHIP,G2A!!!F463!B!!!!
S!SGPIO_PCH_SSATA_DOUT0!R8B29!1!@baseboard_fab2_lib.baseboard_fab2(sch_1):page178_i21@mstr_discrete.res(chips)!RES_0402-49.9,1%,1/16W,CHIP,G2A!!!F417!A!!!!
S!SGPIO_PCH_SSATA_DOUT0_R!R8B29!2!@baseboard_fab2_lib.baseboard_fab2(sch_1):page178_i21@mstr_discrete.res(chips)!RES_0402-49.9,1%,1/16W,CHIP,G2A!!!F417!B!!!!
S!SGPIO_PCH_SSATA_CLOCK!R2N22!1!@baseboard_fab2_lib.baseboard_fab2(sch_1):page178_i23@mstr_discrete.res(chips)!RES_0402-49.9,1%,1/16W,CHIP,G2A!!!F462!A!!!!
S!SGPIO_PCH_SSATA_CLOCK_R!R2N22!2!@baseboard_fab2_lib.baseboard_fab2(sch_1):page178_i23@mstr_discrete.res(chips)!RES_0402-49.9,1%,1/16W,CHIP,G2A!!!F462!B!!!!
S!PVCCIO_CPU0!R3L13!1!@baseboard_fab2_lib.baseboard_fab2(sch_1):page218_i47@mstr_discrete.res(chips)!RES_0402-49.9,1%,1/16W,CHIP,G2A!!!F453!A!!!!
S!SVID_CLK1_CPU0_R!R3L13!2!@baseboard_fab2_lib.baseboard_fab2(sch_1):page218_i47@mstr_discrete.res(chips)!RES_0402-49.9,1%,1/16W,CHIP,G2A!!!F453!B!!!!
S!PVCCIO_CPU1!R9M6!1!@baseboard_fab2_lib.baseboard_fab2(sch_1):page226_i50@mstr_discrete.res(chips)!RES_0402-49.9,1%,1/16W,CHIP,G2A!!!F408!A!!!!
S!SVID_CLK1_CPU1_R!R9M6!2!@baseboard_fab2_lib.baseboard_fab2(sch_1):page226_i50@mstr_discrete.res(chips)!RES_0402-49.9,1%,1/16W,CHIP,G2A!!!F408!B!!!!
S!PVCCIO_CPU0!R4E9!1!@baseboard_fab2_lib.baseboard_fab2(sch_1):page201_i52@mstr_discrete.res(chips)!RES_0402-49.9,1%,1/16W,CHIP,G2A!!!F450!A!!!!
S!SVID_CLK0_CPU0_R!R4E9!2!@baseboard_fab2_lib.baseboard_fab2(sch_1):page201_i52@mstr_discrete.res(chips)!RES_0402-49.9,1%,1/16W,CHIP,G2A!!!F450!B!!!!
S!PVCCIO_CPU1!R9P2!1!@baseboard_fab2_lib.baseboard_fab2(sch_1):page206_i53@mstr_discrete.res(chips)!RES_0402-49.9,1%,1/16W,CHIP,G2A!!!F406!A!!!!
S!SVID_CLK0_CPU1_R!R9P2!2!@baseboard_fab2_lib.baseboard_fab2(sch_1):page206_i53@mstr_discrete.res(chips)!RES_0402-49.9,1%,1/16W,CHIP,G2A!!!F406!B!!!!
S!H_PM_SYNC_GTL_R1!R4P18!1!@baseboard_fab2_lib.baseboard_fab2(sch_1):page21_i244@mstr_discrete.res(chips)!RES_0402-49.9,1%,1/16W,CHIP,G2A!!!F444!A!!!!
S!H_PM_SYNC_GTL!R4P18!2!@baseboard_fab2_lib.baseboard_fab2(sch_1):page21_i244@mstr_discrete.res(chips)!RES_0402-49.9,1%,1/16W,CHIP,G2A!!!F444!B!!!!
S!H_PM_SYNC_GTL_R2!R7P25!1!@baseboard_fab2_lib.baseboard_fab2(sch_1):page55_i170@mstr_discrete.res(chips)!RES_0402-49.9,1%,1/16W,CHIP,G2A!!!F419!A!!!!
S!H_PM_SYNC_GTL!R7P25!2!@baseboard_fab2_lib.baseboard_fab2(sch_1):page55_i170@mstr_discrete.res(chips)!RES_0402-49.9,1%,1/16W,CHIP,G2A!!!F419!B!!!!
S!H_PMSYNC_CLK_24M_CPU0!R4P19!1!@baseboard_fab2_lib.baseboard_fab2(sch_1):page21_i219@mstr_discrete.res(chips)!RES_0402-49.9,1%,1/16W,CHIP,G2A!!!F443!A!!!!
S!H_PMSYNC_CLK_24M!R4P19!2!@baseboard_fab2_lib.baseboard_fab2(sch_1):page21_i219@mstr_discrete.res(chips)!RES_0402-49.9,1%,1/16W,CHIP,G2A!!!F443!B!!!!
S!H_PMSYNC_CLK_24M_CPU1!R7P26!1!@baseboard_fab2_lib.baseboard_fab2(sch_1):page55_i156@mstr_discrete.res(chips)!RES_0402-49.9,1%,1/16W,CHIP,G2A!!!F418!A!!!!
S!H_PMSYNC_CLK_24M!R7P26!2!@baseboard_fab2_lib.baseboard_fab2(sch_1):page55_i156@mstr_discrete.res(chips)!RES_0402-49.9,1%,1/16W,CHIP,G2A!!!F418!B!!!!
S!A_CPU1_MCP01_RBIAS!R3D4!1!@baseboard_fab2_lib.baseboard_fab2(sch_1):page55_i155@mstr_discrete.res(chips)!RES_0402-49.9,1%,1/16W,CHIP,G2A!!!F458!A!!!!
S!GND!R3D4!2!@baseboard_fab2_lib.baseboard_fab2(sch_1):page55_i155@mstr_discrete.res(chips)!RES_0402-49.9,1%,1/16W,CHIP,G2A!!!F458!B!!!!
S!PVCCIO_CPU0!R1U43!1!@baseboard_fab2_lib.baseboard_fab2(sch_1):page152_i25@mstr_discrete.res(chips)!RES_0402-49.9,1%,1/16W,CHIP,G2A!!!F464!A!!!!
S!P0V7_GTL2014_2!R1U43!2!@baseboard_fab2_lib.baseboard_fab2(sch_1):page152_i25@mstr_discrete.res(chips)!RES_0402-49.9,1%,1/16W,CHIP,G2A!!!F464!B!!!!
S!IRQ_DIMM_SAVE_N!R6F4!1!@baseboard_fab2_lib.baseboard_fab2(sch_1):page89_i3@mstr_discrete.res(chips)!RES_0402-49.9,1%,1/16W,CHIP,G2A!!!F430!A!!!!
S!FM_ADR_COMPLETE_ABC_N!R6F4!2!@baseboard_fab2_lib.baseboard_fab2(sch_1):page89_i3@mstr_discrete.res(chips)!RES_0402-49.9,1%,1/16W,CHIP,G2A!!!F430!B!!!!
S!IRQ_DIMM_SAVE_N!R6F1!1!@baseboard_fab2_lib.baseboard_fab2(sch_1):page89_i4@mstr_discrete.res(chips)!RES_0402-49.9,1%,1/16W,CHIP,G2A!!!F432!A!!!!
S!FM_ADR_COMPLETE_DEF_N!R6F1!2!@baseboard_fab2_lib.baseboard_fab2(sch_1):page89_i4@mstr_discrete.res(chips)!RES_0402-49.9,1%,1/16W,CHIP,G2A!!!F432!B!!!!
S!IRQ_DIMM_SAVE_N!R6F5!1!@baseboard_fab2_lib.baseboard_fab2(sch_1):page89_i5@mstr_discrete.res(chips)!RES_0402-49.9,1%,1/16W,CHIP,G2A!!!F429!A!!!!
S!FM_ADR_COMPLETE_GHJ_N!R6F5!2!@baseboard_fab2_lib.baseboard_fab2(sch_1):page89_i5@mstr_discrete.res(chips)!RES_0402-49.9,1%,1/16W,CHIP,G2A!!!F429!B!!!!
S!IRQ_DIMM_SAVE_N!R6F2!1!@baseboard_fab2_lib.baseboard_fab2(sch_1):page89_i6@mstr_discrete.res(chips)!RES_0402-49.9,1%,1/16W,CHIP,G2A!!!F431!A!!!!
S!FM_ADR_COMPLETE_KLM_N!R6F2!2!@baseboard_fab2_lib.baseboard_fab2(sch_1):page89_i6@mstr_discrete.res(chips)!RES_0402-49.9,1%,1/16W,CHIP,G2A!!!F431!B!!!!
S!ISENSE_TMP421_1_E!R9B4!1!@baseboard_fab2_lib.baseboard_fab2(sch_1):page167_i6@mstr_discrete.res(chips)!RES_0402-49.9,1%,1/16W,CHIP,G2A!!!F410!A!!!!
S!ISENSE_TMP421_1_DXP!R9B4!2!@baseboard_fab2_lib.baseboard_fab2(sch_1):page167_i6@mstr_discrete.res(chips)!RES_0402-49.9,1%,1/16W,CHIP,G2A!!!F410!B!!!!
S!ISENSE_TMP421_1_BC!R9B5!1!@baseboard_fab2_lib.baseboard_fab2(sch_1):page167_i5@mstr_discrete.res(chips)!RES_0402-49.9,1%,1/16W,CHIP,G2A!!!F409!A!!!!
S!ISENSE_TMP421_1_DXN!R9B5!2!@baseboard_fab2_lib.baseboard_fab2(sch_1):page167_i5@mstr_discrete.res(chips)!RES_0402-49.9,1%,1/16W,CHIP,G2A!!!F409!B!!!!
S!ISENSE_TMP421_2_E!R9R5!1!@baseboard_fab2_lib.baseboard_fab2(sch_1):page167_i25@mstr_discrete.res(chips)!RES_0402-49.9,1%,1/16W,CHIP,G2A!!!F405!A!!!!
S!ISENSE_TMP421_2_DXP!R9R5!2!@baseboard_fab2_lib.baseboard_fab2(sch_1):page167_i25@mstr_discrete.res(chips)!RES_0402-49.9,1%,1/16W,CHIP,G2A!!!F405!B!!!!
S!ISENSE_TMP421_2_BC!R9R6!1!@baseboard_fab2_lib.baseboard_fab2(sch_1):page167_i26@mstr_discrete.res(chips)!RES_0402-49.9,1%,1/16W,CHIP,G2A!!!F404!A!!!!
S!ISENSE_TMP421_2_DXN!R9R6!2!@baseboard_fab2_lib.baseboard_fab2(sch_1):page167_i26@mstr_discrete.res(chips)!RES_0402-49.9,1%,1/16W,CHIP,G2A!!!F404!B!!!!
S!PVCCIO_CPU0!R2T36!1!@baseboard_fab2_lib.baseboard_fab2(sch_1):page93_i97@mstr_discrete.res(chips)!RES_0402-49.9,1%,1/16W,CHIP,G2A!!!F460!A!!!!
S!P0V7_GTL2104_5_VREF!R2T36!2!@baseboard_fab2_lib.baseboard_fab2(sch_1):page93_i97@mstr_discrete.res(chips)!RES_0402-49.9,1%,1/16W,CHIP,G2A!!!F460!B!!!!
S!PVCCIO_CPU1!R3D20!1!@baseboard_fab2_lib.baseboard_fab2(sch_1):page96_i25@mstr_discrete.res(chips)!RES_0402-49.9,1%,1/16W,CHIP,G2A!!!F454!A!!!!
S!RST_CPU1_G_N!R3D20!2!@baseboard_fab2_lib.baseboard_fab2(sch_1):page96_i25@mstr_discrete.res(chips)!RES_0402-49.9,1%,1/16W,CHIP,G2A!!!F454!B!!!!
S!PVCCIO_CPU1!R3D15!1!@baseboard_fab2_lib.baseboard_fab2(sch_1):page96_i26@mstr_discrete.res(chips)!RES_0402-49.9,1%,1/16W,CHIP,G2A!!!F456!A!!!!
S!PWRGD_CPU1_G!R3D15!2!@baseboard_fab2_lib.baseboard_fab2(sch_1):page96_i26@mstr_discrete.res(chips)!RES_0402-49.9,1%,1/16W,CHIP,G2A!!!F456!B!!!!
S!PVCCIO_CPU0!R6D12!1!@baseboard_fab2_lib.baseboard_fab2(sch_1):page96_i2@mstr_discrete.res(chips)!RES_0402-49.9,1%,1/16W,CHIP,G2A!!!F433!A!!!!
S!RST_CPU0_G_N!R6D12!2!@baseboard_fab2_lib.baseboard_fab2(sch_1):page96_i2@mstr_discrete.res(chips)!RES_0402-49.9,1%,1/16W,CHIP,G2A!!!F433!B!!!!
S!PVCCIO_CPU0!R6D8!1!@baseboard_fab2_lib.baseboard_fab2(sch_1):page96_i3@mstr_discrete.res(chips)!RES_0402-49.9,1%,1/16W,CHIP,G2A!!!F435!A!!!!
S!PWRGD_CPU0_G!R6D8!2!@baseboard_fab2_lib.baseboard_fab2(sch_1):page96_i3@mstr_discrete.res(chips)!RES_0402-49.9,1%,1/16W,CHIP,G2A!!!F435!B!!!!
S!PVCCIO_CPU0!R6B1!1!@baseboard_fab2_lib.baseboard_fab2(sch_1):page21_i161@mstr_discrete.res(chips)!RES_0402-49.9,1%,1/16W,CHIP,G2A!!!F438!A!!!!
S!SVID_ALERT1_CPU0_R_N!R6B1!2!@baseboard_fab2_lib.baseboard_fab2(sch_1):page21_i161@mstr_discrete.res(chips)!RES_0402-49.9,1%,1/16W,CHIP,G2A!!!F438!B!!!!
S!SVID_ALERT0_CPU0_R_N!R6N1!1!@baseboard_fab2_lib.baseboard_fab2(sch_1):page21_i164@mstr_discrete.res(chips)!RES_0402-49.9,1%,1/16W,CHIP,G2A!!!F425!A!!!!
S!PVCCIO_CPU0!R6N1!2!@baseboard_fab2_lib.baseboard_fab2(sch_1):page21_i164@mstr_discrete.res(chips)!RES_0402-49.9,1%,1/16W,CHIP,G2A!!!F425!B!!!!
S!PVCCIO_CPU1!R9N1!1!@baseboard_fab2_lib.baseboard_fab2(sch_1):page55_i4@mstr_discrete.res(chips)!RES_0402-49.9,1%,1/16W,CHIP,G2A!!!F407!A!!!!
S!SVID_ALERT1_CPU1_R_N!R9N1!2!@baseboard_fab2_lib.baseboard_fab2(sch_1):page55_i4@mstr_discrete.res(chips)!RES_0402-49.9,1%,1/16W,CHIP,G2A!!!F407!B!!!!
S!SVID_ALERT0_CPU1_R_N!R3B2!1!@baseboard_fab2_lib.baseboard_fab2(sch_1):page55_i19@mstr_discrete.res(chips)!RES_0402-49.9,1%,1/16W,CHIP,G2A!!!F459!A!!!!
S!PVCCIO_CPU1!R3B2!2!@baseboard_fab2_lib.baseboard_fab2(sch_1):page55_i19@mstr_discrete.res(chips)!RES_0402-49.9,1%,1/16W,CHIP,G2A!!!F459!B!!!!
S!PVCCIO_CPU0!R3P45!1!@baseboard_fab2_lib.baseboard_fab2(sch_1):page92_i39@mstr_discrete.res(chips)!RES_0402-49.9,1%,1/16W,CHIP,G2A!!!F451!A!!!!
S!P0V7_GTL2104_VREF_1!R3P45!2!@baseboard_fab2_lib.baseboard_fab2(sch_1):page92_i39@mstr_discrete.res(chips)!RES_0402-49.9,1%,1/16W,CHIP,G2A!!!F451!B!!!!
S!PVCCIO_CPU0!R7D33!1!@baseboard_fab2_lib.baseboard_fab2(sch_1):page92_i51@mstr_discrete.res(chips)!RES_0402-49.9,1%,1/16W,CHIP,G2A!!!F424!A!!!!
S!P0V7_GTL2104_VREF_0!R7D33!2!@baseboard_fab2_lib.baseboard_fab2(sch_1):page92_i51@mstr_discrete.res(chips)!RES_0402-49.9,1%,1/16W,CHIP,G2A!!!F424!B!!!!
S!A_CPU0_MCP01_RBIAS!R6D2!1!@baseboard_fab2_lib.baseboard_fab2(sch_1):page21_i204@mstr_discrete.res(chips)!RES_0402-49.9,1%,1/16W,CHIP,G2A!!!F437!A!!!!
S!GND!R6D2!2!@baseboard_fab2_lib.baseboard_fab2(sch_1):page21_i204@mstr_discrete.res(chips)!RES_0402-49.9,1%,1/16W,CHIP,G2A!!!F437!B!!!!
S!A_CPU0_PE3_RBIAS!R4P2!1!@baseboard_fab2_lib.baseboard_fab2(sch_1):page21_i188@mstr_discrete.res(chips)!RES_0402-49.9,1%,1/16W,CHIP,G2A!!!F449!A!!!!
S!GND!R4P2!2!@baseboard_fab2_lib.baseboard_fab2(sch_1):page21_i188@mstr_discrete.res(chips)!RES_0402-49.9,1%,1/16W,CHIP,G2A!!!F449!B!!!!
S!A_CPU0_PE012_RBIAS!R4P3!1!@baseboard_fab2_lib.baseboard_fab2(sch_1):page21_i186@mstr_discrete.res(chips)!RES_0402-49.9,1%,1/16W,CHIP,G2A!!!F448!A!!!!
S!GND!R4P3!2!@baseboard_fab2_lib.baseboard_fab2(sch_1):page21_i186@mstr_discrete.res(chips)!RES_0402-49.9,1%,1/16W,CHIP,G2A!!!F448!B!!!!
S!A_CPU0_UPI01_RBIAS!R6D11!1!@baseboard_fab2_lib.baseboard_fab2(sch_1):page21_i184@mstr_discrete.res(chips)!RES_0402-49.9,1%,1/16W,CHIP,G2A!!!F434!A!!!!
S!GND!R6D11!2!@baseboard_fab2_lib.baseboard_fab2(sch_1):page21_i184@mstr_discrete.res(chips)!RES_0402-49.9,1%,1/16W,CHIP,G2A!!!F434!B!!!!
S!A_CPU0_UPI2_RBIAS!R4P4!1!@baseboard_fab2_lib.baseboard_fab2(sch_1):page21_i189@mstr_discrete.res(chips)!RES_0402-49.9,1%,1/16W,CHIP,G2A!!!F447!A!!!!
S!GND!R4P4!2!@baseboard_fab2_lib.baseboard_fab2(sch_1):page21_i189@mstr_discrete.res(chips)!RES_0402-49.9,1%,1/16W,CHIP,G2A!!!F447!B!!!!
S!A_CPU1_PE3_RBIAS!R7P8!1!@baseboard_fab2_lib.baseboard_fab2(sch_1):page55_i123@mstr_discrete.res(chips)!RES_0402-49.9,1%,1/16W,CHIP,G2A!!!F423!A!!!!
S!GND!R7P8!2!@baseboard_fab2_lib.baseboard_fab2(sch_1):page55_i123@mstr_discrete.res(chips)!RES_0402-49.9,1%,1/16W,CHIP,G2A!!!F423!B!!!!
S!A_CPU1_PE012_RBIAS!R7P10!1!@baseboard_fab2_lib.baseboard_fab2(sch_1):page55_i124@mstr_discrete.res(chips)!RES_0402-49.9,1%,1/16W,CHIP,G2A!!!F422!A!!!!
S!GND!R7P10!2!@baseboard_fab2_lib.baseboard_fab2(sch_1):page55_i124@mstr_discrete.res(chips)!RES_0402-49.9,1%,1/16W,CHIP,G2A!!!F422!B!!!!
S!A_CPU1_UPI01_RBIAS!R3D19!1!@baseboard_fab2_lib.baseboard_fab2(sch_1):page55_i125@mstr_discrete.res(chips)!RES_0402-49.9,1%,1/16W,CHIP,G2A!!!F455!A!!!!
S!GND!R3D19!2!@baseboard_fab2_lib.baseboard_fab2(sch_1):page55_i125@mstr_discrete.res(chips)!RES_0402-49.9,1%,1/16W,CHIP,G2A!!!F455!B!!!!
S!A_CPU1_UPI2_RBIAS!R7P11!1!@baseboard_fab2_lib.baseboard_fab2(sch_1):page55_i126@mstr_discrete.res(chips)!RES_0402-49.9,1%,1/16W,CHIP,G2A!!!F421!A!!!!
S!GND!R7P11!2!@baseboard_fab2_lib.baseboard_fab2(sch_1):page55_i126@mstr_discrete.res(chips)!RES_0402-49.9,1%,1/16W,CHIP,G2A!!!F421!B!!!!
S!FM_P12V_HSC_ADR1!EU1D2!7!@baseboard_fab2_lib.baseboard_fab2(sch_1):page199_i10@mstr_controller.adm1278(chips)!ADM1278_SM-IC,G99251-001!!!F4197!ADR1!!!!
S!FM_P12V_HSC_ADR2!EU1D2!8!@baseboard_fab2_lib.baseboard_fab2(sch_1):page199_i10@mstr_controller.adm1278(chips)!ADM1278_SM-IC,G99251-001!!!F4197!ADR2!!!!
S!A_HSC_CSOUT!EU1D2!19!@baseboard_fab2_lib.baseboard_fab2(sch_1):page199_i10@mstr_controller.adm1278(chips)!ADM1278_SM-IC,G99251-001!!!F4197!CSOUT!!!!
S!FM_P12V_HOTSWAP0_EN!EU1D2!12!@baseboard_fab2_lib.baseboard_fab2(sch_1):page199_i10@mstr_controller.adm1278(chips)!ADM1278_SM-IC,G99251-001!!!F4197!ENABLE!!!!
S!AGND_HSC!EU1D2!33!@baseboard_fab2_lib.baseboard_fab2(sch_1):page199_i10@mstr_controller.adm1278(chips)!ADM1278_SM-IC,G99251-001!!!F4197!EP!!!!
S!IRQ_HSC_FAULT_R_N!EU1D2!6!@baseboard_fab2_lib.baseboard_fab2(sch_1):page199_i10@mstr_controller.adm1278(chips)!ADM1278_SM-IC,G99251-001!!!F4197!FAULT_N!!!!
S!A_HSC_GATE!EU1D2!24!@baseboard_fab2_lib.baseboard_fab2(sch_1):page199_i10@mstr_controller.adm1278(chips)!ADM1278_SM-IC,G99251-001!!!F4197!GATE!!!!
S!AGND_HSC!EU1D2!22!@baseboard_fab2_lib.baseboard_fab2(sch_1):page199_i10@mstr_controller.adm1278(chips)!ADM1278_SM-IC,G99251-001!!!F4197!GND!!!!
S!IRQ_SML1_PMBUS_ALERT_R_N!EU1D2!13!@baseboard_fab2_lib.baseboard_fab2(sch_1):page199_i10@mstr_controller.adm1278(chips)!ADM1278_SM-IC,G99251-001!!!F4197!GPO1_ALERT1_N_CONV!!!!
S!TP_HSC_ALERT2_N!EU1D2!14!@baseboard_fab2_lib.baseboard_fab2(sch_1):page199_i10@mstr_controller.adm1278(chips)!ADM1278_SM-IC,G99251-001!!!F4197!GPO2_ALERT2_N!!!!
S!A_HSC_HSN!EU1D2!27!@baseboard_fab2_lib.baseboard_fab2(sch_1):page199_i10@mstr_controller.adm1278(chips)!ADM1278_SM-IC,G99251-001!!!F4197!HSN!!!!
S!A_HSC_HSP!EU1D2!28!@baseboard_fab2_lib.baseboard_fab2(sch_1):page199_i10@mstr_controller.adm1278(chips)!ADM1278_SM-IC,G99251-001!!!F4197!HSP!!!!
S!A_HSC_ISET!EU1D2!3!@baseboard_fab2_lib.baseboard_fab2(sch_1):page199_i10@mstr_controller.adm1278(chips)!ADM1278_SM-IC,G99251-001!!!F4197!ISET!!!!
S!A_HSC_ISTART!EU1D2!4!@baseboard_fab2_lib.baseboard_fab2(sch_1):page199_i10@mstr_controller.adm1278(chips)!ADM1278_SM-IC,G99251-001!!!F4197!ISTART!!!!
S!TP_HSC_MCLK!EU1D2!10!@baseboard_fab2_lib.baseboard_fab2(sch_1):page199_i10@mstr_controller.adm1278(chips)!ADM1278_SM-IC,G99251-001!!!F4197!MCLK!!!!
S!TP_HSC_MDAT!EU1D2!11!@baseboard_fab2_lib.baseboard_fab2(sch_1):page199_i10@mstr_controller.adm1278(chips)!ADM1278_SM-IC,G99251-001!!!F4197!MDAT!!!!
S!A_HSC_MON!EU1D2!26!@baseboard_fab2_lib.baseboard_fab2(sch_1):page199_i10@mstr_controller.adm1278(chips)!ADM1278_SM-IC,G99251-001!!!F4197!MON!!!!
S!A_HSC_MOP!EU1D2!29!@baseboard_fab2_lib.baseboard_fab2(sch_1):page199_i10@mstr_controller.adm1278(chips)!ADM1278_SM-IC,G99251-001!!!F4197!MOP!!!!
S!A_HSC_OV!EU1D2!32!@baseboard_fab2_lib.baseboard_fab2(sch_1):page199_i10@mstr_controller.adm1278(chips)!ADM1278_SM-IC,G99251-001!!!F4197!OV!!!!
S!GND!EU1D2!23!@baseboard_fab2_lib.baseboard_fab2(sch_1):page199_i10@mstr_controller.adm1278(chips)!ADM1278_SM-IC,G99251-001!!!F4197!PGND!!!!
S!A_HSC_PSET!EU1D2!1!@baseboard_fab2_lib.baseboard_fab2(sch_1):page199_i10@mstr_controller.adm1278(chips)!ADM1278_SM-IC,G99251-001!!!F4197!PSET!!!!
S!A_HSC_PWGIN!EU1D2!21!@baseboard_fab2_lib.baseboard_fab2(sch_1):page199_i10@mstr_controller.adm1278(chips)!ADM1278_SM-IC,G99251-001!!!F4197!PWGIN!!!!
S!PWRGD_P12V_R!EU1D2!18!@baseboard_fab2_lib.baseboard_fab2(sch_1):page199_i10@mstr_controller.adm1278(chips)!ADM1278_SM-IC,G99251-001!!!F4197!PWRGD!!!!
S!PD_HSC_RETRY_N!EU1D2!17!@baseboard_fab2_lib.baseboard_fab2(sch_1):page199_i10@mstr_controller.adm1278(chips)!ADM1278_SM-IC,G99251-001!!!F4197!RETRY_N!!!!
S!SMB_3V3SB_HSC_SCL_R!EU1D2!16!@baseboard_fab2_lib.baseboard_fab2(sch_1):page199_i10@mstr_controller.adm1278(chips)!ADM1278_SM-IC,G99251-001!!!F4197!SCL!!!!
S!SMB_3V3SB_HSC_SDA_R!EU1D2!15!@baseboard_fab2_lib.baseboard_fab2(sch_1):page199_i10@mstr_controller.adm1278(chips)!ADM1278_SM-IC,G99251-001!!!F4197!SDA!!!!
S!TP_HSC_SPISSN!EU1D2!9!@baseboard_fab2_lib.baseboard_fab2(sch_1):page199_i10@mstr_controller.adm1278(chips)!ADM1278_SM-IC,G99251-001!!!F4197!SPISS_N!!!!
S!A_HSC_TEMP!EU1D2!25!@baseboard_fab2_lib.baseboard_fab2(sch_1):page199_i10@mstr_controller.adm1278(chips)!ADM1278_SM-IC,G99251-001!!!F4197!TEMP!!!!
S!A_HSC_TIMER!EU1D2!5!@baseboard_fab2_lib.baseboard_fab2(sch_1):page199_i10@mstr_controller.adm1278(chips)!ADM1278_SM-IC,G99251-001!!!F4197!TIMER!!!!
S!A_HSC_UV!EU1D2!31!@baseboard_fab2_lib.baseboard_fab2(sch_1):page199_i10@mstr_controller.adm1278(chips)!ADM1278_SM-IC,G99251-001!!!F4197!UV!!!!
S!A_HSC_VCAP!EU1D2!2!@baseboard_fab2_lib.baseboard_fab2(sch_1):page199_i10@mstr_controller.adm1278(chips)!ADM1278_SM-IC,G99251-001!!!F4197!VCAP!!!!
S!P12V_HSC_VCC!EU1D2!30!@baseboard_fab2_lib.baseboard_fab2(sch_1):page199_i10@mstr_controller.adm1278(chips)!ADM1278_SM-IC,G99251-001!!!F4197!VCC!!!!
S!A_HSC_VOUT!EU1D2!20!@baseboard_fab2_lib.baseboard_fab2(sch_1):page199_i10@mstr_controller.adm1278(chips)!ADM1278_SM-IC,G99251-001!!!F4197!VOUT!!!!
S!M_BMC_DDR3_MA<0>!U9F4!AB14!@baseboard_fab2_lib.baseboard_fab2(sch_1):page143_i281@mstr_controller.ast1250(chips)!AST1250_BGA-IC,G85138-002!!!F4192!MA(0)!!!!
S!M_BMC_DDR3_MA<10>!U9F4!Y15!@baseboard_fab2_lib.baseboard_fab2(sch_1):page143_i281@mstr_controller.ast1250(chips)!AST1250_BGA-IC,G85138-002!!!F4192!MA(10)!!!!
S!M_BMC_DDR3_MA<11>!U9F4!AA16!@baseboard_fab2_lib.baseboard_fab2(sch_1):page143_i281@mstr_controller.ast1250(chips)!AST1250_BGA-IC,G85138-002!!!F4192!MA(11)!!!!
S!M_BMC_DDR3_MA<12>!U9F4!W17!@baseboard_fab2_lib.baseboard_fab2(sch_1):page143_i281@mstr_controller.ast1250(chips)!AST1250_BGA-IC,G85138-002!!!F4192!MA(12)!!!!
S!M_BMC_DDR3_MA<13>!U9F4!Y17!@baseboard_fab2_lib.baseboard_fab2(sch_1):page143_i281@mstr_controller.ast1250(chips)!AST1250_BGA-IC,G85138-002!!!F4192!MA(13)!!!!
S!M_BMC_DDR3_MA<14>!U9F4!AB17!@baseboard_fab2_lib.baseboard_fab2(sch_1):page143_i281@mstr_controller.ast1250(chips)!AST1250_BGA-IC,G85138-002!!!F4192!MA(14)!!!!
S!M_BMC_DDR3_MA<1>!U9F4!W15!@baseboard_fab2_lib.baseboard_fab2(sch_1):page143_i281@mstr_controller.ast1250(chips)!AST1250_BGA-IC,G85138-002!!!F4192!MA(1)!!!!
S!M_BMC_DDR3_MA<2>!U9F4!V15!@baseboard_fab2_lib.baseboard_fab2(sch_1):page143_i281@mstr_controller.ast1250(chips)!AST1250_BGA-IC,G85138-002!!!F4192!MA(2)!!!!
S!M_BMC_DDR3_MA<3>!U9F4!Y16!@baseboard_fab2_lib.baseboard_fab2(sch_1):page143_i281@mstr_controller.ast1250(chips)!AST1250_BGA-IC,G85138-002!!!F4192!MA(3)!!!!
S!M_BMC_DDR3_MA<4>!U9F4!AB15!@baseboard_fab2_lib.baseboard_fab2(sch_1):page143_i281@mstr_controller.ast1250(chips)!AST1250_BGA-IC,G85138-002!!!F4192!MA(4)!!!!
S!M_BMC_DDR3_MA<5>!U9F4!W16!@baseboard_fab2_lib.baseboard_fab2(sch_1):page143_i281@mstr_controller.ast1250(chips)!AST1250_BGA-IC,G85138-002!!!F4192!MA(5)!!!!
S!M_BMC_DDR3_MA<6>!U9F4!AA15!@baseboard_fab2_lib.baseboard_fab2(sch_1):page143_i281@mstr_controller.ast1250(chips)!AST1250_BGA-IC,G85138-002!!!F4192!MA(6)!!!!
S!M_BMC_DDR3_MA<7>!U9F4!AB18!@baseboard_fab2_lib.baseboard_fab2(sch_1):page143_i281@mstr_controller.ast1250(chips)!AST1250_BGA-IC,G85138-002!!!F4192!MA(7)!!!!
S!M_BMC_DDR3_MA<8>!U9F4!AB16!@baseboard_fab2_lib.baseboard_fab2(sch_1):page143_i281@mstr_controller.ast1250(chips)!AST1250_BGA-IC,G85138-002!!!F4192!MA(8)!!!!
S!M_BMC_DDR3_MA<9>!U9F4!AA17!@baseboard_fab2_lib.baseboard_fab2(sch_1):page143_i281@mstr_controller.ast1250(chips)!AST1250_BGA-IC,G85138-002!!!F4192!MA(9)!!!!
S!M_BMC_DDR3_MBA_0!U9F4!W14!@baseboard_fab2_lib.baseboard_fab2(sch_1):page143_i281@mstr_controller.ast1250(chips)!AST1250_BGA-IC,G85138-002!!!F4192!MBA(0)!!!!
S!M_BMC_DDR3_MBA_1!U9F4!AA14!@baseboard_fab2_lib.baseboard_fab2(sch_1):page143_i281@mstr_controller.ast1250(chips)!AST1250_BGA-IC,G85138-002!!!F4192!MBA(1)!!!!
S!M_BMC_DDR3_MBA_2!U9F4!Y14!@baseboard_fab2_lib.baseboard_fab2(sch_1):page143_i281@mstr_controller.ast1250(chips)!AST1250_BGA-IC,G85138-002!!!F4192!MBA(2)!!!!
S!M_BMC_DDR3_MCAS_N!U9F4!AB13!@baseboard_fab2_lib.baseboard_fab2(sch_1):page143_i281@mstr_controller.ast1250(chips)!AST1250_BGA-IC,G85138-002!!!F4192!MCAS_N!!!!
S!M_BMC_DDR3_MCKE!U9F4!Y12!@baseboard_fab2_lib.baseboard_fab2(sch_1):page143_i281@mstr_controller.ast1250(chips)!AST1250_BGA-IC,G85138-002!!!F4192!MCKE!!!!
S!M_BMC_DDR3_MCK_N!U9F4!AA12!@baseboard_fab2_lib.baseboard_fab2(sch_1):page143_i281@mstr_controller.ast1250(chips)!AST1250_BGA-IC,G85138-002!!!F4192!MCKN!!!!
S!M_BMC_DDR3_MCK_P!U9F4!AB12!@baseboard_fab2_lib.baseboard_fab2(sch_1):page143_i281@mstr_controller.ast1250(chips)!AST1250_BGA-IC,G85138-002!!!F4192!MCKP!!!!
S!M_BMC_DDR3_MCS_N!U9F4!AA13!@baseboard_fab2_lib.baseboard_fab2(sch_1):page143_i281@mstr_controller.ast1250(chips)!AST1250_BGA-IC,G85138-002!!!F4192!MCS_N!!!!
S!M_BMC_DDR3_MDM_0!U9F4!W10!@baseboard_fab2_lib.baseboard_fab2(sch_1):page143_i281@mstr_controller.ast1250(chips)!AST1250_BGA-IC,G85138-002!!!F4192!MDM(0)!!!!
S!M_BMC_DDR3_MDM_1!U9F4!V8!@baseboard_fab2_lib.baseboard_fab2(sch_1):page143_i281@mstr_controller.ast1250(chips)!AST1250_BGA-IC,G85138-002!!!F4192!MDM(1)!!!!
S!M_BMC_DDR3_DQ<0>!U9F4!W12!@baseboard_fab2_lib.baseboard_fab2(sch_1):page143_i281@mstr_controller.ast1250(chips)!AST1250_BGA-IC,G85138-002!!!F4192!MDQ(0)!!!!
S!M_BMC_DDR3_DQ<10>!U9F4!AA9!@baseboard_fab2_lib.baseboard_fab2(sch_1):page143_i281@mstr_controller.ast1250(chips)!AST1250_BGA-IC,G85138-002!!!F4192!MDQ(10)!!!!
S!M_BMC_DDR3_DQ<11>!U9F4!Y9!@baseboard_fab2_lib.baseboard_fab2(sch_1):page143_i281@mstr_controller.ast1250(chips)!AST1250_BGA-IC,G85138-002!!!F4192!MDQ(11)!!!!
S!M_BMC_DDR3_DQ<12>!U9F4!W9!@baseboard_fab2_lib.baseboard_fab2(sch_1):page143_i281@mstr_controller.ast1250(chips)!AST1250_BGA-IC,G85138-002!!!F4192!MDQ(12)!!!!
S!M_BMC_DDR3_DQ<13>!U9F4!V9!@baseboard_fab2_lib.baseboard_fab2(sch_1):page143_i281@mstr_controller.ast1250(chips)!AST1250_BGA-IC,G85138-002!!!F4192!MDQ(13)!!!!
S!M_BMC_DDR3_DQ<14>!U9F4!Y8!@baseboard_fab2_lib.baseboard_fab2(sch_1):page143_i281@mstr_controller.ast1250(chips)!AST1250_BGA-IC,G85138-002!!!F4192!MDQ(14)!!!!
S!M_BMC_DDR3_DQ<15>!U9F4!W8!@baseboard_fab2_lib.baseboard_fab2(sch_1):page143_i281@mstr_controller.ast1250(chips)!AST1250_BGA-IC,G85138-002!!!F4192!MDQ(15)!!!!
S!M_BMC_DDR3_DQ<1>!U9F4!V12!@baseboard_fab2_lib.baseboard_fab2(sch_1):page143_i281@mstr_controller.ast1250(chips)!AST1250_BGA-IC,G85138-002!!!F4192!MDQ(1)!!!!
S!M_BMC_DDR3_DQ<2>!U9F4!AB11!@baseboard_fab2_lib.baseboard_fab2(sch_1):page143_i281@mstr_controller.ast1250(chips)!AST1250_BGA-IC,G85138-002!!!F4192!MDQ(2)!!!!
S!M_BMC_DDR3_DQ<3>!U9F4!AA11!@baseboard_fab2_lib.baseboard_fab2(sch_1):page143_i281@mstr_controller.ast1250(chips)!AST1250_BGA-IC,G85138-002!!!F4192!MDQ(3)!!!!
S!M_BMC_DDR3_DQ<4>!U9F4!Y11!@baseboard_fab2_lib.baseboard_fab2(sch_1):page143_i281@mstr_controller.ast1250(chips)!AST1250_BGA-IC,G85138-002!!!F4192!MDQ(4)!!!!
S!M_BMC_DDR3_DQ<5>!U9F4!W11!@baseboard_fab2_lib.baseboard_fab2(sch_1):page143_i281@mstr_controller.ast1250(chips)!AST1250_BGA-IC,G85138-002!!!F4192!MDQ(5)!!!!
S!M_BMC_DDR3_DQ<6>!U9F4!V11!@baseboard_fab2_lib.baseboard_fab2(sch_1):page143_i281@mstr_controller.ast1250(chips)!AST1250_BGA-IC,G85138-002!!!F4192!MDQ(6)!!!!
S!M_BMC_DDR3_DQ<7>!U9F4!Y10!@baseboard_fab2_lib.baseboard_fab2(sch_1):page143_i281@mstr_controller.ast1250(chips)!AST1250_BGA-IC,G85138-002!!!F4192!MDQ(7)!!!!
S!M_BMC_DDR3_DQ<8>!U9F4!V10!@baseboard_fab2_lib.baseboard_fab2(sch_1):page143_i281@mstr_controller.ast1250(chips)!AST1250_BGA-IC,G85138-002!!!F4192!MDQ(8)!!!!
S!M_BMC_DDR3_DQ<9>!U9F4!AB9!@baseboard_fab2_lib.baseboard_fab2(sch_1):page143_i281@mstr_controller.ast1250(chips)!AST1250_BGA-IC,G85138-002!!!F4192!MDQ(9)!!!!
S!M_BMC_DDR3_MDQS_0_DP!U9F4!AB10!@baseboard_fab2_lib.baseboard_fab2(sch_1):page143_i281@mstr_controller.ast1250(chips)!AST1250_BGA-IC,G85138-002!!!F4192!MDQS0!!!!
S!M_BMC_DDR3_MDQS_0_DN!U9F4!AA10!@baseboard_fab2_lib.baseboard_fab2(sch_1):page143_i281@mstr_controller.ast1250(chips)!AST1250_BGA-IC,G85138-002!!!F4192!MDQS0_N!!!!
S!M_BMC_DDR3_MDQS_1_DP!U9F4!AA8!@baseboard_fab2_lib.baseboard_fab2(sch_1):page143_i281@mstr_controller.ast1250(chips)!AST1250_BGA-IC,G85138-002!!!F4192!MDQS1!!!!
S!M_BMC_DDR3_MDQS_1_DN!U9F4!AB8!@baseboard_fab2_lib.baseboard_fab2(sch_1):page143_i281@mstr_controller.ast1250(chips)!AST1250_BGA-IC,G85138-002!!!F4192!MDQS1_N!!!!
S!TP_M_BMC_DDR3_MIOZ!U9F4!V16!@baseboard_fab2_lib.baseboard_fab2(sch_1):page143_i281@mstr_controller.ast1250(chips)!AST1250_BGA-IC,G85138-002!!!F4192!MIOZ!!!!
S!M_BMC_DDR3_MODT!U9F4!V14!@baseboard_fab2_lib.baseboard_fab2(sch_1):page143_i281@mstr_controller.ast1250(chips)!AST1250_BGA-IC,G85138-002!!!F4192!MODT!!!!
S!M_BMC_DDR3_MRAS_N!U9F4!W13!@baseboard_fab2_lib.baseboard_fab2(sch_1):page143_i281@mstr_controller.ast1250(chips)!AST1250_BGA-IC,G85138-002!!!F4192!MRAS_N!!!!
S!M_BMC_DDR3_MVREF!U9F4!V13!@baseboard_fab2_lib.baseboard_fab2(sch_1):page143_i281@mstr_controller.ast1250(chips)!AST1250_BGA-IC,G85138-002!!!F4192!MVREF!!!!
S!M_BMC_DDR3_MWE_N!U9F4!Y13!@baseboard_fab2_lib.baseboard_fab2(sch_1):page143_i281@mstr_controller.ast1250(chips)!AST1250_BGA-IC,G85138-002!!!F4192!MWE_N!!!!
S!TP_DACB!U9F4!R4!@baseboard_fab2_lib.baseboard_fab2(sch_1):page144_i347@mstr_controller.ast1250(chips)!AST1250_BGA-IC,G85138-002!!!F4191!DACB!!!!
S!TP_DACG!U9F4!R3!@baseboard_fab2_lib.baseboard_fab2(sch_1):page144_i347@mstr_controller.ast1250(chips)!AST1250_BGA-IC,G85138-002!!!F4191!DACG!!!!
S!TP_DACR!U9F4!R2!@baseboard_fab2_lib.baseboard_fab2(sch_1):page144_i347@mstr_controller.ast1250(chips)!AST1250_BGA-IC,G85138-002!!!F4191!DACR!!!!
S!A_DACRSET!U9F4!R1!@baseboard_fab2_lib.baseboard_fab2(sch_1):page144_i347@mstr_controller.ast1250(chips)!AST1250_BGA-IC,G85138-002!!!F4191!DACRSET!!!!
S!TP_DDCCLK_GPIOJ6!U9F4!T2!@baseboard_fab2_lib.baseboard_fab2(sch_1):page144_i347@mstr_controller.ast1250(chips)!AST1250_BGA-IC,G85138-002!!!F4191!DDCCLK_GPIOJ6!!!!
S!TP_DDCDAT_GPIOJ7!U9F4!T1!@baseboard_fab2_lib.baseboard_fab2(sch_1):page144_i347@mstr_controller.ast1250(chips)!AST1250_BGA-IC,G85138-002!!!F4191!DDCDAT_GPIOJ7!!!!
S!USB_PCH_BMC_P4_DN!U9F4!K3!@baseboard_fab2_lib.baseboard_fab2(sch_1):page144_i347@mstr_controller.ast1250(chips)!AST1250_BGA-IC,G85138-002!!!F4191!DN_USB11_DN_USB11_HDN2!!!!
S!USB2_PCH_BMC_P5_DN!U9F4!AB20!@baseboard_fab2_lib.baseboard_fab2(sch_1):page144_i347@mstr_controller.ast1250(chips)!AST1250_BGA-IC,G85138-002!!!F4191!DN_USB2_DN_USB2_HDN!!!!
S!USB_PCH_BMC_P4_DP!U9F4!K4!@baseboard_fab2_lib.baseboard_fab2(sch_1):page144_i347@mstr_controller.ast1250(chips)!AST1250_BGA-IC,G85138-002!!!F4191!DP_USB11_DP_USB11_HDP2!!!!
S!USB2_PCH_BMC_P5_DP!U9F4!AB21!@baseboard_fab2_lib.baseboard_fab2(sch_1):page144_i347@mstr_controller.ast1250(chips)!AST1250_BGA-IC,G85138-002!!!F4191!DP_USB2_DP_USB2_HDP!!!!
S!SMB_OCP_FRU_STBY_LVC3_SCL_R!U9F4!C5!@baseboard_fab2_lib.baseboard_fab2(sch_1):page144_i347@mstr_controller.ast1250(chips)!AST1250_BGA-IC,G85138-002!!!F4191!GPIOA4_TIMER5_SCL9!!!!
S!SMB_OCP_FRU_STBY_LVC3_SDA_R!U9F4!B4!@baseboard_fab2_lib.baseboard_fab2(sch_1):page144_i347@mstr_controller.ast1250(chips)!AST1250_BGA-IC,G85138-002!!!F4191!GPIOA5_TIMER6_SDA9!!!!
S!FM_BMC_HEARTBEAT_N!U9F4!J21!@baseboard_fab2_lib.baseboard_fab2(sch_1):page144_i347@mstr_controller.ast1250(chips)!AST1250_BGA-IC,G85138-002!!!F4191!GPIOB0_SALT1!!!!
S!FM_BIOS_SMI_ACTIVE_N!U9F4!J20!@baseboard_fab2_lib.baseboard_fab2(sch_1):page144_i347@mstr_controller.ast1250(chips)!AST1250_BGA-IC,G85138-002!!!F4191!GPIOB1_SALT2!!!!
S!FM_POST_CARD_PRES_BMC_N!U9F4!H18!@baseboard_fab2_lib.baseboard_fab2(sch_1):page144_i347@mstr_controller.ast1250(chips)!AST1250_BGA-IC,G85138-002!!!F4191!GPIOB2_SALT3!!!!
S!FM_FAST_PROCHOT_EN_N!U9F4!F18!@baseboard_fab2_lib.baseboard_fab2(sch_1):page144_i347@mstr_controller.ast1250(chips)!AST1250_BGA-IC,G85138-002!!!F4191!GPIOB3_SALT4!!!!
S!RST_BMC_LVC3_N!U9F4!E19!@baseboard_fab2_lib.baseboard_fab2(sch_1):page144_i347@mstr_controller.ast1250(chips)!AST1250_BGA-IC,G85138-002!!!F4191!GPIOB4_LPCRST_N!!!!
S!FM_CPU0_THERMTRIP_LATCH_LVT3_N!U9F4!H19!@baseboard_fab2_lib.baseboard_fab2(sch_1):page144_i347@mstr_controller.ast1250(chips)!AST1250_BGA-IC,G85138-002!!!F4191!GPIOB5_LPCPD_N_LPCSMI_N!!!!
S!FM_CPU1_THERMTRIP_LATCH_LVT3_N!U9F4!H20!@baseboard_fab2_lib.baseboard_fab2(sch_1):page144_i347@mstr_controller.ast1250(chips)!AST1250_BGA-IC,G85138-002!!!F4191!GPIOB6_LPCPME_N!!!!
S!FM_CPU_BMC_INIT!U9F4!A14!@baseboard_fab2_lib.baseboard_fab2(sch_1):page144_i347@mstr_controller.ast1250(chips)!AST1250_BGA-IC,G85138-002!!!F4191!GPIOG0_SGPSCK!!!!
S!IRQ_PCH_NIC_ALERT_N!U9F4!E13!@baseboard_fab2_lib.baseboard_fab2(sch_1):page144_i347@mstr_controller.ast1250(chips)!AST1250_BGA-IC,G85138-002!!!F4191!GPIOG1_SGPSLD!!!!
S!FM_SLPS3_N!U9F4!D13!@baseboard_fab2_lib.baseboard_fab2(sch_1):page144_i347@mstr_controller.ast1250(chips)!AST1250_BGA-IC,G85138-002!!!F4191!GPIOG2_SGPSI0!!!!
S!FM_SLPS4_N!U9F4!C13!@baseboard_fab2_lib.baseboard_fab2(sch_1):page144_i347@mstr_controller.ast1250(chips)!AST1250_BGA-IC,G85138-002!!!F4191!GPIOG3_SGPSI1!!!!
S!TP_SPI_PCH_BIOS_CS0_R_N!U9F4!C22!@baseboard_fab2_lib.baseboard_fab2(sch_1):page144_i347@mstr_controller.ast1250(chips)!AST1250_BGA-IC,G85138-002!!!F4191!GPIOI0_SYSCS_N!!!!
S!TP_SPI_PCH_BIOS_CLK_R!U9F4!G18!@baseboard_fab2_lib.baseboard_fab2(sch_1):page144_i347@mstr_controller.ast1250(chips)!AST1250_BGA-IC,G85138-002!!!F4191!GPIOI1_SYSCK!!!!
S!TP_SPI_PCH_BIOS_MOSI_R!U9F4!D19!@baseboard_fab2_lib.baseboard_fab2(sch_1):page144_i347@mstr_controller.ast1250(chips)!AST1250_BGA-IC,G85138-002!!!F4191!GPIOI2_SYSDO!!!!
S!TP_SPI_PCH_BIOS_MISO_R!U9F4!C20!@baseboard_fab2_lib.baseboard_fab2(sch_1):page144_i347@mstr_controller.ast1250(chips)!AST1250_BGA-IC,G85138-002!!!F4191!GPIOI3_SYSDI!!!!
S!SPI_BMC_CS0_N!U9F4!B22!@baseboard_fab2_lib.baseboard_fab2(sch_1):page144_i347@mstr_controller.ast1250(chips)!AST1250_BGA-IC,G85138-002!!!F4191!GPIOI4_SPICS0_N_VBCS_N!!!!
S!SPI_BMC_CLK!U9F4!G19!@baseboard_fab2_lib.baseboard_fab2(sch_1):page144_i347@mstr_controller.ast1250(chips)!AST1250_BGA-IC,G85138-002!!!F4191!GPIOI5_SPICK_VBCK!!!!
S!SPI_BMC_DO!U9F4!C18!@baseboard_fab2_lib.baseboard_fab2(sch_1):page144_i347@mstr_controller.ast1250(chips)!AST1250_BGA-IC,G85138-002!!!F4191!GPIOI6_SPIDO_VBDO!!!!
S!SPI_BMC_DI!U9F4!E20!@baseboard_fab2_lib.baseboard_fab2(sch_1):page144_i347@mstr_controller.ast1250(chips)!AST1250_BGA-IC,G85138-002!!!F4191!GPIOI7_SPIDI_VBDI!!!!
S!SGPIO_BMC_CLK_R!U9F4!J5!@baseboard_fab2_lib.baseboard_fab2(sch_1):page144_i347@mstr_controller.ast1250(chips)!AST1250_BGA-IC,G85138-002!!!F4191!GPIOJ0_SGPMCK!!!!
S!SGPIO_BMC_LD_R_N!U9F4!J4!@baseboard_fab2_lib.baseboard_fab2(sch_1):page144_i347@mstr_controller.ast1250(chips)!AST1250_BGA-IC,G85138-002!!!F4191!GPIOJ1_SGPMLD!!!!
S!SGPIO_BMC_DOUT_R!U9F4!K5!@baseboard_fab2_lib.baseboard_fab2(sch_1):page144_i347@mstr_controller.ast1250(chips)!AST1250_BGA-IC,G85138-002!!!F4191!GPIOJ2_SGPMO!!!!
S!SGPIO_BMC_DIN!U9F4!J3!@baseboard_fab2_lib.baseboard_fab2(sch_1):page144_i347@mstr_controller.ast1250(chips)!AST1250_BGA-IC,G85138-002!!!F4191!GPIOJ3_SGPMI!!!!
S!SMB_SMLINK0_STBY_LVC3_SCL_R!U9F4!E3!@baseboard_fab2_lib.baseboard_fab2(sch_1):page144_i347@mstr_controller.ast1250(chips)!AST1250_BGA-IC,G85138-002!!!F4191!GPIOK0_SCL5!!!!
S!SMB_SMLINK0_STBY_LVC3_SDA_R!U9F4!D2!@baseboard_fab2_lib.baseboard_fab2(sch_1):page144_i347@mstr_controller.ast1250(chips)!AST1250_BGA-IC,G85138-002!!!F4191!GPIOK1_SDA5!!!!
S!SMB_VR_STBY_LVC3_SCL_R!U9F4!C1!@baseboard_fab2_lib.baseboard_fab2(sch_1):page144_i347@mstr_controller.ast1250(chips)!AST1250_BGA-IC,G85138-002!!!F4191!GPIOK2_SCL6!!!!
S!SMB_VR_STBY_LVC3_SDA_R!U9F4!F4!@baseboard_fab2_lib.baseboard_fab2(sch_1):page144_i347@mstr_controller.ast1250(chips)!AST1250_BGA-IC,G85138-002!!!F4191!GPIOK3_SDA6!!!!
S!SMB_SENSOR_BMC_STBY_LVC3_SCL!U9F4!E2!@baseboard_fab2_lib.baseboard_fab2(sch_1):page144_i347@mstr_controller.ast1250(chips)!AST1250_BGA-IC,G85138-002!!!F4191!GPIOK4_SCL7!!!!
S!SMB_SENSOR_BMC_STBY_LVC3_SDA!U9F4!D1!@baseboard_fab2_lib.baseboard_fab2(sch_1):page144_i347@mstr_controller.ast1250(chips)!AST1250_BGA-IC,G85138-002!!!F4191!GPIOK5_SDA7!!!!
S!SMB_BMC_PMBUS_STBY_LVC3_SCL_R!U9F4!G5!@baseboard_fab2_lib.baseboard_fab2(sch_1):page144_i347@mstr_controller.ast1250(chips)!AST1250_BGA-IC,G85138-002!!!F4191!GPIOK6_SCL8!!!!
S!SMB_BMC_PMBUS_STBY_LVC3_SDA_R!U9F4!F3!@baseboard_fab2_lib.baseboard_fab2(sch_1):page144_i347@mstr_controller.ast1250(chips)!AST1250_BGA-IC,G85138-002!!!F4191!GPIOK7_SDA8!!!!
S!SMB_OCP_LAN_STBY_LVC3_SCL_R!U9F4!D3!@baseboard_fab2_lib.baseboard_fab2(sch_1):page144_i347@mstr_controller.ast1250(chips)!AST1250_BGA-IC,G85138-002!!!F4191!GPIOQ0_SCL3!!!!
S!SMB_OCP_LAN_STBY_LVC3_SDA_R!U9F4!C2!@baseboard_fab2_lib.baseboard_fab2(sch_1):page144_i347@mstr_controller.ast1250(chips)!AST1250_BGA-IC,G85138-002!!!F4191!GPIOQ1_SDA3!!!!
S!SMB_HOST_STBY_LVC3_SCL_R!U9F4!B1!@baseboard_fab2_lib.baseboard_fab2(sch_1):page144_i347@mstr_controller.ast1250(chips)!AST1250_BGA-IC,G85138-002!!!F4191!GPIOQ2_SCL4!!!!
S!SMB_HOST_STBY_LVC3_SDA_R!U9F4!F5!@baseboard_fab2_lib.baseboard_fab2(sch_1):page144_i347@mstr_controller.ast1250(chips)!AST1250_BGA-IC,G85138-002!!!F4191!GPIOQ3_SDA4!!!!
S!LPC_LAD0_IO0_R!U9F4!B21!@baseboard_fab2_lib.baseboard_fab2(sch_1):page144_i347@mstr_controller.ast1250(chips)!AST1250_BGA-IC,G85138-002!!!F4191!LAD(0)!!!!
S!LPC_LAD1_IO1_R!U9F4!A22!@baseboard_fab2_lib.baseboard_fab2(sch_1):page144_i347@mstr_controller.ast1250(chips)!AST1250_BGA-IC,G85138-002!!!F4191!LAD(1)!!!!
S!LPC_LAD2_IO2_R!U9F4!F19!@baseboard_fab2_lib.baseboard_fab2(sch_1):page144_i347@mstr_controller.ast1250(chips)!AST1250_BGA-IC,G85138-002!!!F4191!LAD(2)!!!!
S!LPC_LAD3_IO3_R!U9F4!C19!@baseboard_fab2_lib.baseboard_fab2(sch_1):page144_i347@mstr_controller.ast1250(chips)!AST1250_BGA-IC,G85138-002!!!F4191!LAD(3)!!!!
S!CLK_24M_BMC_LPC!U9F4!B20!@baseboard_fab2_lib.baseboard_fab2(sch_1):page144_i347@mstr_controller.ast1250(chips)!AST1250_BGA-IC,G85138-002!!!F4191!LCLK!!!!
S!LPC_LFRAME_N_CS0_R_N!U9F4!A21!@baseboard_fab2_lib.baseboard_fab2(sch_1):page144_i347@mstr_controller.ast1250(chips)!AST1250_BGA-IC,G85138-002!!!F4191!LFRAME_N!!!!
S!IRQ_LPC_SERIRQ_R!U9F4!E17!@baseboard_fab2_lib.baseboard_fab2(sch_1):page144_i347@mstr_controller.ast1250(chips)!AST1250_BGA-IC,G85138-002!!!F4191!LSIRQ_N!!!!
S!JTAG_BMC_TRST_N!U9F4!E1!@baseboard_fab2_lib.baseboard_fab2(sch_1):page144_i347@mstr_controller.ast1250(chips)!AST1250_BGA-IC,G85138-002!!!F4191!NTRST!!!!
S!TP_JTAG_BMC_RTCK!U9F4!G4!@baseboard_fab2_lib.baseboard_fab2(sch_1):page144_i347@mstr_controller.ast1250(chips)!AST1250_BGA-IC,G85138-002!!!F4191!RTCK!!!!
S!SMB_LAN_STBY_LVC3_SCL_R!U9F4!K21!@baseboard_fab2_lib.baseboard_fab2(sch_1):page144_i347@mstr_controller.ast1250(chips)!AST1250_BGA-IC,G85138-002!!!F4191!SCL(1)!!!!
S!SMB_SLOTX24_STBY_LVC3_SCL_R!U9F4!J19!@baseboard_fab2_lib.baseboard_fab2(sch_1):page144_i347@mstr_controller.ast1250(chips)!AST1250_BGA-IC,G85138-002!!!F4191!SCL(2)!!!!
S!SMB_LAN_STBY_LVC3_SDA_R!U9F4!K22!@baseboard_fab2_lib.baseboard_fab2(sch_1):page144_i347@mstr_controller.ast1250(chips)!AST1250_BGA-IC,G85138-002!!!F4191!SDA(1)!!!!
S!SMB_SLOTX24_STBY_LVC3_SDA_R!U9F4!J18!@baseboard_fab2_lib.baseboard_fab2(sch_1):page144_i347@mstr_controller.ast1250(chips)!AST1250_BGA-IC,G85138-002!!!F4191!SDA(2)!!!!
S!JTAG_BMC_TCK!U9F4!F2!@baseboard_fab2_lib.baseboard_fab2(sch_1):page144_i347@mstr_controller.ast1250(chips)!AST1250_BGA-IC,G85138-002!!!F4191!TCK!!!!
S!JTAG_BMC_TDI!U9F4!F1!@baseboard_fab2_lib.baseboard_fab2(sch_1):page144_i347@mstr_controller.ast1250(chips)!AST1250_BGA-IC,G85138-002!!!F4191!TDI!!!!
S!JTAG_BMC_TDO!U9F4!G3!@baseboard_fab2_lib.baseboard_fab2(sch_1):page144_i347@mstr_controller.ast1250(chips)!AST1250_BGA-IC,G85138-002!!!F4191!TDO!!!!
S!JTAG_BMC_TMS!U9F4!G2!@baseboard_fab2_lib.baseboard_fab2(sch_1):page144_i347@mstr_controller.ast1250(chips)!AST1250_BGA-IC,G85138-002!!!F4191!TMS!!!!
S!PD_USB_BMC_P1_DN!U9F4!J2!@baseboard_fab2_lib.baseboard_fab2(sch_1):page144_i347@mstr_controller.ast1250(chips)!AST1250_BGA-IC,G85138-002!!!F4191!USB11_HDN!!!!
S!PD_USB_BMC_P1_DP!U9F4!J1!@baseboard_fab2_lib.baseboard_fab2(sch_1):page144_i347@mstr_controller.ast1250(chips)!AST1250_BGA-IC,G85138-002!!!F4191!USB11_HDP!!!!
S!A_USB2VRES!U9F4!AA20!@baseboard_fab2_lib.baseboard_fab2(sch_1):page144_i347@mstr_controller.ast1250(chips)!AST1250_BGA-IC,G85138-002!!!F4191!USB2VRES!!!!
S!TP_VGAHS_GPIOJ4!U9F4!T4!@baseboard_fab2_lib.baseboard_fab2(sch_1):page144_i347@mstr_controller.ast1250(chips)!AST1250_BGA-IC,G85138-002!!!F4191!VGAHS_GPIOJ4!!!!
S!TP_VGAVS_GPIOJ5!U9F4!U2!@baseboard_fab2_lib.baseboard_fab2(sch_1):page144_i347@mstr_controller.ast1250(chips)!AST1250_BGA-IC,G85138-002!!!F4191!VGAVS_GPIOJ5!!!!
S!CLK_24M_25M_BMC_CLKIN!U9F4!AB22!@baseboard_fab2_lib.baseboard_fab2(sch_1):page145_i100@mstr_controller.ast1250(chips)!AST1250_BGA-IC,G85138-002!!!F4190!CLKIN!!!!
S!PD_SP_ENTEST!U9F4!E4!@baseboard_fab2_lib.baseboard_fab2(sch_1):page145_i100@mstr_controller.ast1250(chips)!AST1250_BGA-IC,G85138-002!!!F4190!ENTEST!!!!
S!FM_CPLD_BMC_PWRDN_N!U9F4!D6!@baseboard_fab2_lib.baseboard_fab2(sch_1):page145_i100@mstr_controller.ast1250(chips)!AST1250_BGA-IC,G85138-002!!!F4190!GPIOA0_MAC1LINK!!!!
S!FM_BMC_FAULT_LED_N!U9F4!B5!@baseboard_fab2_lib.baseboard_fab2(sch_1):page145_i100@mstr_controller.ast1250(chips)!AST1250_BGA-IC,G85138-002!!!F4190!GPIOA1_MAC2LINK!!!!
S!FM_BIOS_POST_CMPLT_N!U9F4!A4!@baseboard_fab2_lib.baseboard_fab2(sch_1):page145_i100@mstr_controller.ast1250(chips)!AST1250_BGA-IC,G85138-002!!!F4190!GPIOA2_TIMER3!!!!
S!FM_BMC_SYS_THROTTLE_R_N!U9F4!E6!@baseboard_fab2_lib.baseboard_fab2(sch_1):page145_i100@mstr_controller.ast1250(chips)!AST1250_BGA-IC,G85138-002!!!F4190!GPIOA3_TIMER4!!!!
S!FM_BMC_CPLD_GPO!U9F4!E18!@baseboard_fab2_lib.baseboard_fab2(sch_1):page145_i100@mstr_controller.ast1250(chips)!AST1250_BGA-IC,G85138-002!!!F4190!GPIOB7_EXTRST_N_SPICS1_N!!!!
S!IRQ_PVDDQ_ABC_VRHOT_LVT3_N!U9F4!C4!@baseboard_fab2_lib.baseboard_fab2(sch_1):page145_i100@mstr_controller.ast1250(chips)!AST1250_BGA-IC,G85138-002!!!F4190!GPIOC0_SD1CLK_SCL10!!!!
S!IRQ_PVDDQ_DEF_VRHOT_LVT3_N!U9F4!B3!@baseboard_fab2_lib.baseboard_fab2(sch_1):page145_i100@mstr_controller.ast1250(chips)!AST1250_BGA-IC,G85138-002!!!F4190!GPIOC1_SD1CMD_SDA10!!!!
S!H_CPU0_MEMABC_MEMHOT_LVT3_BMC_N!U9F4!A2!@baseboard_fab2_lib.baseboard_fab2(sch_1):page145_i100@mstr_controller.ast1250(chips)!AST1250_BGA-IC,G85138-002!!!F4190!GPIOC2_SD1DAT0_SCL11!!!!
S!H_CPU0_MEMDEF_MEMHOT_LVT3_BMC_N!U9F4!E5!@baseboard_fab2_lib.baseboard_fab2(sch_1):page145_i100@mstr_controller.ast1250(chips)!AST1250_BGA-IC,G85138-002!!!F4190!GPIOC3_SD1DAT1_SDA11!!!!
S!IRQ_PVDDQ_GHJ_VRHOT_LVT3_N!U9F4!D4!@baseboard_fab2_lib.baseboard_fab2(sch_1):page145_i100@mstr_controller.ast1250(chips)!AST1250_BGA-IC,G85138-002!!!F4190!GPIOC4_SD1DAT2_SCL12!!!!
S!IRQ_PVDDQ_KLM_VRHOT_LVT3_N!U9F4!C3!@baseboard_fab2_lib.baseboard_fab2(sch_1):page145_i100@mstr_controller.ast1250(chips)!AST1250_BGA-IC,G85138-002!!!F4190!GPIOC5_SD1DAT3_SDA12!!!!
S!H_CPU1_MEMGHJ_MEMHOT_LVT3_BMC_N!U9F4!B2!@baseboard_fab2_lib.baseboard_fab2(sch_1):page145_i100@mstr_controller.ast1250(chips)!AST1250_BGA-IC,G85138-002!!!F4190!GPIOC6_SD1CD_N_SCL13!!!!
S!H_CPU1_MEMKLM_MEMHOT_LVT3_BMC_N!U9F4!A1!@baseboard_fab2_lib.baseboard_fab2(sch_1):page145_i100@mstr_controller.ast1250(chips)!AST1250_BGA-IC,G85138-002!!!F4190!GPIOC7_SD1WP_N_SDA13!!!!
S!FP_NMI_BTN_N!U9F4!A18!@baseboard_fab2_lib.baseboard_fab2(sch_1):page145_i100@mstr_controller.ast1250(chips)!AST1250_BGA-IC,G85138-002!!!F4190!GPIOD0_SD2CLK!!!!
S!IRQ_BMC_PCH_NMI_STBY_N!U9F4!D16!@baseboard_fab2_lib.baseboard_fab2(sch_1):page145_i100@mstr_controller.ast1250(chips)!AST1250_BGA-IC,G85138-002!!!F4190!GPIOD1_SD2CMD!!!!
S!FM_PWR_BTN_N!U9F4!B17!@baseboard_fab2_lib.baseboard_fab2(sch_1):page145_i100@mstr_controller.ast1250(chips)!AST1250_BGA-IC,G85138-002!!!F4190!GPIOD2_SD2DAT0!!!!
S!FM_BMC_PWRBTN_OUT_N!U9F4!A17!@baseboard_fab2_lib.baseboard_fab2(sch_1):page145_i100@mstr_controller.ast1250(chips)!AST1250_BGA-IC,G85138-002!!!F4190!GPIOD3_SD2DAT1!!!!
S!RST_SYSTEM_BTN_N!U9F4!C16!@baseboard_fab2_lib.baseboard_fab2(sch_1):page145_i100@mstr_controller.ast1250(chips)!AST1250_BGA-IC,G85138-002!!!F4190!GPIOD4_SD2DAT2!!!!
S!RST_BMC_SYSRST_BTN_OUT_N!U9F4!B16!@baseboard_fab2_lib.baseboard_fab2(sch_1):page145_i100@mstr_controller.ast1250(chips)!AST1250_BGA-IC,G85138-002!!!F4190!GPIOD5_SD2DAT3!!!!
S!FM_CPU_ERR0_LVT3_BMC_N!U9F4!A16!@baseboard_fab2_lib.baseboard_fab2(sch_1):page145_i100@mstr_controller.ast1250(chips)!AST1250_BGA-IC,G85138-002!!!F4190!GPIOD6_SD2CD_N!!!!
S!FM_CPU_ERR1_LVT3_BMC_N!U9F4!E15!@baseboard_fab2_lib.baseboard_fab2(sch_1):page145_i100@mstr_controller.ast1250(chips)!AST1250_BGA-IC,G85138-002!!!F4190!GPIOD7_SD2WP_N!!!!
S!IRQ_SML0_ALERT_N!U9F4!D15!@baseboard_fab2_lib.baseboard_fab2(sch_1):page145_i100@mstr_controller.ast1250(chips)!AST1250_BGA-IC,G85138-002!!!F4190!GPIOE0_NCTS3!!!!
S!PWRGD_PCH_PWROK!U9F4!C15!@baseboard_fab2_lib.baseboard_fab2(sch_1):page145_i100@mstr_controller.ast1250(chips)!AST1250_BGA-IC,G85138-002!!!F4190!GPIOE1_NDCD3!!!!
S!PWRGD_SYS_PWROK!U9F4!B15!@baseboard_fab2_lib.baseboard_fab2(sch_1):page145_i100@mstr_controller.ast1250(chips)!AST1250_BGA-IC,G85138-002!!!F4190!GPIOE2_NDSR3!!!!
S!FM_BB_BMC_MP_GPIO!U9F4!A15!@baseboard_fab2_lib.baseboard_fab2(sch_1):page145_i100@mstr_controller.ast1250(chips)!AST1250_BGA-IC,G85138-002!!!F4190!GPIOE3_NRI3!!!!
S!IRQ_BMC_PCH_SCI_LPC_N!U9F4!E14!@baseboard_fab2_lib.baseboard_fab2(sch_1):page145_i100@mstr_controller.ast1250(chips)!AST1250_BGA-IC,G85138-002!!!F4190!GPIOE4_NDTR3!!!!
S!IRQ_BMC_PCH_SMI_LPC_N!U9F4!D14!@baseboard_fab2_lib.baseboard_fab2(sch_1):page145_i100@mstr_controller.ast1250(chips)!AST1250_BGA-IC,G85138-002!!!F4190!GPIOE5_NRTS3!!!!
S!FM_BMC_CPLD_MP_RST_N!U9F4!C14!@baseboard_fab2_lib.baseboard_fab2(sch_1):page145_i100@mstr_controller.ast1250(chips)!AST1250_BGA-IC,G85138-002!!!F4190!GPIOE6_TXD3!!!!
S!TP_GPIOE7_RXD3!U9F4!B14!@baseboard_fab2_lib.baseboard_fab2(sch_1):page145_i100@mstr_controller.ast1250(chips)!AST1250_BGA-IC,G85138-002!!!F4190!GPIOE7_RXD3!!!!
S!FM_PCH_BMC_THERMTRIP_N!U9F4!D18!@baseboard_fab2_lib.baseboard_fab2(sch_1):page145_i100@mstr_controller.ast1250(chips)!AST1250_BGA-IC,G85138-002!!!F4190!GPIOF0_NCTS4!!!!
S!FM_CPU_CATERR_LVT3_N!U9F4!B19!@baseboard_fab2_lib.baseboard_fab2(sch_1):page145_i100@mstr_controller.ast1250(chips)!AST1250_BGA-IC,G85138-002!!!F4190!GPIOF1_NDCD4_SIOPBI_N!!!!
S!IRQ_HSC_FAULT_N!U9F4!A20!@baseboard_fab2_lib.baseboard_fab2(sch_1):page145_i100@mstr_controller.ast1250(chips)!AST1250_BGA-IC,G85138-002!!!F4190!GPIOF2_NDSR4_SIOPWRGD!!!!
S!IRQ_OOB_MGMT_RISER_ALERT_N!U9F4!D17!@baseboard_fab2_lib.baseboard_fab2(sch_1):page145_i100@mstr_controller.ast1250(chips)!AST1250_BGA-IC,G85138-002!!!F4190!GPIOF3_NRI4_SIOPBO_N!!!!
S!IRQ_SML1_PMBUS_ALERT_N!U9F4!B18!@baseboard_fab2_lib.baseboard_fab2(sch_1):page145_i100@mstr_controller.ast1250(chips)!AST1250_BGA-IC,G85138-002!!!F4190!GPIOF4_NDTR4!!!!
S!IRQ_MEZZ_LAN_ALERT_N!U9F4!A19!@baseboard_fab2_lib.baseboard_fab2(sch_1):page145_i100@mstr_controller.ast1250(chips)!AST1250_BGA-IC,G85138-002!!!F4190!GPIOF5_NRTS4_SIOSCI_N!!!!
S!IRQ_LOM_ALERT_N!U9F4!E16!@baseboard_fab2_lib.baseboard_fab2(sch_1):page145_i100@mstr_controller.ast1250(chips)!AST1250_BGA-IC,G85138-002!!!F4190!GPIOF6_TXD4!!!!
S!H_CPU0_FAST_WAKE_LVT3_N!U9F4!C17!@baseboard_fab2_lib.baseboard_fab2(sch_1):page145_i100@mstr_controller.ast1250(chips)!AST1250_BGA-IC,G85138-002!!!F4190!GPIOF7_RXD4!!!!
S!FM_BATTERY_SENSE_EN_N!U9F4!B13!@baseboard_fab2_lib.baseboard_fab2(sch_1):page145_i100@mstr_controller.ast1250(chips)!AST1250_BGA-IC,G85138-002!!!F4190!GPIOG4_WDTRST1_OSCCLK!!!!
S!CLK_48M_USB_BMC!U9F4!Y21!@baseboard_fab2_lib.baseboard_fab2(sch_1):page145_i100@mstr_controller.ast1250(chips)!AST1250_BGA-IC,G85138-002!!!F4190!GPIOG5_WDTRST2_USBCKI!!!!
S!IRQ_UV_DETECT_N!U9F4!U1!@baseboard_fab2_lib.baseboard_fab2(sch_1):page145_i100@mstr_controller.ast1250(chips)!AST1250_BGA-IC,G85138-002!!!F4190!GPIOL0_NCTS1!!!!
S!IRQ_OC_DETECT_N!U9F4!T5!@baseboard_fab2_lib.baseboard_fab2(sch_1):page145_i100@mstr_controller.ast1250(chips)!AST1250_BGA-IC,G85138-002!!!F4190!GPIOL1_NDCD1_VPIDE!!!!
S!FM_HSC_TIMER_EXP_N!U9F4!U3!@baseboard_fab2_lib.baseboard_fab2(sch_1):page145_i100@mstr_controller.ast1250(chips)!AST1250_BGA-IC,G85138-002!!!F4190!GPIOL2_NDSR1_VPIODD!!!!
S!FM_BIOS_TOP_SWAP!U9F4!V1!@baseboard_fab2_lib.baseboard_fab2(sch_1):page145_i100@mstr_controller.ast1250(chips)!AST1250_BGA-IC,G85138-002!!!F4190!GPIOL3_NRI1_VPIHS!!!!
S!FM_MEM_THERM_EVENT_PCH_N!U9F4!U4!@baseboard_fab2_lib.baseboard_fab2(sch_1):page145_i100@mstr_controller.ast1250(chips)!AST1250_BGA-IC,G85138-002!!!F4190!GPIOL4_NDTR1_VPIVS!!!!
S!FM_PMBUS_ALERT_BUF_EN_N!U9F4!V2!@baseboard_fab2_lib.baseboard_fab2(sch_1):page145_i100@mstr_controller.ast1250(chips)!AST1250_BGA-IC,G85138-002!!!F4190!GPIOL5_NRTS1_VPICLK!!!!
S!SP1_BMC_HOST_UART_TX!U9F4!W1!@baseboard_fab2_lib.baseboard_fab2(sch_1):page145_i100@mstr_controller.ast1250(chips)!AST1250_BGA-IC,G85138-002!!!F4190!GPIOL6_TXD1_VPIB0!!!!
S!SP1_BMC_HOST_UART_RX!U9F4!U5!@baseboard_fab2_lib.baseboard_fab2(sch_1):page145_i100@mstr_controller.ast1250(chips)!AST1250_BGA-IC,G85138-002!!!F4190!GPIOL7_RXD1_VPIB1!!!!
S!FM_CPU0_RC_ERROR_N!U9F4!V3!@baseboard_fab2_lib.baseboard_fab2(sch_1):page145_i100@mstr_controller.ast1250(chips)!AST1250_BGA-IC,G85138-002!!!F4190!GPIOM0_NCTS2_VPIB2!!!!
S!FM_CPU1_RC_ERROR_N!U9F4!W2!@baseboard_fab2_lib.baseboard_fab2(sch_1):page145_i100@mstr_controller.ast1250(chips)!AST1250_BGA-IC,G85138-002!!!F4190!GPIOM1_NDCD2_VPIB3!!!!
S!IRQ_BOARD_BMC_ALERT_N!U9F4!Y1!@baseboard_fab2_lib.baseboard_fab2(sch_1):page145_i100@mstr_controller.ast1250(chips)!AST1250_BGA-IC,G85138-002!!!F4190!GPIOM2_NDSR2_VPIB4!!!!
S!FM_OC_DETECT_EN_N!U9F4!V4!@baseboard_fab2_lib.baseboard_fab2(sch_1):page145_i100@mstr_controller.ast1250(chips)!AST1250_BGA-IC,G85138-002!!!F4190!GPIOM3_NRI2_VPIB5!!!!
S!FM_BOARD_SKU_ID4!U9F4!W3!@baseboard_fab2_lib.baseboard_fab2(sch_1):page145_i100@mstr_controller.ast1250(chips)!AST1250_BGA-IC,G85138-002!!!F4190!GPIOM4_NDTR2_VPIB6!!!!
S!TP_GPIOM5_NRTS2_VPIB7!U9F4!Y2!@baseboard_fab2_lib.baseboard_fab2(sch_1):page145_i100@mstr_controller.ast1250(chips)!AST1250_BGA-IC,G85138-002!!!F4190!GPIOM5_NRTS2_VPIB7!!!!
S!SP2_BMC_CM_UART_TX!U9F4!AA1!@baseboard_fab2_lib.baseboard_fab2(sch_1):page145_i100@mstr_controller.ast1250(chips)!AST1250_BGA-IC,G85138-002!!!F4190!GPIOM6_TXD2_VPIB8!!!!
S!SP2_BMC_CM_UART_RX!U9F4!V5!@baseboard_fab2_lib.baseboard_fab2(sch_1):page145_i100@mstr_controller.ast1250(chips)!AST1250_BGA-IC,G85138-002!!!F4190!GPIOM7_RXD2_VPIB9!!!!
S!FM_BMC_READY_N!U9F4!H4!@baseboard_fab2_lib.baseboard_fab2(sch_1):page145_i100@mstr_controller.ast1250(chips)!AST1250_BGA-IC,G85138-002!!!F4190!GPIOQ4_SCL14!!!!
S!FP_PWR_ID_LED_N!U9F4!H3!@baseboard_fab2_lib.baseboard_fab2(sch_1):page145_i100@mstr_controller.ast1250(chips)!AST1250_BGA-IC,G85138-002!!!F4190!GPIOQ5_SDA14!!!!
S!FM_CPU0_FIVR_FAULT_LVT3_R_N!U9F4!H2!@baseboard_fab2_lib.baseboard_fab2(sch_1):page145_i100@mstr_controller.ast1250(chips)!AST1250_BGA-IC,G85138-002!!!F4190!GPIOQ(6)!!!!
S!FM_CPU1_FIVR_FAULT_LVT3_R_N!U9F4!H1!@baseboard_fab2_lib.baseboard_fab2(sch_1):page145_i100@mstr_controller.ast1250(chips)!AST1250_BGA-IC,G85138-002!!!F4190!GPIOQ(7)!!!!
S!FM_BMC_ONCTL_R_N!U9F4!K20!@baseboard_fab2_lib.baseboard_fab2(sch_1):page145_i100@mstr_controller.ast1250(chips)!AST1250_BGA-IC,G85138-002!!!F4190!GPIOY3_SIOONCTRL_N!!!!
S!CLK_100M_BMC_PE_R_DN!U9F4!G21!@baseboard_fab2_lib.baseboard_fab2(sch_1):page145_i100@mstr_controller.ast1250(chips)!AST1250_BGA-IC,G85138-002!!!F4190!NC_PEREFCLKN!!!!
S!CLK_100M_BMC_PE_R_DP!U9F4!G22!@baseboard_fab2_lib.baseboard_fab2(sch_1):page145_i100@mstr_controller.ast1250(chips)!AST1250_BGA-IC,G85138-002!!!F4190!NC_PEREFCLKP!!!!
S!PD_PEREXT!U9F4!D20!@baseboard_fab2_lib.baseboard_fab2(sch_1):page145_i100@mstr_controller.ast1250(chips)!AST1250_BGA-IC,G85138-002!!!F4190!NC_PEREXT!!!!
S!P2E_SSB_BMC_TX_C_DN!U9F4!F22!@baseboard_fab2_lib.baseboard_fab2(sch_1):page145_i100@mstr_controller.ast1250(chips)!AST1250_BGA-IC,G85138-002!!!F4190!NC_PERXN!!!!
S!P2E_SSB_BMC_TX_C_DP!U9F4!F21!@baseboard_fab2_lib.baseboard_fab2(sch_1):page145_i100@mstr_controller.ast1250(chips)!AST1250_BGA-IC,G85138-002!!!F4190!NC_PERXP!!!!
S!P2E_SSB_BMC_RX_DN!U9F4!E21!@baseboard_fab2_lib.baseboard_fab2(sch_1):page145_i100@mstr_controller.ast1250(chips)!AST1250_BGA-IC,G85138-002!!!F4190!NC_PETXN!!!!
S!P2E_SSB_BMC_RX_DP!U9F4!E22!@baseboard_fab2_lib.baseboard_fab2(sch_1):page145_i100@mstr_controller.ast1250(chips)!AST1250_BGA-IC,G85138-002!!!F4190!NC_PETXP!!!!
S!FM_PE_BMC_WAKE_N!U9F4!J22!@baseboard_fab2_lib.baseboard_fab2(sch_1):page145_i100@mstr_controller.ast1250(chips)!AST1250_BGA-IC,G85138-002!!!F4190!NC_PEWAKE_N!!!!
S!PECI_BMC_R!U9F4!AA21!@baseboard_fab2_lib.baseboard_fab2(sch_1):page145_i100@mstr_controller.ast1250(chips)!AST1250_BGA-IC,G85138-002!!!F4190!PECI!!!!
S!RST_PLTRST_BUF_N!U9F4!K19!@baseboard_fab2_lib.baseboard_fab2(sch_1):page145_i100@mstr_controller.ast1250(chips)!AST1250_BGA-IC,G85138-002!!!F4190!PERST_N!!!!
S!UART_BMC_RXD5!U9F4!G1!@baseboard_fab2_lib.baseboard_fab2(sch_1):page145_i100@mstr_controller.ast1250(chips)!AST1250_BGA-IC,G85138-002!!!F4190!RXD5!!!!
S!RST_BMC_SRST_N!U9F4!W20!@baseboard_fab2_lib.baseboard_fab2(sch_1):page145_i100@mstr_controller.ast1250(chips)!AST1250_BGA-IC,G85138-002!!!F4190!SRST_N!!!!
S!UART_BMC_TXD5!U9F4!H5!@baseboard_fab2_lib.baseboard_fab2(sch_1):page145_i100@mstr_controller.ast1250(chips)!AST1250_BGA-IC,G85138-002!!!F4190!TXD5!!!!
S!FM_BMC_NMI_N!U9F4!AA22!@baseboard_fab2_lib.baseboard_fab2(sch_1):page146_i1@mstr_controller.ast1250(chips)!AST1250_BGA-IC,G85138-002!!!F4189!GPIOG6_FLBUSY_N!!!!
S!IRQ_DIMM_SAVE_LVT3_N!U9F4!U18!@baseboard_fab2_lib.baseboard_fab2(sch_1):page146_i1@mstr_controller.ast1250(chips)!AST1250_BGA-IC,G85138-002!!!F4189!GPIOG7_FLWP_N!!!!
S!LED_POSTCODE_0!U9F4!A8!@baseboard_fab2_lib.baseboard_fab2(sch_1):page146_i1@mstr_controller.ast1250(chips)!AST1250_BGA-IC,G85138-002!!!F4189!GPIOH0_ROMD8_NCTS6!!!!
S!LED_POSTCODE_1!U9F4!C7!@baseboard_fab2_lib.baseboard_fab2(sch_1):page146_i1@mstr_controller.ast1250(chips)!AST1250_BGA-IC,G85138-002!!!F4189!GPIOH1_ROMD9_NDCD6!!!!
S!LED_POSTCODE_2!U9F4!B7!@baseboard_fab2_lib.baseboard_fab2(sch_1):page146_i1@mstr_controller.ast1250(chips)!AST1250_BGA-IC,G85138-002!!!F4189!GPIOH2_ROMD10_NDSR6!!!!
S!LED_POSTCODE_3!U9F4!A7!@baseboard_fab2_lib.baseboard_fab2(sch_1):page146_i1@mstr_controller.ast1250(chips)!AST1250_BGA-IC,G85138-002!!!F4189!GPIOH3_ROMD11_NRI6!!!!
S!LED_POSTCODE_4!U9F4!D7!@baseboard_fab2_lib.baseboard_fab2(sch_1):page146_i1@mstr_controller.ast1250(chips)!AST1250_BGA-IC,G85138-002!!!F4189!GPIOH4_ROMD12_NDTR6!!!!
S!LED_POSTCODE_5!U9F4!B6!@baseboard_fab2_lib.baseboard_fab2(sch_1):page146_i1@mstr_controller.ast1250(chips)!AST1250_BGA-IC,G85138-002!!!F4189!GPIOH5_ROMD13_NRTS6!!!!
S!LED_POSTCODE_6!U9F4!A6!@baseboard_fab2_lib.baseboard_fab2(sch_1):page146_i1@mstr_controller.ast1250(chips)!AST1250_BGA-IC,G85138-002!!!F4189!GPIOH6_ROMD14_TXD6!!!!
S!LED_POSTCODE_7!U9F4!E7!@baseboard_fab2_lib.baseboard_fab2(sch_1):page146_i1@mstr_controller.ast1250(chips)!AST1250_BGA-IC,G85138-002!!!F4189!GPIOH7_ROMD15_RXD6!!!!
S!FM_MB_SLOT_ID0!U9F4!V20!@baseboard_fab2_lib.baseboard_fab2(sch_1):page146_i1@mstr_controller.ast1250(chips)!AST1250_BGA-IC,G85138-002!!!F4189!GPIOR0_ROMCS1_N!!!!
S!FM_MB_SLOT_ID1!U9F4!W21!@baseboard_fab2_lib.baseboard_fab2(sch_1):page146_i1@mstr_controller.ast1250(chips)!AST1250_BGA-IC,G85138-002!!!F4189!GPIOR1_ROMCS2_N!!!!
S!FM_MB_SLOT_ID2!U9F4!Y22!@baseboard_fab2_lib.baseboard_fab2(sch_1):page146_i1@mstr_controller.ast1250(chips)!AST1250_BGA-IC,G85138-002!!!F4189!GPIOR2_ROMCS3_N!!!!
S!FM_FLASH_DESC_OVERRIDE_R!U9F4!U19!@baseboard_fab2_lib.baseboard_fab2(sch_1):page146_i1@mstr_controller.ast1250(chips)!AST1250_BGA-IC,G85138-002!!!F4189!GPIOR3_ROMCS4_N!!!!
S!FM_THROTTLE_N!U9F4!V21!@baseboard_fab2_lib.baseboard_fab2(sch_1):page146_i1@mstr_controller.ast1250(chips)!AST1250_BGA-IC,G85138-002!!!F4189!GPIOR4_ROMA24_VPOR6!!!!
S!TP_GPIOR5_ROMA25_VPOR7!U9F4!W22!@baseboard_fab2_lib.baseboard_fab2(sch_1):page146_i1@mstr_controller.ast1250(chips)!AST1250_BGA-IC,G85138-002!!!F4189!GPIOR5_ROMA25_VPOR7!!!!
S!FM_CPU0_SKTOCC_LVT3_N!U9F4!C6!@baseboard_fab2_lib.baseboard_fab2(sch_1):page146_i1@mstr_controller.ast1250(chips)!AST1250_BGA-IC,G85138-002!!!F4189!GPIOR6_MDC1!!!!
S!FM_CPU1_SKTOCC_LVT3_N!U9F4!A5!@baseboard_fab2_lib.baseboard_fab2(sch_1):page146_i1@mstr_controller.ast1250(chips)!AST1250_BGA-IC,G85138-002!!!F4189!GPIOR7_MDIO1!!!!
S!FM_ROMA<10>!U9F4!M21!@baseboard_fab2_lib.baseboard_fab2(sch_1):page146_i1@mstr_controller.ast1250(chips)!AST1250_BGA-IC,G85138-002!!!F4189!ROMA10_GPIOAA0_VPOG0!!!!
S!FM_ROMA<11>!U9F4!M22!@baseboard_fab2_lib.baseboard_fab2(sch_1):page146_i1@mstr_controller.ast1250(chips)!AST1250_BGA-IC,G85138-002!!!F4189!ROMA11_GPIOAA1_VPOG1!!!!
S!FM_ROMA<12>!U9F4!L18!@baseboard_fab2_lib.baseboard_fab2(sch_1):page146_i1@mstr_controller.ast1250(chips)!AST1250_BGA-IC,G85138-002!!!F4189!ROMA12_GPIOAA2_VPOG2!!!!
S!FM_ROMA<13>!U9F4!L19!@baseboard_fab2_lib.baseboard_fab2(sch_1):page146_i1@mstr_controller.ast1250(chips)!AST1250_BGA-IC,G85138-002!!!F4189!ROMA13_GPIOAA3_VPOG3!!!!
S!FM_ROMA<14>!U9F4!L20!@baseboard_fab2_lib.baseboard_fab2(sch_1):page146_i1@mstr_controller.ast1250(chips)!AST1250_BGA-IC,G85138-002!!!F4189!ROMA14_GPIOAA4_VPOG4!!!!
S!FM_ROMA<15>!U9F4!L21!@baseboard_fab2_lib.baseboard_fab2(sch_1):page146_i1@mstr_controller.ast1250(chips)!AST1250_BGA-IC,G85138-002!!!F4189!ROMA15_GPIOAA5_VPOG5!!!!
S!FM_ROMA<16>!U9F4!T18!@baseboard_fab2_lib.baseboard_fab2(sch_1):page146_i1@mstr_controller.ast1250(chips)!AST1250_BGA-IC,G85138-002!!!F4189!ROMA16_GPIOAA6_VPOG6!!!!
S!FM_ROMA<17>!U9F4!N18!@baseboard_fab2_lib.baseboard_fab2(sch_1):page146_i1@mstr_controller.ast1250(chips)!AST1250_BGA-IC,G85138-002!!!F4189!ROMA17_GPIOAA7_VPOG7!!!!
S!FM_ROMA<18>!U9F4!N19!@baseboard_fab2_lib.baseboard_fab2(sch_1):page146_i1@mstr_controller.ast1250(chips)!AST1250_BGA-IC,G85138-002!!!F4189!ROMA18_GPIOAB0_VPOR0!!!!
S!FM_ROMA<19>!U9F4!M18!@baseboard_fab2_lib.baseboard_fab2(sch_1):page146_i1@mstr_controller.ast1250(chips)!AST1250_BGA-IC,G85138-002!!!F4189!ROMA19_GPIOAB1_VPOR1!!!!
S!FM_ROMA<20>!U9F4!N22!@baseboard_fab2_lib.baseboard_fab2(sch_1):page146_i1@mstr_controller.ast1250(chips)!AST1250_BGA-IC,G85138-002!!!F4189!ROMA20_GPIOAB2_VPOR2!!!!
S!FM_ROMA<21>!U9F4!N20!@baseboard_fab2_lib.baseboard_fab2(sch_1):page146_i1@mstr_controller.ast1250(chips)!AST1250_BGA-IC,G85138-002!!!F4189!ROMA21_GPIOAB3_VPOR3!!!!
S!FM_ROMA<22>!U9F4!L22!@baseboard_fab2_lib.baseboard_fab2(sch_1):page146_i1@mstr_controller.ast1250(chips)!AST1250_BGA-IC,G85138-002!!!F4189!ROMA22_GPIOS6_VPOR4!!!!
S!FM_ROMA<23>!U9F4!K18!@baseboard_fab2_lib.baseboard_fab2(sch_1):page146_i1@mstr_controller.ast1250(chips)!AST1250_BGA-IC,G85138-002!!!F4189!ROMA23_GPIOS7_VPOR5!!!!
S!FM_ROMA<2>!U9F4!R22!@baseboard_fab2_lib.baseboard_fab2(sch_1):page146_i1@mstr_controller.ast1250(chips)!AST1250_BGA-IC,G85138-002!!!F4189!ROMA2_GPIOZ0_VPOB0!!!!
S!FM_ROMA<3>!U9F4!P18!@baseboard_fab2_lib.baseboard_fab2(sch_1):page146_i1@mstr_controller.ast1250(chips)!AST1250_BGA-IC,G85138-002!!!F4189!ROMA3_GPIOZ1_VPOB1!!!!
S!FM_ROMA<4>!U9F4!P19!@baseboard_fab2_lib.baseboard_fab2(sch_1):page146_i1@mstr_controller.ast1250(chips)!AST1250_BGA-IC,G85138-002!!!F4189!ROMA4_GPIOZ2_VPOB2!!!!
S!FM_ROMA<5>!U9F4!P20!@baseboard_fab2_lib.baseboard_fab2(sch_1):page146_i1@mstr_controller.ast1250(chips)!AST1250_BGA-IC,G85138-002!!!F4189!ROMA5_GPIOZ3_VPOB3!!!!
S!FM_ROMA<6>!U9F4!P21!@baseboard_fab2_lib.baseboard_fab2(sch_1):page146_i1@mstr_controller.ast1250(chips)!AST1250_BGA-IC,G85138-002!!!F4189!ROMA6_GPIOZ4_VPOB4!!!!
S!FM_ROMA<7>!U9F4!P22!@baseboard_fab2_lib.baseboard_fab2(sch_1):page146_i1@mstr_controller.ast1250(chips)!AST1250_BGA-IC,G85138-002!!!F4189!ROMA7_GPIOZ5_VPOB5!!!!
S!FM_ROMA<8>!U9F4!M19!@baseboard_fab2_lib.baseboard_fab2(sch_1):page146_i1@mstr_controller.ast1250(chips)!AST1250_BGA-IC,G85138-002!!!F4189!ROMA8_GPIOZ6_VPOB6!!!!
S!FM_ROMA<9>!U9F4!M20!@baseboard_fab2_lib.baseboard_fab2(sch_1):page146_i1@mstr_controller.ast1250(chips)!AST1250_BGA-IC,G85138-002!!!F4189!ROMA9_GPIOZ7_VPOB7!!!!
S!FM_ROMA<0>!U9F4!R20!@baseboard_fab2_lib.baseboard_fab2(sch_1):page146_i1@mstr_controller.ast1250(chips)!AST1250_BGA-IC,G85138-002!!!F4189!ROMA(0)!!!!
S!FM_ROMA<1>!U9F4!R21!@baseboard_fab2_lib.baseboard_fab2(sch_1):page146_i1@mstr_controller.ast1250(chips)!AST1250_BGA-IC,G85138-002!!!F4189!ROMA(1)!!!!
S!SPI_BMC_BT_CS_R_N!U9F4!R19!@baseboard_fab2_lib.baseboard_fab2(sch_1):page146_i1@mstr_controller.ast1250(chips)!AST1250_BGA-IC,G85138-002!!!F4189!ROMCS0_N!!!!
S!SPI_BMC_BT_CLK_R!U9F4!T22!@baseboard_fab2_lib.baseboard_fab2(sch_1):page146_i1@mstr_controller.ast1250(chips)!AST1250_BGA-IC,G85138-002!!!F4189!ROMD0!!!!
S!SPI_BMC_BT_DO_R!U9F4!T21!@baseboard_fab2_lib.baseboard_fab2(sch_1):page146_i1@mstr_controller.ast1250(chips)!AST1250_BGA-IC,G85138-002!!!F4189!ROMD1!!!!
S!SPI_BMC_BT_DI!U9F4!T20!@baseboard_fab2_lib.baseboard_fab2(sch_1):page146_i1@mstr_controller.ast1250(chips)!AST1250_BGA-IC,G85138-002!!!F4189!ROMD2!!!!
S!TP_SPI_BMC_BT_D2!U9F4!U22!@baseboard_fab2_lib.baseboard_fab2(sch_1):page146_i1@mstr_controller.ast1250(chips)!AST1250_BGA-IC,G85138-002!!!F4189!ROMD3!!!!
S!FM_BOARD_REV_ID0!U9F4!U21!@baseboard_fab2_lib.baseboard_fab2(sch_1):page146_i1@mstr_controller.ast1250(chips)!AST1250_BGA-IC,G85138-002!!!F4189!ROMD4_GPIOS0_VPODE!!!!
S!FM_BOARD_REV_ID1!U9F4!T19!@baseboard_fab2_lib.baseboard_fab2(sch_1):page146_i1@mstr_controller.ast1250(chips)!AST1250_BGA-IC,G85138-002!!!F4189!ROMD5_GPIOS1_VPOHS!!!!
S!FM_BOARD_REV_ID2!U9F4!V22!@baseboard_fab2_lib.baseboard_fab2(sch_1):page146_i1@mstr_controller.ast1250(chips)!AST1250_BGA-IC,G85138-002!!!F4189!ROMD6_GPIOS2_VPOVS!!!!
S!FM_BIOS_MRC_DEBUG_MSG_DIS_N!U9F4!U20!@baseboard_fab2_lib.baseboard_fab2(sch_1):page146_i1@mstr_controller.ast1250(chips)!AST1250_BGA-IC,G85138-002!!!F4189!ROMD7_GPIOS3_VPOCLK!!!!
S!FM_SOL_UART_CH_SEL!U9F4!R18!@baseboard_fab2_lib.baseboard_fab2(sch_1):page146_i1@mstr_controller.ast1250(chips)!AST1250_BGA-IC,G85138-002!!!F4189!ROMOE_N_GPIOS4!!!!
S!FM_CPU_ERR2_LVT3_N!U9F4!N21!@baseboard_fab2_lib.baseboard_fab2(sch_1):page146_i1@mstr_controller.ast1250(chips)!AST1250_BGA-IC,G85138-002!!!F4189!ROMWE_N_GPIOS5!!!!
S!A_P3V3_SCALED!U9F4!L5!@baseboard_fab2_lib.baseboard_fab2(sch_1):page147_i1@mstr_controller.ast1250(chips)!AST1250_BGA-IC,G85138-002!!!F4188!ADC0_GPIW0!!!!
S!GND!U9F4!N5!@baseboard_fab2_lib.baseboard_fab2(sch_1):page147_i1@mstr_controller.ast1250(chips)!AST1250_BGA-IC,G85138-002!!!F4188!ADC10_GPIX2!!!!
S!GND!U9F4!N4!@baseboard_fab2_lib.baseboard_fab2(sch_1):page147_i1@mstr_controller.ast1250(chips)!AST1250_BGA-IC,G85138-002!!!F4188!ADC11_GPIX3!!!!
S!GND!U9F4!N3!@baseboard_fab2_lib.baseboard_fab2(sch_1):page147_i1@mstr_controller.ast1250(chips)!AST1250_BGA-IC,G85138-002!!!F4188!ADC12_GPIX4!!!!
S!GND!U9F4!N2!@baseboard_fab2_lib.baseboard_fab2(sch_1):page147_i1@mstr_controller.ast1250(chips)!AST1250_BGA-IC,G85138-002!!!F4188!ADC13_GPIX5!!!!
S!GND!U9F4!N1!@baseboard_fab2_lib.baseboard_fab2(sch_1):page147_i1@mstr_controller.ast1250(chips)!AST1250_BGA-IC,G85138-002!!!F4188!ADC14_GPIX6!!!!
S!GND!U9F4!P5!@baseboard_fab2_lib.baseboard_fab2(sch_1):page147_i1@mstr_controller.ast1250(chips)!AST1250_BGA-IC,G85138-002!!!F4188!ADC15_GPIX7!!!!
S!A_P5V_SCALED!U9F4!L4!@baseboard_fab2_lib.baseboard_fab2(sch_1):page147_i1@mstr_controller.ast1250(chips)!AST1250_BGA-IC,G85138-002!!!F4188!ADC1_GPIW1!!!!
S!A_P12V_STBY_SCALED!U9F4!L3!@baseboard_fab2_lib.baseboard_fab2(sch_1):page147_i1@mstr_controller.ast1250(chips)!AST1250_BGA-IC,G85138-002!!!F4188!ADC2_GPIW2!!!!
S!A_P1V05_STBY_PCH_SENSOR!U9F4!L2!@baseboard_fab2_lib.baseboard_fab2(sch_1):page147_i1@mstr_controller.ast1250(chips)!AST1250_BGA-IC,G85138-002!!!F4188!ADC3_GPIW3!!!!
S!A_PVNN_STBY_PCH_SENSOR!U9F4!L1!@baseboard_fab2_lib.baseboard_fab2(sch_1):page147_i1@mstr_controller.ast1250(chips)!AST1250_BGA-IC,G85138-002!!!F4188!ADC4_GPIW4!!!!
S!A_P3V3_STBY_SCALED!U9F4!M5!@baseboard_fab2_lib.baseboard_fab2(sch_1):page147_i1@mstr_controller.ast1250(chips)!AST1250_BGA-IC,G85138-002!!!F4188!ADC5_GPIW5!!!!
S!A_P5V_STBY_SCALED!U9F4!M4!@baseboard_fab2_lib.baseboard_fab2(sch_1):page147_i1@mstr_controller.ast1250(chips)!AST1250_BGA-IC,G85138-002!!!F4188!ADC6_GPIW6!!!!
S!A_P3V_BAT_SCALED!U9F4!M3!@baseboard_fab2_lib.baseboard_fab2(sch_1):page147_i1@mstr_controller.ast1250(chips)!AST1250_BGA-IC,G85138-002!!!F4188!ADC7_GPIW7!!!!
S!GND!U9F4!M2!@baseboard_fab2_lib.baseboard_fab2(sch_1):page147_i1@mstr_controller.ast1250(chips)!AST1250_BGA-IC,G85138-002!!!F4188!ADC8_GPIX0!!!!
S!GND!U9F4!M1!@baseboard_fab2_lib.baseboard_fab2(sch_1):page147_i1@mstr_controller.ast1250(chips)!AST1250_BGA-IC,G85138-002!!!F4188!ADC9_GPIX1!!!!
S!PD_ADCREXT!U9F4!P2!@baseboard_fab2_lib.baseboard_fab2(sch_1):page147_i1@mstr_controller.ast1250(chips)!AST1250_BGA-IC,G85138-002!!!F4188!ADCREXT!!!!
S!P3V3_STBY_BMC_ADCVREFN!U9F4!K2!@baseboard_fab2_lib.baseboard_fab2(sch_1):page147_i1@mstr_controller.ast1250(chips)!AST1250_BGA-IC,G85138-002!!!F4188!ADCVREFN!!!!
S!P3V3_STBY_BMC_ADCVREFP!U9F4!K1!@baseboard_fab2_lib.baseboard_fab2(sch_1):page147_i1@mstr_controller.ast1250(chips)!AST1250_BGA-IC,G85138-002!!!F4188!ADCVREFP!!!!
S!FM_FORCE_ADR_N!U9F4!A3!@baseboard_fab2_lib.baseboard_fab2(sch_1):page147_i1@mstr_controller.ast1250(chips)!AST1250_BGA-IC,G85138-002!!!F4188!GPIOA6_TIMER7_MDC2!!!!
S!FM_UV_ADR_TRIGGER_EN!U9F4!D5!@baseboard_fab2_lib.baseboard_fab2(sch_1):page147_i1@mstr_controller.ast1250(chips)!AST1250_BGA-IC,G85138-002!!!F4188!GPIOA7_TIMER8_MDIO2!!!!
S!FAN_PWM_OUT_SYS0!U9F4!W4!@baseboard_fab2_lib.baseboard_fab2(sch_1):page147_i1@mstr_controller.ast1250(chips)!AST1250_BGA-IC,G85138-002!!!F4188!GPION0_PWM0_VPIG0!!!!
S!FAN_PWM_OUT_SYS1!U9F4!Y3!@baseboard_fab2_lib.baseboard_fab2(sch_1):page147_i1@mstr_controller.ast1250(chips)!AST1250_BGA-IC,G85138-002!!!F4188!GPION1_PWM1_VPIG1!!!!
S!FM_BIOS_PREFRB2_GOOD!U9F4!AA2!@baseboard_fab2_lib.baseboard_fab2(sch_1):page147_i1@mstr_controller.ast1250(chips)!AST1250_BGA-IC,G85138-002!!!F4188!GPION2_PWM2_VPIG2!!!!
S!FM_CPU_MSMI_LVT3_N!U9F4!AB1!@baseboard_fab2_lib.baseboard_fab2(sch_1):page147_i1@mstr_controller.ast1250(chips)!AST1250_BGA-IC,G85138-002!!!F4188!GPION3_PWM3_VPIG3!!!!
S!FM_BACKUP_BIOS_SEL_N!U9F4!W5!@baseboard_fab2_lib.baseboard_fab2(sch_1):page147_i1@mstr_controller.ast1250(chips)!AST1250_BGA-IC,G85138-002!!!F4188!GPION4_PWM4_VPIG4!!!!
S!FM_BIOS_SPI_BMC_CTRL!U9F4!Y4!@baseboard_fab2_lib.baseboard_fab2(sch_1):page147_i1@mstr_controller.ast1250(chips)!AST1250_BGA-IC,G85138-002!!!F4188!GPION5_PWM5_VPIG5!!!!
S!FM_UARTSW_LSB_N!U9F4!AA3!@baseboard_fab2_lib.baseboard_fab2(sch_1):page147_i1@mstr_controller.ast1250(chips)!AST1250_BGA-IC,G85138-002!!!F4188!GPION6_PWM6_VPIG6!!!!
S!FM_UARTSW_MSB_N!U9F4!AB2!@baseboard_fab2_lib.baseboard_fab2(sch_1):page147_i1@mstr_controller.ast1250(chips)!AST1250_BGA-IC,G85138-002!!!F4188!GPION7_PWM7_VPIG7!!!!
S!FAN_TACH0!U9F4!V6!@baseboard_fab2_lib.baseboard_fab2(sch_1):page147_i1@mstr_controller.ast1250(chips)!AST1250_BGA-IC,G85138-002!!!F4188!GPIOO0_TACH0_VPIG8!!!!
S!FAN_TACH1!U9F4!Y5!@baseboard_fab2_lib.baseboard_fab2(sch_1):page147_i1@mstr_controller.ast1250(chips)!AST1250_BGA-IC,G85138-002!!!F4188!GPIOO1_TACH1_VPIG9!!!!
S!FAN_TACH2!U9F4!AA4!@baseboard_fab2_lib.baseboard_fab2(sch_1):page147_i1@mstr_controller.ast1250(chips)!AST1250_BGA-IC,G85138-002!!!F4188!GPIOO2_TACH2_VPIR0!!!!
S!FAN_TACH3!U9F4!AB3!@baseboard_fab2_lib.baseboard_fab2(sch_1):page147_i1@mstr_controller.ast1250(chips)!AST1250_BGA-IC,G85138-002!!!F4188!GPIOO3_TACH3_VPIR1!!!!
S!FM_MP_PS_FAIL_N!U9F4!W6!@baseboard_fab2_lib.baseboard_fab2(sch_1):page147_i1@mstr_controller.ast1250(chips)!AST1250_BGA-IC,G85138-002!!!F4188!GPIOO4_TACH4_VPIR2!!!!
S!FM_MP_PS_REDUNDANT_LOST_N!U9F4!AA5!@baseboard_fab2_lib.baseboard_fab2(sch_1):page147_i1@mstr_controller.ast1250(chips)!AST1250_BGA-IC,G85138-002!!!F4188!GPIOO5_TACH5_VPIR3!!!!
S!FM_XRC_PRESENT_N!U9F4!AB4!@baseboard_fab2_lib.baseboard_fab2(sch_1):page147_i1@mstr_controller.ast1250(chips)!AST1250_BGA-IC,G85138-002!!!F4188!GPIOO6_TACH6_VPIR4!!!!
S!FM_XRC_READY_N!U9F4!V7!@baseboard_fab2_lib.baseboard_fab2(sch_1):page147_i1@mstr_controller.ast1250(chips)!AST1250_BGA-IC,G85138-002!!!F4188!GPIOO7_TACH7_VPIR5!!!!
S!FM_BOARD_SKU_ID0!U9F4!Y6!@baseboard_fab2_lib.baseboard_fab2(sch_1):page147_i1@mstr_controller.ast1250(chips)!AST1250_BGA-IC,G85138-002!!!F4188!GPIOP0_TACH8_VPIR6!!!!
S!FM_BOARD_SKU_ID1!U9F4!AB5!@baseboard_fab2_lib.baseboard_fab2(sch_1):page147_i1@mstr_controller.ast1250(chips)!AST1250_BGA-IC,G85138-002!!!F4188!GPIOP1_TACH9_VPIR7!!!!
S!FM_BOARD_SKU_ID2!U9F4!W7!@baseboard_fab2_lib.baseboard_fab2(sch_1):page147_i1@mstr_controller.ast1250(chips)!AST1250_BGA-IC,G85138-002!!!F4188!GPIOP2_TACH10_VPIR8!!!!
S!FM_BOARD_SKU_ID3!U9F4!AA6!@baseboard_fab2_lib.baseboard_fab2(sch_1):page147_i1@mstr_controller.ast1250(chips)!AST1250_BGA-IC,G85138-002!!!F4188!GPIOP3_TACH11_VPIR9!!!!
S!IRQ_PVCCIN_CPU0_VRHOT_LVC3_N!U9F4!AB6!@baseboard_fab2_lib.baseboard_fab2(sch_1):page147_i1@mstr_controller.ast1250(chips)!AST1250_BGA-IC,G85138-002!!!F4188!GPIOP4_TACH12!!!!
S!IRQ_PVCCIN_CPU1_VRHOT_LVC3_N!U9F4!Y7!@baseboard_fab2_lib.baseboard_fab2(sch_1):page147_i1@mstr_controller.ast1250(chips)!AST1250_BGA-IC,G85138-002!!!F4188!GPIOP5_TACH13!!!!
S!FM_CPU0_PROCHOT_LVT3_BMC_N!U9F4!AA7!@baseboard_fab2_lib.baseboard_fab2(sch_1):page147_i1@mstr_controller.ast1250(chips)!AST1250_BGA-IC,G85138-002!!!F4188!GPIOP6_TACH14_BMCINT!!!!
S!FM_CPU1_PROCHOT_LVT3_BMC_N!U9F4!AB7!@baseboard_fab2_lib.baseboard_fab2(sch_1):page147_i1@mstr_controller.ast1250(chips)!AST1250_BGA-IC,G85138-002!!!F4188!GPIOP7_TACH15_FLACK!!!!
S!CLK_50M_CKMNG_BMC_1!U9F4!E11!@baseboard_fab2_lib.baseboard_fab2(sch_1):page147_i1@mstr_controller.ast1250(chips)!AST1250_BGA-IC,G85138-002!!!F4188!RGMII1RXCK_RMII1RCLK_GPIOU4!!!!
S!GND!U9F4!D11!@baseboard_fab2_lib.baseboard_fab2(sch_1):page147_i1@mstr_controller.ast1250(chips)!AST1250_BGA-IC,G85138-002!!!F4188!RGMII1RXCTL_GPIOU5!!!!
S!RMII_BMC_OCP_RXD0!U9F4!C11!@baseboard_fab2_lib.baseboard_fab2(sch_1):page147_i1@mstr_controller.ast1250(chips)!AST1250_BGA-IC,G85138-002!!!F4188!RGMII1RXD0_RMII1RXD0_GPIOU6!!!!
S!RMII_BMC_OCP_RXD1!U9F4!B11!@baseboard_fab2_lib.baseboard_fab2(sch_1):page147_i1@mstr_controller.ast1250(chips)!AST1250_BGA-IC,G85138-002!!!F4188!RGMII1RXD1_RMII1RXD1_GPIOU7!!!!
S!RMII_BMC_OCP_CRSDV!U9F4!A11!@baseboard_fab2_lib.baseboard_fab2(sch_1):page147_i1@mstr_controller.ast1250(chips)!AST1250_BGA-IC,G85138-002!!!F4188!RGMII1RXD2_RMII1CRSDV_GPIOV0!!!!
S!RMII_BMC_OCP_RXER!U9F4!E10!@baseboard_fab2_lib.baseboard_fab2(sch_1):page147_i1@mstr_controller.ast1250(chips)!AST1250_BGA-IC,G85138-002!!!F4188!RGMII1RXD3_RMII1RXER_GPIOV1!!!!
S!RMII_BMC_OCP_TXEN_R!U9F4!A12!@baseboard_fab2_lib.baseboard_fab2(sch_1):page147_i1@mstr_controller.ast1250(chips)!AST1250_BGA-IC,G85138-002!!!F4188!RGMII1TXCK_RMII1TXEN_GPIOT0!!!!
S!TP_RGMII2TXCTL_GPIOT7!U9F4!B12!@baseboard_fab2_lib.baseboard_fab2(sch_1):page147_i1@mstr_controller.ast1250(chips)!AST1250_BGA-IC,G85138-002!!!F4188!RGMII1TXCTL_GPIOT1!!!!
S!RMII_BMC_OCP_TXD0_R!U9F4!C12!@baseboard_fab2_lib.baseboard_fab2(sch_1):page147_i1@mstr_controller.ast1250(chips)!AST1250_BGA-IC,G85138-002!!!F4188!RGMII1TXD0_RMII1TXD0_GPIOT2!!!!
S!RMII_BMC_OCP_TXD1_R!U9F4!D12!@baseboard_fab2_lib.baseboard_fab2(sch_1):page147_i1@mstr_controller.ast1250(chips)!AST1250_BGA-IC,G85138-002!!!F4188!RGMII1TXD1_RMII1TXD1_GPIOT3!!!!
S!TP_RGMII2TXD2_GPIOT4!U9F4!E12!@baseboard_fab2_lib.baseboard_fab2(sch_1):page147_i1@mstr_controller.ast1250(chips)!AST1250_BGA-IC,G85138-002!!!F4188!RGMII1TXD2_GPIOT4!!!!
S!TP_RGMII2TXD3_GPIOT5!U9F4!A13!@baseboard_fab2_lib.baseboard_fab2(sch_1):page147_i1@mstr_controller.ast1250(chips)!AST1250_BGA-IC,G85138-002!!!F4188!RGMII1TXD3_GPIOT5!!!!
S!CLK_50M_CKMNG_BMC_2!U9F4!C9!@baseboard_fab2_lib.baseboard_fab2(sch_1):page147_i1@mstr_controller.ast1250(chips)!AST1250_BGA-IC,G85138-002!!!F4188!RGMII2RXCK_RMII2RCLK_GPIOV2!!!!
S!GND!U9F4!B9!@baseboard_fab2_lib.baseboard_fab2(sch_1):page147_i1@mstr_controller.ast1250(chips)!AST1250_BGA-IC,G85138-002!!!F4188!RGMII2RXCTL_GPIOV3!!!!
S!RMII_SPRNGVLLE_BMC_PCH_RXD0!U9F4!A9!@baseboard_fab2_lib.baseboard_fab2(sch_1):page147_i1@mstr_controller.ast1250(chips)!AST1250_BGA-IC,G85138-002!!!F4188!RGMII2RXD0_RMII2RXD0_GPIOV4!!!!
S!RMII_SPRNGVLLE_BMC_PCH_RXD1!U9F4!E8!@baseboard_fab2_lib.baseboard_fab2(sch_1):page147_i1@mstr_controller.ast1250(chips)!AST1250_BGA-IC,G85138-002!!!F4188!RGMII2RXD1_RMII2RXD1_GPIOV5!!!!
S!RMII_BMC_PCH_SPRNGVLLE_CRSDV!U9F4!D8!@baseboard_fab2_lib.baseboard_fab2(sch_1):page147_i1@mstr_controller.ast1250(chips)!AST1250_BGA-IC,G85138-002!!!F4188!RGMII2RXD2_RMII2CRSDV_GPIOV6!!!!
S!RMII_BMC_PCH_SPRNGVLLE_RXER!U9F4!C8!@baseboard_fab2_lib.baseboard_fab2(sch_1):page147_i1@mstr_controller.ast1250(chips)!AST1250_BGA-IC,G85138-002!!!F4188!RGMII2RXD3_RMII2RXER_GPIOV7!!!!
S!RMII_BMC_SPRNGVLLE_TXEN_R!U9F4!D9!@baseboard_fab2_lib.baseboard_fab2(sch_1):page147_i1@mstr_controller.ast1250(chips)!AST1250_BGA-IC,G85138-002!!!F4188!RGMII2TXCK_RMII2TXEN_GPIOT6!!!!
S!TP_RGMII1TXCTL_GPIOT1!U9F4!E9!@baseboard_fab2_lib.baseboard_fab2(sch_1):page147_i1@mstr_controller.ast1250(chips)!AST1250_BGA-IC,G85138-002!!!F4188!RGMII2TXCTL_GPIOT7!!!!
S!RMII_BMC_PCH_SPRNGVLLE_TXD0_R!U9F4!A10!@baseboard_fab2_lib.baseboard_fab2(sch_1):page147_i1@mstr_controller.ast1250(chips)!AST1250_BGA-IC,G85138-002!!!F4188!RGMII2TXD0_RMII2TXD0_GPIOU0!!!!
S!RMII_BMC_PCH_SPRNGVLLE_TXD1_R!U9F4!B10!@baseboard_fab2_lib.baseboard_fab2(sch_1):page147_i1@mstr_controller.ast1250(chips)!AST1250_BGA-IC,G85138-002!!!F4188!RGMII2TXD1_RMII2TXD1_GPIOU1!!!!
S!TP_RGMII1TXD2_GPIOT4!U9F4!C10!@baseboard_fab2_lib.baseboard_fab2(sch_1):page147_i1@mstr_controller.ast1250(chips)!AST1250_BGA-IC,G85138-002!!!F4188!RGMII2TXD2_GPIOU2!!!!
S!TP_RGMII1TXD3_GPIOT5!U9F4!D10!@baseboard_fab2_lib.baseboard_fab2(sch_1):page147_i1@mstr_controller.ast1250(chips)!AST1250_BGA-IC,G85138-002!!!F4188!RGMII2TXD3_GPIOU3!!!!
S!GND!U9F4!B8!@baseboard_fab2_lib.baseboard_fab2(sch_1):page147_i1@mstr_controller.ast1250(chips)!AST1250_BGA-IC,G85138-002!!!F4188!RGMIICK!!!!
S!P3V3_STBY_BMC_ADCAV33!U9F4!P3!@baseboard_fab2_lib.baseboard_fab2(sch_1):page148_i11@mstr_controller.ast1250(chips)!AST1250_BGA-IC,G85138-002!!!F4187!ADCAV33!!!!
S!GND!U9F4!P4!@baseboard_fab2_lib.baseboard_fab2(sch_1):page148_i11@mstr_controller.ast1250(chips)!AST1250_BGA-IC,G85138-002!!!F4187!ADCAVSS!!!!
S!P3V3_STBY!U9F4!P1!@baseboard_fab2_lib.baseboard_fab2(sch_1):page148_i11@mstr_controller.ast1250(chips)!AST1250_BGA-IC,G85138-002!!!F4187!DACAV33!!!!
S!GND!U9F4!R5!@baseboard_fab2_lib.baseboard_fab2(sch_1):page148_i11@mstr_controller.ast1250(chips)!AST1250_BGA-IC,G85138-002!!!F4187!DACAVSS!!!!
S!P3V3_STBY!U9F4!T3!@baseboard_fab2_lib.baseboard_fab2(sch_1):page148_i11@mstr_controller.ast1250(chips)!AST1250_BGA-IC,G85138-002!!!F4187!DACDV33!!!!
S!GND!U9F4!J10!@baseboard_fab2_lib.baseboard_fab2(sch_1):page148_i11@mstr_controller.ast1250(chips)!AST1250_BGA-IC,G85138-002!!!F4187!GND(0)!!!!
S!GND!U9F4!K14!@baseboard_fab2_lib.baseboard_fab2(sch_1):page148_i11@mstr_controller.ast1250(chips)!AST1250_BGA-IC,G85138-002!!!F4187!GND(10)!!!!
S!GND!U9F4!K9!@baseboard_fab2_lib.baseboard_fab2(sch_1):page148_i11@mstr_controller.ast1250(chips)!AST1250_BGA-IC,G85138-002!!!F4187!GND(11)!!!!
S!GND!U9F4!L10!@baseboard_fab2_lib.baseboard_fab2(sch_1):page148_i11@mstr_controller.ast1250(chips)!AST1250_BGA-IC,G85138-002!!!F4187!GND(12)!!!!
S!GND!U9F4!L11!@baseboard_fab2_lib.baseboard_fab2(sch_1):page148_i11@mstr_controller.ast1250(chips)!AST1250_BGA-IC,G85138-002!!!F4187!GND(13)!!!!
S!GND!U9F4!L12!@baseboard_fab2_lib.baseboard_fab2(sch_1):page148_i11@mstr_controller.ast1250(chips)!AST1250_BGA-IC,G85138-002!!!F4187!GND(14)!!!!
S!GND!U9F4!L13!@baseboard_fab2_lib.baseboard_fab2(sch_1):page148_i11@mstr_controller.ast1250(chips)!AST1250_BGA-IC,G85138-002!!!F4187!GND(15)!!!!
S!GND!U9F4!L14!@baseboard_fab2_lib.baseboard_fab2(sch_1):page148_i11@mstr_controller.ast1250(chips)!AST1250_BGA-IC,G85138-002!!!F4187!GND(16)!!!!
S!GND!U9F4!L9!@baseboard_fab2_lib.baseboard_fab2(sch_1):page148_i11@mstr_controller.ast1250(chips)!AST1250_BGA-IC,G85138-002!!!F4187!GND(17)!!!!
S!GND!U9F4!M10!@baseboard_fab2_lib.baseboard_fab2(sch_1):page148_i11@mstr_controller.ast1250(chips)!AST1250_BGA-IC,G85138-002!!!F4187!GND(18)!!!!
S!GND!U9F4!M11!@baseboard_fab2_lib.baseboard_fab2(sch_1):page148_i11@mstr_controller.ast1250(chips)!AST1250_BGA-IC,G85138-002!!!F4187!GND(19)!!!!
S!GND!U9F4!J11!@baseboard_fab2_lib.baseboard_fab2(sch_1):page148_i11@mstr_controller.ast1250(chips)!AST1250_BGA-IC,G85138-002!!!F4187!GND(1)!!!!
S!GND!U9F4!M12!@baseboard_fab2_lib.baseboard_fab2(sch_1):page148_i11@mstr_controller.ast1250(chips)!AST1250_BGA-IC,G85138-002!!!F4187!GND(20)!!!!
S!GND!U9F4!M13!@baseboard_fab2_lib.baseboard_fab2(sch_1):page148_i11@mstr_controller.ast1250(chips)!AST1250_BGA-IC,G85138-002!!!F4187!GND(21)!!!!
S!GND!U9F4!M14!@baseboard_fab2_lib.baseboard_fab2(sch_1):page148_i11@mstr_controller.ast1250(chips)!AST1250_BGA-IC,G85138-002!!!F4187!GND(22)!!!!
S!GND!U9F4!M9!@baseboard_fab2_lib.baseboard_fab2(sch_1):page148_i11@mstr_controller.ast1250(chips)!AST1250_BGA-IC,G85138-002!!!F4187!GND(23)!!!!
S!GND!U9F4!N10!@baseboard_fab2_lib.baseboard_fab2(sch_1):page148_i11@mstr_controller.ast1250(chips)!AST1250_BGA-IC,G85138-002!!!F4187!GND(24)!!!!
S!GND!U9F4!N11!@baseboard_fab2_lib.baseboard_fab2(sch_1):page148_i11@mstr_controller.ast1250(chips)!AST1250_BGA-IC,G85138-002!!!F4187!GND(25)!!!!
S!GND!U9F4!N12!@baseboard_fab2_lib.baseboard_fab2(sch_1):page148_i11@mstr_controller.ast1250(chips)!AST1250_BGA-IC,G85138-002!!!F4187!GND(26)!!!!
S!GND!U9F4!N13!@baseboard_fab2_lib.baseboard_fab2(sch_1):page148_i11@mstr_controller.ast1250(chips)!AST1250_BGA-IC,G85138-002!!!F4187!GND(27)!!!!
S!GND!U9F4!N14!@baseboard_fab2_lib.baseboard_fab2(sch_1):page148_i11@mstr_controller.ast1250(chips)!AST1250_BGA-IC,G85138-002!!!F4187!GND(28)!!!!
S!GND!U9F4!N9!@baseboard_fab2_lib.baseboard_fab2(sch_1):page148_i11@mstr_controller.ast1250(chips)!AST1250_BGA-IC,G85138-002!!!F4187!GND(29)!!!!
S!GND!U9F4!J12!@baseboard_fab2_lib.baseboard_fab2(sch_1):page148_i11@mstr_controller.ast1250(chips)!AST1250_BGA-IC,G85138-002!!!F4187!GND(2)!!!!
S!GND!U9F4!P10!@baseboard_fab2_lib.baseboard_fab2(sch_1):page148_i11@mstr_controller.ast1250(chips)!AST1250_BGA-IC,G85138-002!!!F4187!GND(30)!!!!
S!GND!U9F4!P11!@baseboard_fab2_lib.baseboard_fab2(sch_1):page148_i11@mstr_controller.ast1250(chips)!AST1250_BGA-IC,G85138-002!!!F4187!GND(31)!!!!
S!GND!U9F4!P12!@baseboard_fab2_lib.baseboard_fab2(sch_1):page148_i11@mstr_controller.ast1250(chips)!AST1250_BGA-IC,G85138-002!!!F4187!GND(32)!!!!
S!GND!U9F4!P13!@baseboard_fab2_lib.baseboard_fab2(sch_1):page148_i11@mstr_controller.ast1250(chips)!AST1250_BGA-IC,G85138-002!!!F4187!GND(33)!!!!
S!GND!U9F4!P14!@baseboard_fab2_lib.baseboard_fab2(sch_1):page148_i11@mstr_controller.ast1250(chips)!AST1250_BGA-IC,G85138-002!!!F4187!GND(34)!!!!
S!GND!U9F4!P9!@baseboard_fab2_lib.baseboard_fab2(sch_1):page148_i11@mstr_controller.ast1250(chips)!AST1250_BGA-IC,G85138-002!!!F4187!GND(35)!!!!
S!GND!U9F4!J13!@baseboard_fab2_lib.baseboard_fab2(sch_1):page148_i11@mstr_controller.ast1250(chips)!AST1250_BGA-IC,G85138-002!!!F4187!GND(3)!!!!
S!GND!U9F4!J14!@baseboard_fab2_lib.baseboard_fab2(sch_1):page148_i11@mstr_controller.ast1250(chips)!AST1250_BGA-IC,G85138-002!!!F4187!GND(4)!!!!
S!GND!U9F4!J9!@baseboard_fab2_lib.baseboard_fab2(sch_1):page148_i11@mstr_controller.ast1250(chips)!AST1250_BGA-IC,G85138-002!!!F4187!GND(5)!!!!
S!GND!U9F4!K10!@baseboard_fab2_lib.baseboard_fab2(sch_1):page148_i11@mstr_controller.ast1250(chips)!AST1250_BGA-IC,G85138-002!!!F4187!GND(6)!!!!
S!GND!U9F4!K11!@baseboard_fab2_lib.baseboard_fab2(sch_1):page148_i11@mstr_controller.ast1250(chips)!AST1250_BGA-IC,G85138-002!!!F4187!GND(7)!!!!
S!GND!U9F4!K12!@baseboard_fab2_lib.baseboard_fab2(sch_1):page148_i11@mstr_controller.ast1250(chips)!AST1250_BGA-IC,G85138-002!!!F4187!GND(8)!!!!
S!GND!U9F4!K13!@baseboard_fab2_lib.baseboard_fab2(sch_1):page148_i11@mstr_controller.ast1250(chips)!AST1250_BGA-IC,G85138-002!!!F4187!GND(9)!!!!
S!P1V8_BMC_STBY_PCIEA!U9F4!C21!@baseboard_fab2_lib.baseboard_fab2(sch_1):page148_i11@mstr_controller.ast1250(chips)!AST1250_BGA-IC,G85138-002!!!F4187!GPIOY0_SIOS3_N!!!!
S!P1V8_BMC_STBY_PCIEA!U9F4!F20!@baseboard_fab2_lib.baseboard_fab2(sch_1):page148_i11@mstr_controller.ast1250(chips)!AST1250_BGA-IC,G85138-002!!!F4187!GPIOY1_SIOS5_N!!!!
S!P1V8_BMC_STBY_PCIE!U9F4!G20!@baseboard_fab2_lib.baseboard_fab2(sch_1):page148_i11@mstr_controller.ast1250(chips)!AST1250_BGA-IC,G85138-002!!!F4187!GPIOY2_SIOPWREQ_N!!!!
S!P3V3_STBY_BMC_HPLLAV33!U9F4!V17!@baseboard_fab2_lib.baseboard_fab2(sch_1):page148_i11@mstr_controller.ast1250(chips)!AST1250_BGA-IC,G85138-002!!!F4187!HPLLAV33!!!!
S!P1V26_BMC_STBY!U9F4!F14!@baseboard_fab2_lib.baseboard_fab2(sch_1):page148_i11@mstr_controller.ast1250(chips)!AST1250_BGA-IC,G85138-002!!!F4187!IV12D(0)!!!!
S!P1V26_BMC_STBY!U9F4!U13!@baseboard_fab2_lib.baseboard_fab2(sch_1):page148_i11@mstr_controller.ast1250(chips)!AST1250_BGA-IC,G85138-002!!!F4187!IV12D(10)!!!!
S!P1V26_BMC_STBY!U9F4!F15!@baseboard_fab2_lib.baseboard_fab2(sch_1):page148_i11@mstr_controller.ast1250(chips)!AST1250_BGA-IC,G85138-002!!!F4187!IV12D(1)!!!!
S!P1V26_BMC_STBY!U9F4!K6!@baseboard_fab2_lib.baseboard_fab2(sch_1):page148_i11@mstr_controller.ast1250(chips)!AST1250_BGA-IC,G85138-002!!!F4187!IV12D(2)!!!!
S!P1V26_BMC_STBY!U9F4!L6!@baseboard_fab2_lib.baseboard_fab2(sch_1):page148_i11@mstr_controller.ast1250(chips)!AST1250_BGA-IC,G85138-002!!!F4187!IV12D(3)!!!!
S!P1V26_BMC_STBY!U9F4!L17!@baseboard_fab2_lib.baseboard_fab2(sch_1):page148_i11@mstr_controller.ast1250(chips)!AST1250_BGA-IC,G85138-002!!!F4187!IV12D(4)!!!!
S!P1V26_BMC_STBY!U9F4!P6!@baseboard_fab2_lib.baseboard_fab2(sch_1):page148_i11@mstr_controller.ast1250(chips)!AST1250_BGA-IC,G85138-002!!!F4187!IV12D(5)!!!!
S!P1V26_BMC_STBY!U9F4!P17!@baseboard_fab2_lib.baseboard_fab2(sch_1):page148_i11@mstr_controller.ast1250(chips)!AST1250_BGA-IC,G85138-002!!!F4187!IV12D(6)!!!!
S!P1V26_BMC_STBY!U9F4!R6!@baseboard_fab2_lib.baseboard_fab2(sch_1):page148_i11@mstr_controller.ast1250(chips)!AST1250_BGA-IC,G85138-002!!!F4187!IV12D(7)!!!!
S!P1V26_BMC_STBY!U9F4!R17!@baseboard_fab2_lib.baseboard_fab2(sch_1):page148_i11@mstr_controller.ast1250(chips)!AST1250_BGA-IC,G85138-002!!!F4187!IV12D(8)!!!!
S!P1V26_BMC_STBY!U9F4!U12!@baseboard_fab2_lib.baseboard_fab2(sch_1):page148_i11@mstr_controller.ast1250(chips)!AST1250_BGA-IC,G85138-002!!!F4187!IV12D(9)!!!!
S!P3V3_STBY_BMC_HPLLAV33!U9F4!AB19!@baseboard_fab2_lib.baseboard_fab2(sch_1):page148_i11@mstr_controller.ast1250(chips)!AST1250_BGA-IC,G85138-002!!!F4187!MPLLAV33!!!!
S!P1V26_BMC_STBY!U9F4!Y18!@baseboard_fab2_lib.baseboard_fab2(sch_1):page148_i11@mstr_controller.ast1250(chips)!AST1250_BGA-IC,G85138-002!!!F4187!MPLLDV12!!!!
S!P1V538_BMC_STBY!U9F4!U10!@baseboard_fab2_lib.baseboard_fab2(sch_1):page148_i11@mstr_controller.ast1250(chips)!AST1250_BGA-IC,G85138-002!!!F4187!MVDD(0)!!!!
S!P1V538_BMC_STBY!U9F4!U11!@baseboard_fab2_lib.baseboard_fab2(sch_1):page148_i11@mstr_controller.ast1250(chips)!AST1250_BGA-IC,G85138-002!!!F4187!MVDD(1)!!!!
S!P1V538_BMC_STBY!U9F4!U14!@baseboard_fab2_lib.baseboard_fab2(sch_1):page148_i11@mstr_controller.ast1250(chips)!AST1250_BGA-IC,G85138-002!!!F4187!MVDD(2)!!!!
S!P1V538_BMC_STBY!U9F4!U15!@baseboard_fab2_lib.baseboard_fab2(sch_1):page148_i11@mstr_controller.ast1250(chips)!AST1250_BGA-IC,G85138-002!!!F4187!MVDD(3)!!!!
S!GND!U9F4!H21!@baseboard_fab2_lib.baseboard_fab2(sch_1):page148_i11@mstr_controller.ast1250(chips)!AST1250_BGA-IC,G85138-002!!!F4187!NC(0)!!!!
S!GND!U9F4!H22!@baseboard_fab2_lib.baseboard_fab2(sch_1):page148_i11@mstr_controller.ast1250(chips)!AST1250_BGA-IC,G85138-002!!!F4187!NC(1)!!!!
S!GND!U9F4!D21!@baseboard_fab2_lib.baseboard_fab2(sch_1):page148_i11@mstr_controller.ast1250(chips)!AST1250_BGA-IC,G85138-002!!!F4187!PEAGND(0)!!!!
S!GND!U9F4!D22!@baseboard_fab2_lib.baseboard_fab2(sch_1):page148_i11@mstr_controller.ast1250(chips)!AST1250_BGA-IC,G85138-002!!!F4187!PEAGND(1)!!!!
S!P1V26_BMC_STBY!U9F4!K17!@baseboard_fab2_lib.baseboard_fab2(sch_1):page148_i11@mstr_controller.ast1250(chips)!AST1250_BGA-IC,G85138-002!!!F4187!PEAV12!!!!
S!P3V3_STBY!U9F4!J17!@baseboard_fab2_lib.baseboard_fab2(sch_1):page148_i11@mstr_controller.ast1250(chips)!AST1250_BGA-IC,G85138-002!!!F4187!PEAV33!!!!
S!PVCCIO_CPU0!U9F4!V19!@baseboard_fab2_lib.baseboard_fab2(sch_1):page148_i11@mstr_controller.ast1250(chips)!AST1250_BGA-IC,G85138-002!!!F4187!PECIVDD!!!!
S!GND!U9F4!AA18!@baseboard_fab2_lib.baseboard_fab2(sch_1):page148_i11@mstr_controller.ast1250(chips)!AST1250_BGA-IC,G85138-002!!!F4187!PLLVSS(0)!!!!
S!GND!U9F4!AA19!@baseboard_fab2_lib.baseboard_fab2(sch_1):page148_i11@mstr_controller.ast1250(chips)!AST1250_BGA-IC,G85138-002!!!F4187!PLLVSS(1)!!!!
S!GND!U9F4!V18!@baseboard_fab2_lib.baseboard_fab2(sch_1):page148_i11@mstr_controller.ast1250(chips)!AST1250_BGA-IC,G85138-002!!!F4187!PLLVSS(2)!!!!
S!P3V3_STBY!U9F4!F12!@baseboard_fab2_lib.baseboard_fab2(sch_1):page148_i11@mstr_controller.ast1250(chips)!AST1250_BGA-IC,G85138-002!!!F4187!PV33D(0)!!!!
S!P3V3_STBY!U9F4!U9!@baseboard_fab2_lib.baseboard_fab2(sch_1):page148_i11@mstr_controller.ast1250(chips)!AST1250_BGA-IC,G85138-002!!!F4187!PV33D(10)!!!!
S!P3V3_STBY!U9F4!F13!@baseboard_fab2_lib.baseboard_fab2(sch_1):page148_i11@mstr_controller.ast1250(chips)!AST1250_BGA-IC,G85138-002!!!F4187!PV33D(1)!!!!
S!P3V3_STBY!U9F4!H6!@baseboard_fab2_lib.baseboard_fab2(sch_1):page148_i11@mstr_controller.ast1250(chips)!AST1250_BGA-IC,G85138-002!!!F4187!PV33D(2)!!!!
S!P3V3_STBY!U9F4!H17!@baseboard_fab2_lib.baseboard_fab2(sch_1):page148_i11@mstr_controller.ast1250(chips)!AST1250_BGA-IC,G85138-002!!!F4187!PV33D(3)!!!!
S!P3V3_STBY!U9F4!J6!@baseboard_fab2_lib.baseboard_fab2(sch_1):page148_i11@mstr_controller.ast1250(chips)!AST1250_BGA-IC,G85138-002!!!F4187!PV33D(4)!!!!
S!P3V3_STBY!U9F4!M6!@baseboard_fab2_lib.baseboard_fab2(sch_1):page148_i11@mstr_controller.ast1250(chips)!AST1250_BGA-IC,G85138-002!!!F4187!PV33D(5)!!!!
S!P3V3_STBY!U9F4!M17!@baseboard_fab2_lib.baseboard_fab2(sch_1):page148_i11@mstr_controller.ast1250(chips)!AST1250_BGA-IC,G85138-002!!!F4187!PV33D(6)!!!!
S!P3V3_STBY!U9F4!N6!@baseboard_fab2_lib.baseboard_fab2(sch_1):page148_i11@mstr_controller.ast1250(chips)!AST1250_BGA-IC,G85138-002!!!F4187!PV33D(7)!!!!
S!P3V3_STBY!U9F4!N17!@baseboard_fab2_lib.baseboard_fab2(sch_1):page148_i11@mstr_controller.ast1250(chips)!AST1250_BGA-IC,G85138-002!!!F4187!PV33D(8)!!!!
S!P3V3_STBY!U9F4!U8!@baseboard_fab2_lib.baseboard_fab2(sch_1):page148_i11@mstr_controller.ast1250(chips)!AST1250_BGA-IC,G85138-002!!!F4187!PV33D(9)!!!!
S!P3V3_STBY!U9F4!F10!@baseboard_fab2_lib.baseboard_fab2(sch_1):page148_i11@mstr_controller.ast1250(chips)!AST1250_BGA-IC,G85138-002!!!F4187!R1VDD(0)!!!!
S!P3V3_STBY!U9F4!F11!@baseboard_fab2_lib.baseboard_fab2(sch_1):page148_i11@mstr_controller.ast1250(chips)!AST1250_BGA-IC,G85138-002!!!F4187!R1VDD(1)!!!!
S!P3V3_STBY!U9F4!F8!@baseboard_fab2_lib.baseboard_fab2(sch_1):page148_i11@mstr_controller.ast1250(chips)!AST1250_BGA-IC,G85138-002!!!F4187!R2VDD(0)!!!!
S!P3V3_STBY!U9F4!F9!@baseboard_fab2_lib.baseboard_fab2(sch_1):page148_i11@mstr_controller.ast1250(chips)!AST1250_BGA-IC,G85138-002!!!F4187!R2VDD(1)!!!!
S!P3V3_STBY!U9F4!W18!@baseboard_fab2_lib.baseboard_fab2(sch_1):page148_i11@mstr_controller.ast1250(chips)!AST1250_BGA-IC,G85138-002!!!F4187!USB2AV33!!!!
S!GND!U9F4!Y19!@baseboard_fab2_lib.baseboard_fab2(sch_1):page148_i11@mstr_controller.ast1250(chips)!AST1250_BGA-IC,G85138-002!!!F4187!USB2AVSS!!!!
S!P1V26_BMC_STBY_V1PLLAV12!U9F4!W19!@baseboard_fab2_lib.baseboard_fab2(sch_1):page148_i11@mstr_controller.ast1250(chips)!AST1250_BGA-IC,G85138-002!!!F4187!V1PLLAV12!!!!
S!P1V26_BMC_STBY_V1PLLAV12!U9F4!Y20!@baseboard_fab2_lib.baseboard_fab2(sch_1):page148_i11@mstr_controller.ast1250(chips)!AST1250_BGA-IC,G85138-002!!!F4187!V2PLLAV12!!!!
S!VR_FET_SW_P12V_STBY_PVCCIN_CPU1!C1C1!1!@baseboard_fab2_lib.baseboard_fab2(sch_1):page209_i35@mstr_discrete.capp(chips)!CAPP_2626-270UF,16V,20%,OSCON,A!!!F4184!A!!!!
S!GND!C1C1!2!@baseboard_fab2_lib.baseboard_fab2(sch_1):page209_i35@mstr_discrete.capp(chips)!CAPP_2626-270UF,16V,20%,OSCON,A!!!F4184!B!!!!
S!VR_FET_SW_P12V_STBY_PVCCIN_CPU1!C1E18!1!@baseboard_fab2_lib.baseboard_fab2(sch_1):page209_i37@mstr_discrete.capp(chips)!CAPP_2626-270UF,16V,20%,OSCON,A!!!F4182!A!!!!
S!GND!C1E18!2!@baseboard_fab2_lib.baseboard_fab2(sch_1):page209_i37@mstr_discrete.capp(chips)!CAPP_2626-270UF,16V,20%,OSCON,A!!!F4182!B!!!!
S!VR_FET_SW_P12V_STBY_PVCCIN_CPU1!C1C2!1!@baseboard_fab2_lib.baseboard_fab2(sch_1):page209_i38@mstr_discrete.capp(chips)!CAPP_2626-270UF,16V,20%,OSCON,A!!!F4183!A!!!!
S!GND!C1C2!2!@baseboard_fab2_lib.baseboard_fab2(sch_1):page209_i38@mstr_discrete.capp(chips)!CAPP_2626-270UF,16V,20%,OSCON,A!!!F4183!B!!!!
S!VR_FET_SW_P12V_STBY_PVCCIN_CPU0!C4E16!1!@baseboard_fab2_lib.baseboard_fab2(sch_1):page204_i50@mstr_discrete.capp(chips)!CAPP_2626-270UF,16V,20%,OSCON,A!!!F4179!A!!!!
S!GND!C4E16!2!@baseboard_fab2_lib.baseboard_fab2(sch_1):page204_i50@mstr_discrete.capp(chips)!CAPP_2626-270UF,16V,20%,OSCON,A!!!F4179!B!!!!
S!VR_FET_SW_P12V_STBY_PVCCIN_CPU0!C4D2!1!@baseboard_fab2_lib.baseboard_fab2(sch_1):page204_i48@mstr_discrete.capp(chips)!CAPP_2626-270UF,16V,20%,OSCON,A!!!F4180!A!!!!
S!GND!C4D2!2!@baseboard_fab2_lib.baseboard_fab2(sch_1):page204_i48@mstr_discrete.capp(chips)!CAPP_2626-270UF,16V,20%,OSCON,A!!!F4180!B!!!!
S!VR_FET_SW_P12V_STBY_PVCCIN_CPU0!C4C12!1!@baseboard_fab2_lib.baseboard_fab2(sch_1):page204_i67@mstr_discrete.capp(chips)!CAPP_2626-270UF,16V,20%,OSCON,A!!!F4181!A!!!!
S!GND!C4C12!2!@baseboard_fab2_lib.baseboard_fab2(sch_1):page204_i67@mstr_discrete.capp(chips)!CAPP_2626-270UF,16V,20%,OSCON,A!!!F4181!B!!!!
S!VR_FET_SW_P12V_STBY_PVDDQ_ABC!C7G2!1!@baseboard_fab2_lib.baseboard_fab2(sch_1):page217_i175@mstr_discrete.capp(chips)!CAPP_2626-270UF,16V,20%,OSCON,A!!!F4177!A!!!!
S!GND!C7G2!2!@baseboard_fab2_lib.baseboard_fab2(sch_1):page217_i175@mstr_discrete.capp(chips)!CAPP_2626-270UF,16V,20%,OSCON,A!!!F4177!B!!!!
S!VR_FET_SW_P12V_STBY_PVDDQ_DEF!C7A19!1!@baseboard_fab2_lib.baseboard_fab2(sch_1):page220_i175@mstr_discrete.capp(chips)!CAPP_2626-270UF,16V,20%,OSCON,A!!!F4178!A!!!!
S!GND!C7A19!2!@baseboard_fab2_lib.baseboard_fab2(sch_1):page220_i175@mstr_discrete.capp(chips)!CAPP_2626-270UF,16V,20%,OSCON,A!!!F4178!B!!!!
S!VR_FET_SW_P12V_STBY_PVDDQ_KLM!C1B10!1!@baseboard_fab2_lib.baseboard_fab2(sch_1):page228_i175@mstr_discrete.capp(chips)!CAPP_2626-270UF,16V,20%,OSCON,A!!!F4185!A!!!!
S!GND!C1B10!2!@baseboard_fab2_lib.baseboard_fab2(sch_1):page228_i175@mstr_discrete.capp(chips)!CAPP_2626-270UF,16V,20%,OSCON,A!!!F4185!B!!!!
S!PVCCMCP_CPU0!C4R1!1!@baseboard_fab2_lib.baseboard_fab2(sch_1):page194_i29@mstr_discrete.capp(chips)!CAPP_3018-470UF,2.5V,20%,ALUM,A!!!F4162!A!!!!
S!GND!C4R1!2!@baseboard_fab2_lib.baseboard_fab2(sch_1):page194_i29@mstr_discrete.capp(chips)!CAPP_3018-470UF,2.5V,20%,ALUM,A!!!F4162!B!!!!
S!PVCCMCP_CPU1!C6R16!1!@baseboard_fab2_lib.baseboard_fab2(sch_1):page193_i62@mstr_discrete.capp(chips)!CAPP_3018-470UF,2.5V,20%,ALUM,A!!!F4149!A!!!!
S!GND!C6R16!2!@baseboard_fab2_lib.baseboard_fab2(sch_1):page193_i62@mstr_discrete.capp(chips)!CAPP_3018-470UF,2.5V,20%,ALUM,A!!!F4149!B!!!!
S!PVCCMCP_CPU0!C3R4!1!@baseboard_fab2_lib.baseboard_fab2(sch_1):page194_i31@mstr_discrete.capp(chips)!CAPP_3018-470UF,2.5V,20%,ALUM,A!!!F4170!A!!!!
S!GND!C3R4!2!@baseboard_fab2_lib.baseboard_fab2(sch_1):page194_i31@mstr_discrete.capp(chips)!CAPP_3018-470UF,2.5V,20%,ALUM,A!!!F4170!B!!!!
S!PVCCMCP_CPU1!C4E24!1!@baseboard_fab2_lib.baseboard_fab2(sch_1):page193_i61@mstr_discrete.capp(chips)!CAPP_3018-470UF,2.5V,20%,ALUM,A!!!F4164!A!!!!
S!GND!C4E24!2!@baseboard_fab2_lib.baseboard_fab2(sch_1):page193_i61@mstr_discrete.capp(chips)!CAPP_3018-470UF,2.5V,20%,ALUM,A!!!F4164!B!!!!
S!PVCCIOMCP_CPU0!C3N14!1!@baseboard_fab2_lib.baseboard_fab2(sch_1):page194_i101@mstr_discrete.capp(chips)!CAPP_3018-470UF,2.5V,20%,ALUM,A!!!F4174!A!!!!
S!GND!C3N14!2!@baseboard_fab2_lib.baseboard_fab2(sch_1):page194_i101@mstr_discrete.capp(chips)!CAPP_3018-470UF,2.5V,20%,ALUM,A!!!F4174!B!!!!
S!PVCCIOMCP_CPU1!C4C1!1!@baseboard_fab2_lib.baseboard_fab2(sch_1):page193_i29@mstr_discrete.capp(chips)!CAPP_3018-470UF,2.5V,20%,ALUM,A!!!F4166!A!!!!
S!GND!C4C1!2!@baseboard_fab2_lib.baseboard_fab2(sch_1):page193_i29@mstr_discrete.capp(chips)!CAPP_3018-470UF,2.5V,20%,ALUM,A!!!F4166!B!!!!
S!PVCCIN_CPU0!C6N9!1!@baseboard_fab2_lib.baseboard_fab2(sch_1):page203_i34@mstr_discrete.capp(chips)!CAPP_3018-470UF,2.5V,20%,ALUM,A!!!F4158!A!!!!
S!GND!C6N9!2!@baseboard_fab2_lib.baseboard_fab2(sch_1):page203_i34@mstr_discrete.capp(chips)!CAPP_3018-470UF,2.5V,20%,ALUM,A!!!F4158!B!!!!
S!PVCCIN_CPU0!C6P8!1!@baseboard_fab2_lib.baseboard_fab2(sch_1):page203_i32@mstr_discrete.capp(chips)!CAPP_3018-470UF,2.5V,20%,ALUM,A!!!F4157!A!!!!
S!GND!C6P8!2!@baseboard_fab2_lib.baseboard_fab2(sch_1):page203_i32@mstr_discrete.capp(chips)!CAPP_3018-470UF,2.5V,20%,ALUM,A!!!F4157!B!!!!
S!PVCCIN_CPU0!C6P18!1!@baseboard_fab2_lib.baseboard_fab2(sch_1):page203_i30@mstr_discrete.capp(chips)!CAPP_3018-470UF,2.5V,20%,ALUM,A!!!F4155!A!!!!
S!GND!C6P18!2!@baseboard_fab2_lib.baseboard_fab2(sch_1):page203_i30@mstr_discrete.capp(chips)!CAPP_3018-470UF,2.5V,20%,ALUM,A!!!F4155!B!!!!
S!PVCCIN_CPU0!C6P14!1!@baseboard_fab2_lib.baseboard_fab2(sch_1):page203_i29@mstr_discrete.capp(chips)!CAPP_3018-470UF,2.5V,20%,ALUM,A!!!F4156!A!!!!
S!GND!C6P14!2!@baseboard_fab2_lib.baseboard_fab2(sch_1):page203_i29@mstr_discrete.capp(chips)!CAPP_3018-470UF,2.5V,20%,ALUM,A!!!F4156!B!!!!
S!PVCCIN_CPU0!C6P23!1!@baseboard_fab2_lib.baseboard_fab2(sch_1):page203_i28@mstr_discrete.capp(chips)!CAPP_3018-470UF,2.5V,20%,ALUM,A!!!F4154!A!!!!
S!GND!C6P23!2!@baseboard_fab2_lib.baseboard_fab2(sch_1):page203_i28@mstr_discrete.capp(chips)!CAPP_3018-470UF,2.5V,20%,ALUM,A!!!F4154!B!!!!
S!PVCCIN_CPU0!C6R9!1!@baseboard_fab2_lib.baseboard_fab2(sch_1):page203_i18@mstr_discrete.capp(chips)!CAPP_3018-470UF,2.5V,20%,ALUM,A!!!F4151!A!!!!
S!GND!C6R9!2!@baseboard_fab2_lib.baseboard_fab2(sch_1):page203_i18@mstr_discrete.capp(chips)!CAPP_3018-470UF,2.5V,20%,ALUM,A!!!F4151!B!!!!
S!PVCCIN_CPU0!C6R3!1!@baseboard_fab2_lib.baseboard_fab2(sch_1):page203_i16@mstr_discrete.capp(chips)!CAPP_3018-470UF,2.5V,20%,ALUM,A!!!F4153!A!!!!
S!GND!C6R3!2!@baseboard_fab2_lib.baseboard_fab2(sch_1):page203_i16@mstr_discrete.capp(chips)!CAPP_3018-470UF,2.5V,20%,ALUM,A!!!F4153!B!!!!
S!PVCCIO_CPU0!C3N35!1!@baseboard_fab2_lib.baseboard_fab2(sch_1):page212_i18@mstr_discrete.capp(chips)!CAPP_3018-470UF,2.5V,20%,ALUM,A!!!F4172!A!!!!
S!GND!C3N35!2!@baseboard_fab2_lib.baseboard_fab2(sch_1):page212_i18@mstr_discrete.capp(chips)!CAPP_3018-470UF,2.5V,20%,ALUM,A!!!F4172!B!!!!
S!PVCCIO_CPU0!C3N26!1!@baseboard_fab2_lib.baseboard_fab2(sch_1):page212_i17@mstr_discrete.capp(chips)!CAPP_3018-470UF,2.5V,20%,ALUM,A!!!F4173!A!!!!
S!GND!C3N26!2!@baseboard_fab2_lib.baseboard_fab2(sch_1):page212_i17@mstr_discrete.capp(chips)!CAPP_3018-470UF,2.5V,20%,ALUM,A!!!F4173!B!!!!
S!PVCCIO_CPU0!C3N38!1!@baseboard_fab2_lib.baseboard_fab2(sch_1):page212_i16@mstr_discrete.capp(chips)!CAPP_3018-470UF,2.5V,20%,ALUM,A!!!F4171!A!!!!
S!GND!C3N38!2!@baseboard_fab2_lib.baseboard_fab2(sch_1):page212_i16@mstr_discrete.capp(chips)!CAPP_3018-470UF,2.5V,20%,ALUM,A!!!F4171!B!!!!
S!PVCCIO_CPU1!C6R5!1!@baseboard_fab2_lib.baseboard_fab2(sch_1):page214_i24@mstr_discrete.capp(chips)!CAPP_3018-470UF,2.5V,20%,ALUM,A!!!F4152!A!!!!
S!GND!C6R5!2!@baseboard_fab2_lib.baseboard_fab2(sch_1):page214_i24@mstr_discrete.capp(chips)!CAPP_3018-470UF,2.5V,20%,ALUM,A!!!F4152!B!!!!
S!PVCCIO_CPU1!C6R12!1!@baseboard_fab2_lib.baseboard_fab2(sch_1):page214_i21@mstr_discrete.capp(chips)!CAPP_3018-470UF,2.5V,20%,ALUM,A!!!F4150!A!!!!
S!GND!C6R12!2!@baseboard_fab2_lib.baseboard_fab2(sch_1):page214_i21@mstr_discrete.capp(chips)!CAPP_3018-470UF,2.5V,20%,ALUM,A!!!F4150!B!!!!
S!PVCCIO_CPU1!C4E7!1!@baseboard_fab2_lib.baseboard_fab2(sch_1):page214_i20@mstr_discrete.capp(chips)!CAPP_3018-470UF,2.5V,20%,ALUM,A!!!F4165!A!!!!
S!GND!C4E7!2!@baseboard_fab2_lib.baseboard_fab2(sch_1):page214_i20@mstr_discrete.capp(chips)!CAPP_3018-470UF,2.5V,20%,ALUM,A!!!F4165!B!!!!
S!PVSA_CPU0!C6N4!1!@baseboard_fab2_lib.baseboard_fab2(sch_1):page205_i14@mstr_discrete.capp(chips)!CAPP_3018-470UF,2.5V,20%,ALUM,A!!!F4159!A!!!!
S!GND!C6N4!2!@baseboard_fab2_lib.baseboard_fab2(sch_1):page205_i14@mstr_discrete.capp(chips)!CAPP_3018-470UF,2.5V,20%,ALUM,A!!!F4159!B!!!!
S!PVSA_CPU0!C6N1!1!@baseboard_fab2_lib.baseboard_fab2(sch_1):page205_i12@mstr_discrete.capp(chips)!CAPP_3018-470UF,2.5V,20%,ALUM,A!!!F4160!A!!!!
S!GND!C6N1!2!@baseboard_fab2_lib.baseboard_fab2(sch_1):page205_i12@mstr_discrete.capp(chips)!CAPP_3018-470UF,2.5V,20%,ALUM,A!!!F4160!B!!!!
S!PVDDQ_ABC!C7G28!1!@baseboard_fab2_lib.baseboard_fab2(sch_1):page217_i75@mstr_discrete.capp(chips)!CAPP_3018-470UF,2.5V,20%,ALUM,A!!!F4148!A!!!!
S!GND!C7G28!2!@baseboard_fab2_lib.baseboard_fab2(sch_1):page217_i75@mstr_discrete.capp(chips)!CAPP_3018-470UF,2.5V,20%,ALUM,A!!!F4148!B!!!!
S!PVDDQ_ABC!C3U1!1!@baseboard_fab2_lib.baseboard_fab2(sch_1):page217_i76@mstr_discrete.capp(chips)!CAPP_3018-470UF,2.5V,20%,ALUM,A!!!F4169!A!!!!
S!GND!C3U1!2!@baseboard_fab2_lib.baseboard_fab2(sch_1):page217_i76@mstr_discrete.capp(chips)!CAPP_3018-470UF,2.5V,20%,ALUM,A!!!F4169!B!!!!
S!PVDDQ_ABC!C3U5!1!@baseboard_fab2_lib.baseboard_fab2(sch_1):page217_i77@mstr_discrete.capp(chips)!CAPP_3018-470UF,2.5V,20%,ALUM,A!!!F4168!A!!!!
S!GND!C3U5!2!@baseboard_fab2_lib.baseboard_fab2(sch_1):page217_i77@mstr_discrete.capp(chips)!CAPP_3018-470UF,2.5V,20%,ALUM,A!!!F4168!B!!!!
S!PVDDQ_ABC!C3U8!1!@baseboard_fab2_lib.baseboard_fab2(sch_1):page217_i78@mstr_discrete.capp(chips)!CAPP_3018-470UF,2.5V,20%,ALUM,A!!!F4167!A!!!!
S!GND!C3U8!2!@baseboard_fab2_lib.baseboard_fab2(sch_1):page217_i78@mstr_discrete.capp(chips)!CAPP_3018-470UF,2.5V,20%,ALUM,A!!!F4167!B!!!!
S!PVDDQ_DEF!C3L6!1!@baseboard_fab2_lib.baseboard_fab2(sch_1):page220_i75@mstr_discrete.capp(chips)!CAPP_3018-470UF,2.5V,20%,ALUM,A!!!F4176!A!!!!
S!GND!C3L6!2!@baseboard_fab2_lib.baseboard_fab2(sch_1):page220_i75@mstr_discrete.capp(chips)!CAPP_3018-470UF,2.5V,20%,ALUM,A!!!F4176!B!!!!
S!PVDDQ_DEF!C3L14!1!@baseboard_fab2_lib.baseboard_fab2(sch_1):page220_i76@mstr_discrete.capp(chips)!CAPP_3018-470UF,2.5V,20%,ALUM,A!!!F4175!A!!!!
S!GND!C3L14!2!@baseboard_fab2_lib.baseboard_fab2(sch_1):page220_i76@mstr_discrete.capp(chips)!CAPP_3018-470UF,2.5V,20%,ALUM,A!!!F4175!B!!!!
S!PVDDQ_DEF!C6A5!1!@baseboard_fab2_lib.baseboard_fab2(sch_1):page220_i77@mstr_discrete.capp(chips)!CAPP_3018-470UF,2.5V,20%,ALUM,A!!!F4161!A!!!!
S!GND!C6A5!2!@baseboard_fab2_lib.baseboard_fab2(sch_1):page220_i77@mstr_discrete.capp(chips)!CAPP_3018-470UF,2.5V,20%,ALUM,A!!!F4161!B!!!!
S!PVDDQ_DEF!C4L5!1!@baseboard_fab2_lib.baseboard_fab2(sch_1):page220_i78@mstr_discrete.capp(chips)!CAPP_3018-470UF,2.5V,20%,ALUM,A!!!F4163!A!!!!
S!GND!C4L5!2!@baseboard_fab2_lib.baseboard_fab2(sch_1):page220_i78@mstr_discrete.capp(chips)!CAPP_3018-470UF,2.5V,20%,ALUM,A!!!F4163!B!!!!
S!PVDDQ_GHJ!C9T5!1!@baseboard_fab2_lib.baseboard_fab2(sch_1):page225_i75@mstr_discrete.capp(chips)!CAPP_3018-470UF,2.5V,20%,ALUM,A!!!F4134!A!!!!
S!GND!C9T5!2!@baseboard_fab2_lib.baseboard_fab2(sch_1):page225_i75@mstr_discrete.capp(chips)!CAPP_3018-470UF,2.5V,20%,ALUM,A!!!F4134!B!!!!
S!PVDDQ_GHJ!C9U2!1!@baseboard_fab2_lib.baseboard_fab2(sch_1):page225_i76@mstr_discrete.capp(chips)!CAPP_3018-470UF,2.5V,20%,ALUM,A!!!F4133!A!!!!
S!GND!C9U2!2!@baseboard_fab2_lib.baseboard_fab2(sch_1):page225_i76@mstr_discrete.capp(chips)!CAPP_3018-470UF,2.5V,20%,ALUM,A!!!F4133!B!!!!
S!PVDDQ_GHJ!C9U9!1!@baseboard_fab2_lib.baseboard_fab2(sch_1):page225_i77@mstr_discrete.capp(chips)!CAPP_3018-470UF,2.5V,20%,ALUM,A!!!F4131!A!!!!
S!GND!C9U9!2!@baseboard_fab2_lib.baseboard_fab2(sch_1):page225_i77@mstr_discrete.capp(chips)!CAPP_3018-470UF,2.5V,20%,ALUM,A!!!F4131!B!!!!
S!PVDDQ_GHJ!C9U5!1!@baseboard_fab2_lib.baseboard_fab2(sch_1):page225_i78@mstr_discrete.capp(chips)!CAPP_3018-470UF,2.5V,20%,ALUM,A!!!F4132!A!!!!
S!GND!C9U5!2!@baseboard_fab2_lib.baseboard_fab2(sch_1):page225_i78@mstr_discrete.capp(chips)!CAPP_3018-470UF,2.5V,20%,ALUM,A!!!F4132!B!!!!
S!PVDDQ_KLM!C9L9!1!@baseboard_fab2_lib.baseboard_fab2(sch_1):page228_i75@mstr_discrete.capp(chips)!CAPP_3018-470UF,2.5V,20%,ALUM,A!!!F4145!A!!!!
S!GND!C9L9!2!@baseboard_fab2_lib.baseboard_fab2(sch_1):page228_i75@mstr_discrete.capp(chips)!CAPP_3018-470UF,2.5V,20%,ALUM,A!!!F4145!B!!!!
S!PVDDQ_KLM!C9L12!1!@baseboard_fab2_lib.baseboard_fab2(sch_1):page228_i76@mstr_discrete.capp(chips)!CAPP_3018-470UF,2.5V,20%,ALUM,A!!!F4144!A!!!!
S!GND!C9L12!2!@baseboard_fab2_lib.baseboard_fab2(sch_1):page228_i76@mstr_discrete.capp(chips)!CAPP_3018-470UF,2.5V,20%,ALUM,A!!!F4144!B!!!!
S!PVDDQ_KLM!C9L4!1!@baseboard_fab2_lib.baseboard_fab2(sch_1):page228_i77@mstr_discrete.capp(chips)!CAPP_3018-470UF,2.5V,20%,ALUM,A!!!F4146!A!!!!
S!GND!C9L4!2!@baseboard_fab2_lib.baseboard_fab2(sch_1):page228_i77@mstr_discrete.capp(chips)!CAPP_3018-470UF,2.5V,20%,ALUM,A!!!F4146!B!!!!
S!PVDDQ_KLM!C9L2!1!@baseboard_fab2_lib.baseboard_fab2(sch_1):page228_i78@mstr_discrete.capp(chips)!CAPP_3018-470UF,2.5V,20%,ALUM,A!!!F4147!A!!!!
S!GND!C9L2!2!@baseboard_fab2_lib.baseboard_fab2(sch_1):page228_i78@mstr_discrete.capp(chips)!CAPP_3018-470UF,2.5V,20%,ALUM,A!!!F4147!B!!!!
S!PVCCIN_CPU1!C9P18!1!@baseboard_fab2_lib.baseboard_fab2(sch_1):page208_i30@mstr_discrete.capp(chips)!CAPP_3018-470UF,2.5V,20%,ALUM,A!!!F4138!A!!!!
S!GND!C9P18!2!@baseboard_fab2_lib.baseboard_fab2(sch_1):page208_i30@mstr_discrete.capp(chips)!CAPP_3018-470UF,2.5V,20%,ALUM,A!!!F4138!B!!!!
S!PVCCIN_CPU1!C9P23!1!@baseboard_fab2_lib.baseboard_fab2(sch_1):page208_i28@mstr_discrete.capp(chips)!CAPP_3018-470UF,2.5V,20%,ALUM,A!!!F4137!A!!!!
S!GND!C9P23!2!@baseboard_fab2_lib.baseboard_fab2(sch_1):page208_i28@mstr_discrete.capp(chips)!CAPP_3018-470UF,2.5V,20%,ALUM,A!!!F4137!B!!!!
S!PVCCIN_CPU1!C9R3!1!@baseboard_fab2_lib.baseboard_fab2(sch_1):page208_i26@mstr_discrete.capp(chips)!CAPP_3018-470UF,2.5V,20%,ALUM,A!!!F4136!A!!!!
S!GND!C9R3!2!@baseboard_fab2_lib.baseboard_fab2(sch_1):page208_i26@mstr_discrete.capp(chips)!CAPP_3018-470UF,2.5V,20%,ALUM,A!!!F4136!B!!!!
S!PVCCIN_CPU1!C9R9!1!@baseboard_fab2_lib.baseboard_fab2(sch_1):page208_i25@mstr_discrete.capp(chips)!CAPP_3018-470UF,2.5V,20%,ALUM,A!!!F4135!A!!!!
S!GND!C9R9!2!@baseboard_fab2_lib.baseboard_fab2(sch_1):page208_i25@mstr_discrete.capp(chips)!CAPP_3018-470UF,2.5V,20%,ALUM,A!!!F4135!B!!!!
S!PVCCIN_CPU1!C9N24!1!@baseboard_fab2_lib.baseboard_fab2(sch_1):page208_i24@mstr_discrete.capp(chips)!CAPP_3018-470UF,2.5V,20%,ALUM,A!!!F4141!A!!!!
S!GND!C9N24!2!@baseboard_fab2_lib.baseboard_fab2(sch_1):page208_i24@mstr_discrete.capp(chips)!CAPP_3018-470UF,2.5V,20%,ALUM,A!!!F4141!B!!!!
S!PVCCIN_CPU1!C9P5!1!@baseboard_fab2_lib.baseboard_fab2(sch_1):page208_i14@mstr_discrete.capp(chips)!CAPP_3018-470UF,2.5V,20%,ALUM,A!!!F4140!A!!!!
S!GND!C9P5!2!@baseboard_fab2_lib.baseboard_fab2(sch_1):page208_i14@mstr_discrete.capp(chips)!CAPP_3018-470UF,2.5V,20%,ALUM,A!!!F4140!B!!!!
S!PVCCIN_CPU1!C9P8!1!@baseboard_fab2_lib.baseboard_fab2(sch_1):page208_i12@mstr_discrete.capp(chips)!CAPP_3018-470UF,2.5V,20%,ALUM,A!!!F4139!A!!!!
S!GND!C9P8!2!@baseboard_fab2_lib.baseboard_fab2(sch_1):page208_i12@mstr_discrete.capp(chips)!CAPP_3018-470UF,2.5V,20%,ALUM,A!!!F4139!B!!!!
S!PVSA_CPU1!C9N20!1!@baseboard_fab2_lib.baseboard_fab2(sch_1):page210_i14@mstr_discrete.capp(chips)!CAPP_3018-470UF,2.5V,20%,ALUM,A!!!F4142!A!!!!
S!GND!C9N20!2!@baseboard_fab2_lib.baseboard_fab2(sch_1):page210_i14@mstr_discrete.capp(chips)!CAPP_3018-470UF,2.5V,20%,ALUM,A!!!F4142!B!!!!
S!PVSA_CPU1!C9N11!1!@baseboard_fab2_lib.baseboard_fab2(sch_1):page210_i12@mstr_discrete.capp(chips)!CAPP_3018-470UF,2.5V,20%,ALUM,A!!!F4143!A!!!!
S!GND!C9N11!2!@baseboard_fab2_lib.baseboard_fab2(sch_1):page210_i12@mstr_discrete.capp(chips)!CAPP_3018-470UF,2.5V,20%,ALUM,A!!!F4143!B!!!!
S!P1V05_PCH_STBY!C3L19!1!@baseboard_fab2_lib.baseboard_fab2(sch_1):page236_i76@mstr_discrete.capp(chips)!CAPP_SM-470UF,2V,20%,ALUM,6990A!!!F4095!A!!!!
S!GND!C3L19!2!@baseboard_fab2_lib.baseboard_fab2(sch_1):page236_i76@mstr_discrete.capp(chips)!CAPP_SM-470UF,2V,20%,ALUM,6990A!!!F4095!B!!!!
S!PVNN_PCH_STBY!C3L18!1!@baseboard_fab2_lib.baseboard_fab2(sch_1):page236_i71@mstr_discrete.capp(chips)!CAPP_SM-470UF,2V,20%,ALUM,6990A!!!F4096!A!!!!
S!GND!C3L18!2!@baseboard_fab2_lib.baseboard_fab2(sch_1):page236_i71@mstr_discrete.capp(chips)!CAPP_SM-470UF,2V,20%,ALUM,6990A!!!F4096!B!!!!
S!PVNN_PCH_STBY!C3L20!1!@baseboard_fab2_lib.baseboard_fab2(sch_1):page236_i73@mstr_discrete.capp(chips)!CAPP_SM-470UF,2V,20%,ALUM,6990A!!!F4094!A!!!!
S!GND!C3L20!2!@baseboard_fab2_lib.baseboard_fab2(sch_1):page236_i73@mstr_discrete.capp(chips)!CAPP_SM-470UF,2V,20%,ALUM,6990A!!!F4094!B!!!!
S!PVNN_PCH_STBY!C3L21!1!@baseboard_fab2_lib.baseboard_fab2(sch_1):page236_i74@mstr_discrete.capp(chips)!CAPP_SM-470UF,2V,20%,ALUM,6990A!!!F4093!A!!!!
S!GND!C3L21!2!@baseboard_fab2_lib.baseboard_fab2(sch_1):page236_i74@mstr_discrete.capp(chips)!CAPP_SM-470UF,2V,20%,ALUM,6990A!!!F4093!B!!!!
S!PVNN_PCH_STBY!C7A27!1!@baseboard_fab2_lib.baseboard_fab2(sch_1):page236_i75@mstr_discrete.capp(chips)!CAPP_SM-470UF,2V,20%,ALUM,6990A!!!F4092!A!!!!
S!GND!C7A27!2!@baseboard_fab2_lib.baseboard_fab2(sch_1):page236_i75@mstr_discrete.capp(chips)!CAPP_SM-470UF,2V,20%,ALUM,6990A!!!F4092!B!!!!
S!P1V05_PCH_STBY!C2L46!1!@baseboard_fab2_lib.baseboard_fab2(sch_1):page236_i77@mstr_discrete.capp(chips)!CAPP_SM-470UF,2V,20%,ALUM,6990A!!!F4097!A!!!!
S!GND!C2L46!2!@baseboard_fab2_lib.baseboard_fab2(sch_1):page236_i77@mstr_discrete.capp(chips)!CAPP_SM-470UF,2V,20%,ALUM,6990A!!!F4097!B!!!!
S!P1V05_PCH_STBY!C8A15!1!@baseboard_fab2_lib.baseboard_fab2(sch_1):page236_i78@mstr_discrete.capp(chips)!CAPP_SM-470UF,2V,20%,ALUM,6990A!!!F4091!A!!!!
S!GND!C8A15!2!@baseboard_fab2_lib.baseboard_fab2(sch_1):page236_i78@mstr_discrete.capp(chips)!CAPP_SM-470UF,2V,20%,ALUM,6990A!!!F4091!B!!!!
S!P1V05_PCH_STBY!C2L25!1!@baseboard_fab2_lib.baseboard_fab2(sch_1):page236_i79@mstr_discrete.capp(chips)!CAPP_SM-470UF,2V,20%,ALUM,6990A!!!F4098!A!!!!
S!GND!C2L25!2!@baseboard_fab2_lib.baseboard_fab2(sch_1):page236_i79@mstr_discrete.capp(chips)!CAPP_SM-470UF,2V,20%,ALUM,6990A!!!F4098!B!!!!
S!P3V3_RTC_STBY!C2U26!1!@baseboard_fab2_lib.baseboard_fab2(sch_1):page196_i102@mstr_discrete.cap(chips)!CAP_0402-1.0UF,6.3V,10%,X6S,D9A!!!F3682!A!!!!
S!GND!C2U26!2!@baseboard_fab2_lib.baseboard_fab2(sch_1):page196_i102@mstr_discrete.cap(chips)!CAP_0402-1.0UF,6.3V,10%,X6S,D9A!!!F3682!B!!!!
S!P3V3!C1M3!1!@baseboard_fab2_lib.baseboard_fab2(sch_1):page177_i20@mstr_discrete.cap(chips)!CAP_0402-1.0UF,6.3V,10%,X6S,D9A!!!F3736!A!!!!
S!GND!C1M3!2!@baseboard_fab2_lib.baseboard_fab2(sch_1):page177_i20@mstr_discrete.cap(chips)!CAP_0402-1.0UF,6.3V,10%,X6S,D9A!!!F3736!B!!!!
S!FP_NMI_BTN_OUT_N!C2R12!1!@baseboard_fab2_lib.baseboard_fab2(sch_1):page157_i353@mstr_discrete.cap(chips)!CAP_0402-1.0UF,6.3V,10%,X6S,D9A!!!F3688!A!!!!
S!GND!C2R12!2!@baseboard_fab2_lib.baseboard_fab2(sch_1):page157_i353@mstr_discrete.cap(chips)!CAP_0402-1.0UF,6.3V,10%,X6S,D9A!!!F3688!B!!!!
S!P3V3_STBY!C1M32!1!@baseboard_fab2_lib.baseboard_fab2(sch_1):page113_i117@mstr_discrete.cap(chips)!CAP_0402-1.0UF,6.3V,10%,X6S,D9A!!!F3689!A!!!!
S!GND!C1M32!2!@baseboard_fab2_lib.baseboard_fab2(sch_1):page113_i117@mstr_discrete.cap(chips)!CAP_0402-1.0UF,6.3V,10%,X6S,D9A!!!F3689!B!!!!
S!P3V3_STBY!C1M25!1!@baseboard_fab2_lib.baseboard_fab2(sch_1):page186_i335@mstr_discrete.cap(chips)!CAP_0402-1.0UF,6.3V,10%,X6S,D9A!!!F3734!A!!!!
S!GND!C1M25!2!@baseboard_fab2_lib.baseboard_fab2(sch_1):page186_i335@mstr_discrete.cap(chips)!CAP_0402-1.0UF,6.3V,10%,X6S,D9A!!!F3734!B!!!!
S!VR_PVDDQ_ABC_VDD!C7F18!1!@baseboard_fab2_lib.baseboard_fab2(sch_1):page215_i309@mstr_discrete.cap(chips)!CAP_0402-1.0UF,6.3V,10%,X6S,D9A!!!F3616!A!!!!
S!GND!C7F18!2!@baseboard_fab2_lib.baseboard_fab2(sch_1):page215_i309@mstr_discrete.cap(chips)!CAP_0402-1.0UF,6.3V,10%,X6S,D9A!!!F3616!B!!!!
S!VR_PVDDQ_ABC_VD12!C7F16!1!@baseboard_fab2_lib.baseboard_fab2(sch_1):page215_i325@mstr_discrete.cap(chips)!CAP_0402-1.0UF,6.3V,10%,X6S,D9A!!!F3617!A!!!!
S!GND!C7F16!2!@baseboard_fab2_lib.baseboard_fab2(sch_1):page215_i325@mstr_discrete.cap(chips)!CAP_0402-1.0UF,6.3V,10%,X6S,D9A!!!F3617!B!!!!
S!VR_PVCCIN_CPU0_VDD!C4D15!1!@baseboard_fab2_lib.baseboard_fab2(sch_1):page201_i37@mstr_discrete.cap(chips)!CAP_0402-1.0UF,6.3V,10%,X6S,D9A!!!F3636!A!!!!
S!GND!C4D15!2!@baseboard_fab2_lib.baseboard_fab2(sch_1):page201_i37@mstr_discrete.cap(chips)!CAP_0402-1.0UF,6.3V,10%,X6S,D9A!!!F3636!B!!!!
S!VR_PVCCIN_CPU0_VD12!C4D25!1!@baseboard_fab2_lib.baseboard_fab2(sch_1):page201_i30@mstr_discrete.cap(chips)!CAP_0402-1.0UF,6.3V,10%,X6S,D9A!!!F3634!A!!!!
S!GND!C4D25!2!@baseboard_fab2_lib.baseboard_fab2(sch_1):page201_i30@mstr_discrete.cap(chips)!CAP_0402-1.0UF,6.3V,10%,X6S,D9A!!!F3634!B!!!!
S!VR_PVCCIN_CPU1_VDD!C1C7!1!@baseboard_fab2_lib.baseboard_fab2(sch_1):page206_i41@mstr_discrete.cap(chips)!CAP_0402-1.0UF,6.3V,10%,X6S,D9A!!!F3750!A!!!!
S!GND!C1C7!2!@baseboard_fab2_lib.baseboard_fab2(sch_1):page206_i41@mstr_discrete.cap(chips)!CAP_0402-1.0UF,6.3V,10%,X6S,D9A!!!F3750!B!!!!
S!VR_PVDDQ_DEF_VDD!C7A37!1!@baseboard_fab2_lib.baseboard_fab2(sch_1):page218_i29@mstr_discrete.cap(chips)!CAP_0402-1.0UF,6.3V,10%,X6S,D9A!!!F3621!A!!!!
S!GND!C7A37!2!@baseboard_fab2_lib.baseboard_fab2(sch_1):page218_i29@mstr_discrete.cap(chips)!CAP_0402-1.0UF,6.3V,10%,X6S,D9A!!!F3621!B!!!!
S!VR_PVDDQ_DEF_VD12!C7B1!1!@baseboard_fab2_lib.baseboard_fab2(sch_1):page218_i22@mstr_discrete.cap(chips)!CAP_0402-1.0UF,6.3V,10%,X6S,D9A!!!F3620!A!!!!
S!GND!C7B1!2!@baseboard_fab2_lib.baseboard_fab2(sch_1):page218_i22@mstr_discrete.cap(chips)!CAP_0402-1.0UF,6.3V,10%,X6S,D9A!!!F3620!B!!!!
S!VR_PVDDQ_GHJ_VDD!C1G27!1!@baseboard_fab2_lib.baseboard_fab2(sch_1):page223_i25@mstr_discrete.cap(chips)!CAP_0402-1.0UF,6.3V,10%,X6S,D9A!!!F3740!A!!!!
S!GND!C1G27!2!@baseboard_fab2_lib.baseboard_fab2(sch_1):page223_i25@mstr_discrete.cap(chips)!CAP_0402-1.0UF,6.3V,10%,X6S,D9A!!!F3740!B!!!!
S!VR_PVDDQ_GHJ_VD12!C1G23!1!@baseboard_fab2_lib.baseboard_fab2(sch_1):page223_i41@mstr_discrete.cap(chips)!CAP_0402-1.0UF,6.3V,10%,X6S,D9A!!!F3741!A!!!!
S!GND!C1G23!2!@baseboard_fab2_lib.baseboard_fab2(sch_1):page223_i41@mstr_discrete.cap(chips)!CAP_0402-1.0UF,6.3V,10%,X6S,D9A!!!F3741!B!!!!
S!VR_PVDDQ_KLM_VDD!C1B6!1!@baseboard_fab2_lib.baseboard_fab2(sch_1):page226_i25@mstr_discrete.cap(chips)!CAP_0402-1.0UF,6.3V,10%,X6S,D9A!!!F3752!A!!!!
S!GND!C1B6!2!@baseboard_fab2_lib.baseboard_fab2(sch_1):page226_i25@mstr_discrete.cap(chips)!CAP_0402-1.0UF,6.3V,10%,X6S,D9A!!!F3752!B!!!!
S!VR_PVDDQ_KLM_VD12!C1B3!1!@baseboard_fab2_lib.baseboard_fab2(sch_1):page226_i41@mstr_discrete.cap(chips)!CAP_0402-1.0UF,6.3V,10%,X6S,D9A!!!F3753!A!!!!
S!GND!C1B3!2!@baseboard_fab2_lib.baseboard_fab2(sch_1):page226_i41@mstr_discrete.cap(chips)!CAP_0402-1.0UF,6.3V,10%,X6S,D9A!!!F3753!B!!!!
S!VR_PVCCIN_CPU1_VD12!C1C13!1!@baseboard_fab2_lib.baseboard_fab2(sch_1):page206_i29@mstr_discrete.cap(chips)!CAP_0402-1.0UF,6.3V,10%,X6S,D9A!!!F3749!A!!!!
S!GND!C1C13!2!@baseboard_fab2_lib.baseboard_fab2(sch_1):page206_i29@mstr_discrete.cap(chips)!CAP_0402-1.0UF,6.3V,10%,X6S,D9A!!!F3749!B!!!!
S!P3V3!C1M21!1!@baseboard_fab2_lib.baseboard_fab2(sch_1):page186_i334@mstr_discrete.cap(chips)!CAP_0402-1.0UF,6.3V,10%,X6S,D9A!!!F3735!A!!!!
S!GND!C1M21!2!@baseboard_fab2_lib.baseboard_fab2(sch_1):page186_i334@mstr_discrete.cap(chips)!CAP_0402-1.0UF,6.3V,10%,X6S,D9A!!!F3735!B!!!!
S!VR_PVCCIO_CPU0_VD12!C3P4!1!@baseboard_fab2_lib.baseboard_fab2(sch_1):page211_i11@mstr_discrete.cap(chips)!CAP_0402-1.0UF,6.3V,10%,X6S,D9A!!!F3646!A!!!!
S!GND!C3P4!2!@baseboard_fab2_lib.baseboard_fab2(sch_1):page211_i11@mstr_discrete.cap(chips)!CAP_0402-1.0UF,6.3V,10%,X6S,D9A!!!F3646!B!!!!
S!VR_PVCCIO_CPU1_VD12!C4D31!1!@baseboard_fab2_lib.baseboard_fab2(sch_1):page213_i9@mstr_discrete.cap(chips)!CAP_0402-1.0UF,6.3V,10%,X6S,D9A!!!F3632!A!!!!
S!GND!C4D31!2!@baseboard_fab2_lib.baseboard_fab2(sch_1):page213_i9@mstr_discrete.cap(chips)!CAP_0402-1.0UF,6.3V,10%,X6S,D9A!!!F3632!B!!!!
S!VR_PVCCIO_CPU0_VDD!C3P3!1!@baseboard_fab2_lib.baseboard_fab2(sch_1):page211_i20@mstr_discrete.cap(chips)!CAP_0402-1.0UF,6.3V,10%,X6S,D9A!!!F3647!A!!!!
S!GND!C3P3!2!@baseboard_fab2_lib.baseboard_fab2(sch_1):page211_i20@mstr_discrete.cap(chips)!CAP_0402-1.0UF,6.3V,10%,X6S,D9A!!!F3647!B!!!!
S!VR_PVCCIO_CPU1_VDD!C4D36!1!@baseboard_fab2_lib.baseboard_fab2(sch_1):page213_i17@mstr_discrete.cap(chips)!CAP_0402-1.0UF,6.3V,10%,X6S,D9A!!!F3631!A!!!!
S!GND!C4D36!2!@baseboard_fab2_lib.baseboard_fab2(sch_1):page213_i17@mstr_discrete.cap(chips)!CAP_0402-1.0UF,6.3V,10%,X6S,D9A!!!F3631!B!!!!
S!VR_PVNN_P1V05_PCH_VD12!C8A7!1!@baseboard_fab2_lib.baseboard_fab2(sch_1):page235_i143@mstr_discrete.cap(chips)!CAP_0402-1.0UF,6.3V,10%,X6S,D9A!!!F3612!A!!!!
S!GND!C8A7!2!@baseboard_fab2_lib.baseboard_fab2(sch_1):page235_i143@mstr_discrete.cap(chips)!CAP_0402-1.0UF,6.3V,10%,X6S,D9A!!!F3612!B!!!!
S!P3V3_DB1200_R!C4D27!1!@baseboard_fab2_lib.baseboard_fab2(sch_1):page102_i30@mstr_discrete.cap(chips)!CAP_0402-1.0UF,6.3V,10%,X6S,D9A!!!F3633!A!!!!
S!GND!C4D27!2!@baseboard_fab2_lib.baseboard_fab2(sch_1):page102_i30@mstr_discrete.cap(chips)!CAP_0402-1.0UF,6.3V,10%,X6S,D9A!!!F3633!B!!!!
S!P3V3_DB1200_A!C4D23!1!@baseboard_fab2_lib.baseboard_fab2(sch_1):page102_i19@mstr_discrete.cap(chips)!CAP_0402-1.0UF,6.3V,10%,X6S,D9A!!!F3635!A!!!!
S!GND!C4D23!2!@baseboard_fab2_lib.baseboard_fab2(sch_1):page102_i19@mstr_discrete.cap(chips)!CAP_0402-1.0UF,6.3V,10%,X6S,D9A!!!F3635!B!!!!
S!VR_PVNN_PCH_VDD!C2L8!1!@baseboard_fab2_lib.baseboard_fab2(sch_1):page235_i151@mstr_discrete.cap(chips)!CAP_0402-1.0UF,6.3V,10%,X6S,D9A!!!F3718!A!!!!
S!GND!C2L8!2!@baseboard_fab2_lib.baseboard_fab2(sch_1):page235_i151@mstr_discrete.cap(chips)!CAP_0402-1.0UF,6.3V,10%,X6S,D9A!!!F3718!B!!!!
S!P1V05_PCH_STBY_KR_PLL!C2N1!1!@baseboard_fab2_lib.baseboard_fab2(sch_1):page127_i63@mstr_discrete.cap(chips)!CAP_0402-1.0UF,6.3V,10%,X6S,D9A!!!F3707!A!!!!
S!GND!C2N1!2!@baseboard_fab2_lib.baseboard_fab2(sch_1):page127_i63@mstr_discrete.cap(chips)!CAP_0402-1.0UF,6.3V,10%,X6S,D9A!!!F3707!B!!!!
S!P1V05_PCH_STBY_VCCA_PLL1!C3M19!1!@baseboard_fab2_lib.baseboard_fab2(sch_1):page127_i31@mstr_discrete.cap(chips)!CAP_0402-1.0UF,6.3V,10%,X6S,D9A!!!F3678!A!!!!
S!GND!C3M19!2!@baseboard_fab2_lib.baseboard_fab2(sch_1):page127_i31@mstr_discrete.cap(chips)!CAP_0402-1.0UF,6.3V,10%,X6S,D9A!!!F3678!B!!!!
S!P1V05_PCH_STBY_VCCA_PLL0!C3M20!1!@baseboard_fab2_lib.baseboard_fab2(sch_1):page127_i33@mstr_discrete.cap(chips)!CAP_0402-1.0UF,6.3V,10%,X6S,D9A!!!F3677!A!!!!
S!GND!C3M20!2!@baseboard_fab2_lib.baseboard_fab2(sch_1):page127_i33@mstr_discrete.cap(chips)!CAP_0402-1.0UF,6.3V,10%,X6S,D9A!!!F3677!B!!!!
S!P1V05_PCH_STBY_WM20_PLL!C2M6!1!@baseboard_fab2_lib.baseboard_fab2(sch_1):page127_i42@mstr_discrete.cap(chips)!CAP_0402-1.0UF,6.3V,10%,X6S,D9A!!!F3717!A!!!!
S!GND!C2M6!2!@baseboard_fab2_lib.baseboard_fab2(sch_1):page127_i42@mstr_discrete.cap(chips)!CAP_0402-1.0UF,6.3V,10%,X6S,D9A!!!F3717!B!!!!
S!P1V05_PCH_STBY_VCCA_XTAL!C3M27!1!@baseboard_fab2_lib.baseboard_fab2(sch_1):page127_i35@mstr_discrete.cap(chips)!CAP_0402-1.0UF,6.3V,10%,X6S,D9A!!!F3674!A!!!!
S!GND!C3M27!2!@baseboard_fab2_lib.baseboard_fab2(sch_1):page127_i35@mstr_discrete.cap(chips)!CAP_0402-1.0UF,6.3V,10%,X6S,D9A!!!F3674!B!!!!
S!P1V05_PCH_STBY_ISCLK_PLL!C3M29!1!@baseboard_fab2_lib.baseboard_fab2(sch_1):page127_i53@mstr_discrete.cap(chips)!CAP_0402-1.0UF,6.3V,10%,X6S,D9A!!!F3673!A!!!!
S!GND!C3M29!2!@baseboard_fab2_lib.baseboard_fab2(sch_1):page127_i53@mstr_discrete.cap(chips)!CAP_0402-1.0UF,6.3V,10%,X6S,D9A!!!F3673!B!!!!
S!P1V05_PCH_STBY_WM26_PLL!C2M8!1!@baseboard_fab2_lib.baseboard_fab2(sch_1):page127_i48@mstr_discrete.cap(chips)!CAP_0402-1.0UF,6.3V,10%,X6S,D9A!!!F3715!A!!!!
S!GND!C2M8!2!@baseboard_fab2_lib.baseboard_fab2(sch_1):page127_i48@mstr_discrete.cap(chips)!CAP_0402-1.0UF,6.3V,10%,X6S,D9A!!!F3715!B!!!!
S!FP_PWR_BTN_R1_N!C1L18!1!@baseboard_fab2_lib.baseboard_fab2(sch_1):page175_i11@mstr_discrete.cap(chips)!CAP_0402-1.0UF,6.3V,10%,X6S,D9A!!!F3737!A!!!!
S!GND!C1L18!2!@baseboard_fab2_lib.baseboard_fab2(sch_1):page175_i11@mstr_discrete.cap(chips)!CAP_0402-1.0UF,6.3V,10%,X6S,D9A!!!F3737!B!!!!
S!FP_RST_BTN_R_N!C1L10!1!@baseboard_fab2_lib.baseboard_fab2(sch_1):page175_i19@mstr_discrete.cap(chips)!CAP_0402-1.0UF,6.3V,10%,X6S,D9A!!!F3738!A!!!!
S!GND!C1L10!2!@baseboard_fab2_lib.baseboard_fab2(sch_1):page175_i19@mstr_discrete.cap(chips)!CAP_0402-1.0UF,6.3V,10%,X6S,D9A!!!F3738!B!!!!
S!P3V3_STBY!C8F4!1!@baseboard_fab2_lib.baseboard_fab2(sch_1):page162_i30@mstr_discrete.cap(chips)!CAP_0402-1.0UF,6.3V,10%,X6S,D9A!!!F3611!A!!!!
S!GND!C8F4!2!@baseboard_fab2_lib.baseboard_fab2(sch_1):page162_i30@mstr_discrete.cap(chips)!CAP_0402-1.0UF,6.3V,10%,X6S,D9A!!!F3611!B!!!!
S!P5V_STBY!C4C4!1!@baseboard_fab2_lib.baseboard_fab2(sch_1):page205_i18@mstr_discrete.cap(chips)!CAP_0402-1.0UF,6.3V,10%,X6S,D9A!!!F3640!A!!!!
S!GND!C4C4!2!@baseboard_fab2_lib.baseboard_fab2(sch_1):page205_i18@mstr_discrete.cap(chips)!CAP_0402-1.0UF,6.3V,10%,X6S,D9A!!!F3640!B!!!!
S!P5V_STBY!C3L29!1!@baseboard_fab2_lib.baseboard_fab2(sch_1):page236_i38@mstr_discrete.cap(chips)!CAP_0402-1.0UF,6.3V,10%,X6S,D9A!!!F3613!A!!!!
S!GND!C3L29!2!@baseboard_fab2_lib.baseboard_fab2(sch_1):page236_i38@mstr_discrete.cap(chips)!CAP_0402-1.0UF,6.3V,10%,X6S,D9A!!!F3613!B!!!!
S!P5V_STBY!C3L1!1!@baseboard_fab2_lib.baseboard_fab2(sch_1):page236_i17@mstr_discrete.cap(chips)!CAP_0402-1.0UF,6.3V,10%,X6S,D9A!!!F3679!A!!!!
S!GND!C3L1!2!@baseboard_fab2_lib.baseboard_fab2(sch_1):page236_i17@mstr_discrete.cap(chips)!CAP_0402-1.0UF,6.3V,10%,X6S,D9A!!!F3679!B!!!!
S!PVCCIOMCP_CPU0!C3N40!1!@baseboard_fab2_lib.baseboard_fab2(sch_1):page194_i86@mstr_discrete.cap(chips)!CAP_0402-1.0UF,6.3V,10%,X6S,D9A!!!F3644!A!!!!
S!GND!C3N40!2!@baseboard_fab2_lib.baseboard_fab2(sch_1):page194_i86@mstr_discrete.cap(chips)!CAP_0402-1.0UF,6.3V,10%,X6S,D9A!!!F3644!B!!!!
S!PVCCIOMCP_CPU0!C3M46!1!@baseboard_fab2_lib.baseboard_fab2(sch_1):page194_i99@mstr_discrete.cap(chips)!CAP_0402-1.0UF,6.3V,10%,X6S,D9A!!!F3645!A!!!!
S!GND!C3M46!2!@baseboard_fab2_lib.baseboard_fab2(sch_1):page194_i99@mstr_discrete.cap(chips)!CAP_0402-1.0UF,6.3V,10%,X6S,D9A!!!F3645!B!!!!
S!PVCCIOMCP_CPU1!C3C2!1!@baseboard_fab2_lib.baseboard_fab2(sch_1):page193_i31@mstr_discrete.cap(chips)!CAP_0402-1.0UF,6.3V,10%,X6S,D9A!!!F3680!A!!!!
S!GND!C3C2!2!@baseboard_fab2_lib.baseboard_fab2(sch_1):page193_i31@mstr_discrete.cap(chips)!CAP_0402-1.0UF,6.3V,10%,X6S,D9A!!!F3680!B!!!!
S!PVCCIOMCP_CPU1!C3C1!1!@baseboard_fab2_lib.baseboard_fab2(sch_1):page193_i38@mstr_discrete.cap(chips)!CAP_0402-1.0UF,6.3V,10%,X6S,D9A!!!F3681!A!!!!
S!GND!C3C1!2!@baseboard_fab2_lib.baseboard_fab2(sch_1):page193_i38@mstr_discrete.cap(chips)!CAP_0402-1.0UF,6.3V,10%,X6S,D9A!!!F3681!B!!!!
S!P1V8_MCP_CPU0!C4T2!1!@baseboard_fab2_lib.baseboard_fab2(sch_1):page194_i9@mstr_discrete.cap(chips)!CAP_0402-1.0UF,6.3V,10%,X6S,D9A!!!F3625!A!!!!
S!GND!C4T2!2!@baseboard_fab2_lib.baseboard_fab2(sch_1):page194_i9@mstr_discrete.cap(chips)!CAP_0402-1.0UF,6.3V,10%,X6S,D9A!!!F3625!B!!!!
S!P1V8_MCP_CPU0!C4T1!1!@baseboard_fab2_lib.baseboard_fab2(sch_1):page194_i16@mstr_discrete.cap(chips)!CAP_0402-1.0UF,6.3V,10%,X6S,D9A!!!F3626!A!!!!
S!GND!C4T1!2!@baseboard_fab2_lib.baseboard_fab2(sch_1):page194_i16@mstr_discrete.cap(chips)!CAP_0402-1.0UF,6.3V,10%,X6S,D9A!!!F3626!B!!!!
S!P1V8_MCP_CPU1!C4F1!1!@baseboard_fab2_lib.baseboard_fab2(sch_1):page193_i68@mstr_discrete.cap(chips)!CAP_0402-1.0UF,6.3V,10%,X6S,D9A!!!F3628!A!!!!
S!GND!C4F1!2!@baseboard_fab2_lib.baseboard_fab2(sch_1):page193_i68@mstr_discrete.cap(chips)!CAP_0402-1.0UF,6.3V,10%,X6S,D9A!!!F3628!B!!!!
S!P1V8_MCP_CPU1!C4F3!1!@baseboard_fab2_lib.baseboard_fab2(sch_1):page193_i70@mstr_discrete.cap(chips)!CAP_0402-1.0UF,6.3V,10%,X6S,D9A!!!F3627!A!!!!
S!GND!C4F3!2!@baseboard_fab2_lib.baseboard_fab2(sch_1):page193_i70@mstr_discrete.cap(chips)!CAP_0402-1.0UF,6.3V,10%,X6S,D9A!!!F3627!B!!!!
S!P3V3_STBY!C7F2!1!@baseboard_fab2_lib.baseboard_fab2(sch_1):page153_i130@mstr_discrete.cap(chips)!CAP_0402-1.0UF,6.3V,10%,X6S,D9A!!!F3618!A!!!!
S!GND!C7F2!2!@baseboard_fab2_lib.baseboard_fab2(sch_1):page153_i130@mstr_discrete.cap(chips)!CAP_0402-1.0UF,6.3V,10%,X6S,D9A!!!F3618!B!!!!
S!P3V3_STBY!C3T4!1!@baseboard_fab2_lib.baseboard_fab2(sch_1):page153_i138@mstr_discrete.cap(chips)!CAP_0402-1.0UF,6.3V,10%,X6S,D9A!!!F3642!A!!!!
S!GND!C3T4!2!@baseboard_fab2_lib.baseboard_fab2(sch_1):page153_i138@mstr_discrete.cap(chips)!CAP_0402-1.0UF,6.3V,10%,X6S,D9A!!!F3642!B!!!!
S!P5V_STBY!C7C20!1!@baseboard_fab2_lib.baseboard_fab2(sch_1):page212_i34@mstr_discrete.cap(chips)!CAP_0402-1.0UF,6.3V,10%,X6S,D9A!!!F3648!A!!!!
S!GND!C7C20!2!@baseboard_fab2_lib.baseboard_fab2(sch_1):page212_i34@mstr_discrete.cap(chips)!CAP_0402-1.0UF,6.3V,10%,X6S,D9A!!!F3648!B!!!!
S!P5V_STBY!C4E28!1!@baseboard_fab2_lib.baseboard_fab2(sch_1):page214_i74@mstr_discrete.cap(chips)!CAP_0402-1.0UF,6.3V,10%,X6S,D9A!!!F3624!A!!!!
S!GND!C4E28!2!@baseboard_fab2_lib.baseboard_fab2(sch_1):page214_i74@mstr_discrete.cap(chips)!CAP_0402-1.0UF,6.3V,10%,X6S,D9A!!!F3624!B!!!!
S!P5V_STBY!C4D14!1!@baseboard_fab2_lib.baseboard_fab2(sch_1):page203_i41@mstr_discrete.cap(chips)!CAP_0402-1.0UF,6.3V,10%,X6S,D9A!!!F3637!A!!!!
S!GND!C4D14!2!@baseboard_fab2_lib.baseboard_fab2(sch_1):page203_i41@mstr_discrete.cap(chips)!CAP_0402-1.0UF,6.3V,10%,X6S,D9A!!!F3637!B!!!!
S!P5V_STBY!C4D6!1!@baseboard_fab2_lib.baseboard_fab2(sch_1):page203_i49@mstr_discrete.cap(chips)!CAP_0402-1.0UF,6.3V,10%,X6S,D9A!!!F3638!A!!!!
S!GND!C4D6!2!@baseboard_fab2_lib.baseboard_fab2(sch_1):page203_i49@mstr_discrete.cap(chips)!CAP_0402-1.0UF,6.3V,10%,X6S,D9A!!!F3638!B!!!!
S!M_BMC_DDR3_MVREF!C1T51!1!@baseboard_fab2_lib.baseboard_fab2(sch_1):page151_i62@mstr_discrete.cap(chips)!CAP_0402-1.0UF,6.3V,10%,X6S,D9A!!!F3724!A!!!!
S!GND!C1T51!2!@baseboard_fab2_lib.baseboard_fab2(sch_1):page151_i62@mstr_discrete.cap(chips)!CAP_0402-1.0UF,6.3V,10%,X6S,D9A!!!F3724!B!!!!
S!PVNN_PCH_STBY!C3N5!1!@baseboard_fab2_lib.baseboard_fab2(sch_1):page132_i48@mstr_discrete.cap(chips)!CAP_0402-1.0UF,6.3V,10%,X6S,D9A!!!F3662!A!!!!
S!GND!C3N5!2!@baseboard_fab2_lib.baseboard_fab2(sch_1):page132_i48@mstr_discrete.cap(chips)!CAP_0402-1.0UF,6.3V,10%,X6S,D9A!!!F3662!B!!!!
S!PVNN_PCH_STBY!C3N20!1!@baseboard_fab2_lib.baseboard_fab2(sch_1):page132_i51@mstr_discrete.cap(chips)!CAP_0402-1.0UF,6.3V,10%,X6S,D9A!!!F3654!A!!!!
S!GND!C3N20!2!@baseboard_fab2_lib.baseboard_fab2(sch_1):page132_i51@mstr_discrete.cap(chips)!CAP_0402-1.0UF,6.3V,10%,X6S,D9A!!!F3654!B!!!!
S!PVNN_PCH_STBY!C3N4!1!@baseboard_fab2_lib.baseboard_fab2(sch_1):page132_i46@mstr_discrete.cap(chips)!CAP_0402-1.0UF,6.3V,10%,X6S,D9A!!!F3663!A!!!!
S!GND!C3N4!2!@baseboard_fab2_lib.baseboard_fab2(sch_1):page132_i46@mstr_discrete.cap(chips)!CAP_0402-1.0UF,6.3V,10%,X6S,D9A!!!F3663!B!!!!
S!PVNN_PCH_STBY!C3N15!1!@baseboard_fab2_lib.baseboard_fab2(sch_1):page132_i49@mstr_discrete.cap(chips)!CAP_0402-1.0UF,6.3V,10%,X6S,D9A!!!F3659!A!!!!
S!GND!C3N15!2!@baseboard_fab2_lib.baseboard_fab2(sch_1):page132_i49@mstr_discrete.cap(chips)!CAP_0402-1.0UF,6.3V,10%,X6S,D9A!!!F3659!B!!!!
S!PVNN_PCH_STBY!C3N2!1!@baseboard_fab2_lib.baseboard_fab2(sch_1):page132_i43@mstr_discrete.cap(chips)!CAP_0402-1.0UF,6.3V,10%,X6S,D9A!!!F3665!A!!!!
S!GND!C3N2!2!@baseboard_fab2_lib.baseboard_fab2(sch_1):page132_i43@mstr_discrete.cap(chips)!CAP_0402-1.0UF,6.3V,10%,X6S,D9A!!!F3665!B!!!!
S!PVNN_PCH_STBY!C3N17!1!@baseboard_fab2_lib.baseboard_fab2(sch_1):page132_i45@mstr_discrete.cap(chips)!CAP_0402-1.0UF,6.3V,10%,X6S,D9A!!!F3657!A!!!!
S!GND!C3N17!2!@baseboard_fab2_lib.baseboard_fab2(sch_1):page132_i45@mstr_discrete.cap(chips)!CAP_0402-1.0UF,6.3V,10%,X6S,D9A!!!F3657!B!!!!
S!PVNN_PCH_STBY!C3N18!1!@baseboard_fab2_lib.baseboard_fab2(sch_1):page132_i42@mstr_discrete.cap(chips)!CAP_0402-1.0UF,6.3V,10%,X6S,D9A!!!F3656!A!!!!
S!GND!C3N18!2!@baseboard_fab2_lib.baseboard_fab2(sch_1):page132_i42@mstr_discrete.cap(chips)!CAP_0402-1.0UF,6.3V,10%,X6S,D9A!!!F3656!B!!!!
S!PVNN_PCH_STBY!C3N6!1!@baseboard_fab2_lib.baseboard_fab2(sch_1):page132_i44@mstr_discrete.cap(chips)!CAP_0402-1.0UF,6.3V,10%,X6S,D9A!!!F3661!A!!!!
S!GND!C3N6!2!@baseboard_fab2_lib.baseboard_fab2(sch_1):page132_i44@mstr_discrete.cap(chips)!CAP_0402-1.0UF,6.3V,10%,X6S,D9A!!!F3661!B!!!!
S!PVNN_PCH_STBY!C3N3!1!@baseboard_fab2_lib.baseboard_fab2(sch_1):page132_i32@mstr_discrete.cap(chips)!CAP_0402-1.0UF,6.3V,10%,X6S,D9A!!!F3664!A!!!!
S!GND!C3N3!2!@baseboard_fab2_lib.baseboard_fab2(sch_1):page132_i32@mstr_discrete.cap(chips)!CAP_0402-1.0UF,6.3V,10%,X6S,D9A!!!F3664!B!!!!
S!PVNN_PCH_STBY!C3N16!1!@baseboard_fab2_lib.baseboard_fab2(sch_1):page132_i36@mstr_discrete.cap(chips)!CAP_0402-1.0UF,6.3V,10%,X6S,D9A!!!F3658!A!!!!
S!GND!C3N16!2!@baseboard_fab2_lib.baseboard_fab2(sch_1):page132_i36@mstr_discrete.cap(chips)!CAP_0402-1.0UF,6.3V,10%,X6S,D9A!!!F3658!B!!!!
S!PVNN_PCH_STBY!C3N19!1!@baseboard_fab2_lib.baseboard_fab2(sch_1):page132_i31@mstr_discrete.cap(chips)!CAP_0402-1.0UF,6.3V,10%,X6S,D9A!!!F3655!A!!!!
S!GND!C3N19!2!@baseboard_fab2_lib.baseboard_fab2(sch_1):page132_i31@mstr_discrete.cap(chips)!CAP_0402-1.0UF,6.3V,10%,X6S,D9A!!!F3655!B!!!!
S!PVNN_PCH_STBY!C3N7!1!@baseboard_fab2_lib.baseboard_fab2(sch_1):page132_i35@mstr_discrete.cap(chips)!CAP_0402-1.0UF,6.3V,10%,X6S,D9A!!!F3660!A!!!!
S!GND!C3N7!2!@baseboard_fab2_lib.baseboard_fab2(sch_1):page132_i35@mstr_discrete.cap(chips)!CAP_0402-1.0UF,6.3V,10%,X6S,D9A!!!F3660!B!!!!
S!PVNN_PCH_STBY!C2N11!1!@baseboard_fab2_lib.baseboard_fab2(sch_1):page132_i30@mstr_discrete.cap(chips)!CAP_0402-1.0UF,6.3V,10%,X6S,D9A!!!F3699!A!!!!
S!GND!C2N11!2!@baseboard_fab2_lib.baseboard_fab2(sch_1):page132_i30@mstr_discrete.cap(chips)!CAP_0402-1.0UF,6.3V,10%,X6S,D9A!!!F3699!B!!!!
S!PVNN_PCH_STBY!C3N1!1!@baseboard_fab2_lib.baseboard_fab2(sch_1):page132_i34@mstr_discrete.cap(chips)!CAP_0402-1.0UF,6.3V,10%,X6S,D9A!!!F3666!A!!!!
S!GND!C3N1!2!@baseboard_fab2_lib.baseboard_fab2(sch_1):page132_i34@mstr_discrete.cap(chips)!CAP_0402-1.0UF,6.3V,10%,X6S,D9A!!!F3666!B!!!!
S!PVNN_PCH_STBY!C2N3!1!@baseboard_fab2_lib.baseboard_fab2(sch_1):page132_i27@mstr_discrete.cap(chips)!CAP_0402-1.0UF,6.3V,10%,X6S,D9A!!!F3705!A!!!!
S!GND!C2N3!2!@baseboard_fab2_lib.baseboard_fab2(sch_1):page132_i27@mstr_discrete.cap(chips)!CAP_0402-1.0UF,6.3V,10%,X6S,D9A!!!F3705!B!!!!
S!PVNN_PCH_STBY!C2N12!1!@baseboard_fab2_lib.baseboard_fab2(sch_1):page132_i29@mstr_discrete.cap(chips)!CAP_0402-1.0UF,6.3V,10%,X6S,D9A!!!F3698!A!!!!
S!GND!C2N12!2!@baseboard_fab2_lib.baseboard_fab2(sch_1):page132_i29@mstr_discrete.cap(chips)!CAP_0402-1.0UF,6.3V,10%,X6S,D9A!!!F3698!B!!!!
S!PVNN_PCH_STBY!C2N9!1!@baseboard_fab2_lib.baseboard_fab2(sch_1):page132_i26@mstr_discrete.cap(chips)!CAP_0402-1.0UF,6.3V,10%,X6S,D9A!!!F3700!A!!!!
S!GND!C2N9!2!@baseboard_fab2_lib.baseboard_fab2(sch_1):page132_i26@mstr_discrete.cap(chips)!CAP_0402-1.0UF,6.3V,10%,X6S,D9A!!!F3700!B!!!!
S!PVNN_PCH_STBY!C2N4!1!@baseboard_fab2_lib.baseboard_fab2(sch_1):page132_i28@mstr_discrete.cap(chips)!CAP_0402-1.0UF,6.3V,10%,X6S,D9A!!!F3704!A!!!!
S!GND!C2N4!2!@baseboard_fab2_lib.baseboard_fab2(sch_1):page132_i28@mstr_discrete.cap(chips)!CAP_0402-1.0UF,6.3V,10%,X6S,D9A!!!F3704!B!!!!
S!P1V8_PCH_STBY!C3N21!1!@baseboard_fab2_lib.baseboard_fab2(sch_1):page130_i49@mstr_discrete.cap(chips)!CAP_0402-1.0UF,6.3V,10%,X6S,D9A!!!F3653!A!!!!
S!GND!C3N21!2!@baseboard_fab2_lib.baseboard_fab2(sch_1):page130_i49@mstr_discrete.cap(chips)!CAP_0402-1.0UF,6.3V,10%,X6S,D9A!!!F3653!B!!!!
S!P3V3_STBY!C2M16!1!@baseboard_fab2_lib.baseboard_fab2(sch_1):page130_i37@mstr_discrete.cap(chips)!CAP_0402-1.0UF,6.3V,10%,X6S,D9A!!!F3713!A!!!!
S!GND!C2M16!2!@baseboard_fab2_lib.baseboard_fab2(sch_1):page130_i37@mstr_discrete.cap(chips)!CAP_0402-1.0UF,6.3V,10%,X6S,D9A!!!F3713!B!!!!
S!P3V3_STBY!C2N25!1!@baseboard_fab2_lib.baseboard_fab2(sch_1):page130_i34@mstr_discrete.cap(chips)!CAP_0402-1.0UF,6.3V,10%,X6S,D9A!!!F3691!A!!!!
S!GND!C2N25!2!@baseboard_fab2_lib.baseboard_fab2(sch_1):page130_i34@mstr_discrete.cap(chips)!CAP_0402-1.0UF,6.3V,10%,X6S,D9A!!!F3691!B!!!!
S!P3V3_STBY!C2N18!1!@baseboard_fab2_lib.baseboard_fab2(sch_1):page130_i29@mstr_discrete.cap(chips)!CAP_0402-1.0UF,6.3V,10%,X6S,D9A!!!F3694!A!!!!
S!GND!C2N18!2!@baseboard_fab2_lib.baseboard_fab2(sch_1):page130_i29@mstr_discrete.cap(chips)!CAP_0402-1.0UF,6.3V,10%,X6S,D9A!!!F3694!B!!!!
S!P1V8_PCH_STBY!C2N15!1!@baseboard_fab2_lib.baseboard_fab2(sch_1):page130_i47@mstr_discrete.cap(chips)!CAP_0402-1.0UF,6.3V,10%,X6S,D9A!!!F3696!A!!!!
S!GND!C2N15!2!@baseboard_fab2_lib.baseboard_fab2(sch_1):page130_i47@mstr_discrete.cap(chips)!CAP_0402-1.0UF,6.3V,10%,X6S,D9A!!!F3696!B!!!!
S!P1V05_PCH_STBY!C2N2!1!@baseboard_fab2_lib.baseboard_fab2(sch_1):page131_i41@mstr_discrete.cap(chips)!CAP_0402-1.0UF,6.3V,10%,X6S,D9A!!!F3706!A!!!!
S!GND!C2N2!2!@baseboard_fab2_lib.baseboard_fab2(sch_1):page131_i41@mstr_discrete.cap(chips)!CAP_0402-1.0UF,6.3V,10%,X6S,D9A!!!F3706!B!!!!
S!P1V05_PCH_STBY!C2N13!1!@baseboard_fab2_lib.baseboard_fab2(sch_1):page131_i40@mstr_discrete.cap(chips)!CAP_0402-1.0UF,6.3V,10%,X6S,D9A!!!F3697!A!!!!
S!GND!C2N13!2!@baseboard_fab2_lib.baseboard_fab2(sch_1):page131_i40@mstr_discrete.cap(chips)!CAP_0402-1.0UF,6.3V,10%,X6S,D9A!!!F3697!B!!!!
S!P1V05_PCH_STBY!C2M20!1!@baseboard_fab2_lib.baseboard_fab2(sch_1):page131_i39@mstr_discrete.cap(chips)!CAP_0402-1.0UF,6.3V,10%,X6S,D9A!!!F3710!A!!!!
S!GND!C2M20!2!@baseboard_fab2_lib.baseboard_fab2(sch_1):page131_i39@mstr_discrete.cap(chips)!CAP_0402-1.0UF,6.3V,10%,X6S,D9A!!!F3710!B!!!!
S!P1V05_PCH_STBY!C2M18!1!@baseboard_fab2_lib.baseboard_fab2(sch_1):page131_i29@mstr_discrete.cap(chips)!CAP_0402-1.0UF,6.3V,10%,X6S,D9A!!!F3712!A!!!!
S!GND!C2M18!2!@baseboard_fab2_lib.baseboard_fab2(sch_1):page131_i29@mstr_discrete.cap(chips)!CAP_0402-1.0UF,6.3V,10%,X6S,D9A!!!F3712!B!!!!
S!P3V3_STBY!C2N20!1!@baseboard_fab2_lib.baseboard_fab2(sch_1):page130_i12@mstr_discrete.cap(chips)!CAP_0402-1.0UF,6.3V,10%,X6S,D9A!!!F3692!A!!!!
S!GND!C2N20!2!@baseboard_fab2_lib.baseboard_fab2(sch_1):page130_i12@mstr_discrete.cap(chips)!CAP_0402-1.0UF,6.3V,10%,X6S,D9A!!!F3692!B!!!!
S!P1V05_PCH_STBY!C2M21!1!@baseboard_fab2_lib.baseboard_fab2(sch_1):page131_i28@mstr_discrete.cap(chips)!CAP_0402-1.0UF,6.3V,10%,X6S,D9A!!!F3709!A!!!!
S!GND!C2M21!2!@baseboard_fab2_lib.baseboard_fab2(sch_1):page131_i28@mstr_discrete.cap(chips)!CAP_0402-1.0UF,6.3V,10%,X6S,D9A!!!F3709!B!!!!
S!P3V3_STBY!C2N19!1!@baseboard_fab2_lib.baseboard_fab2(sch_1):page130_i7@mstr_discrete.cap(chips)!CAP_0402-1.0UF,6.3V,10%,X6S,D9A!!!F3693!A!!!!
S!GND!C2N19!2!@baseboard_fab2_lib.baseboard_fab2(sch_1):page130_i7@mstr_discrete.cap(chips)!CAP_0402-1.0UF,6.3V,10%,X6S,D9A!!!F3693!B!!!!
S!P1V05_PCH_STBY!C2N8!1!@baseboard_fab2_lib.baseboard_fab2(sch_1):page131_i47@mstr_discrete.cap(chips)!CAP_0402-1.0UF,6.3V,10%,X6S,D9A!!!F3701!A!!!!
S!GND!C2N8!2!@baseboard_fab2_lib.baseboard_fab2(sch_1):page131_i47@mstr_discrete.cap(chips)!CAP_0402-1.0UF,6.3V,10%,X6S,D9A!!!F3701!B!!!!
S!P1V05_PCH_STBY!C2N7!1!@baseboard_fab2_lib.baseboard_fab2(sch_1):page131_i43@mstr_discrete.cap(chips)!CAP_0402-1.0UF,6.3V,10%,X6S,D9A!!!F3702!A!!!!
S!GND!C2N7!2!@baseboard_fab2_lib.baseboard_fab2(sch_1):page131_i43@mstr_discrete.cap(chips)!CAP_0402-1.0UF,6.3V,10%,X6S,D9A!!!F3702!B!!!!
S!P1V05_PCH_STBY!C3M43!1!@baseboard_fab2_lib.baseboard_fab2(sch_1):page131_i42@mstr_discrete.cap(chips)!CAP_0402-1.0UF,6.3V,10%,X6S,D9A!!!F3667!A!!!!
S!GND!C3M43!2!@baseboard_fab2_lib.baseboard_fab2(sch_1):page131_i42@mstr_discrete.cap(chips)!CAP_0402-1.0UF,6.3V,10%,X6S,D9A!!!F3667!B!!!!
S!P1V05_PCH_STBY!C3M38!1!@baseboard_fab2_lib.baseboard_fab2(sch_1):page131_i32@mstr_discrete.cap(chips)!CAP_0402-1.0UF,6.3V,10%,X6S,D9A!!!F3670!A!!!!
S!GND!C3M38!2!@baseboard_fab2_lib.baseboard_fab2(sch_1):page131_i32@mstr_discrete.cap(chips)!CAP_0402-1.0UF,6.3V,10%,X6S,D9A!!!F3670!B!!!!
S!P1V05_PCH_STBY!C2M19!1!@baseboard_fab2_lib.baseboard_fab2(sch_1):page131_i31@mstr_discrete.cap(chips)!CAP_0402-1.0UF,6.3V,10%,X6S,D9A!!!F3711!A!!!!
S!GND!C2M19!2!@baseboard_fab2_lib.baseboard_fab2(sch_1):page131_i31@mstr_discrete.cap(chips)!CAP_0402-1.0UF,6.3V,10%,X6S,D9A!!!F3711!B!!!!
S!P1V05_PCH_STBY!C2M22!1!@baseboard_fab2_lib.baseboard_fab2(sch_1):page131_i27@mstr_discrete.cap(chips)!CAP_0402-1.0UF,6.3V,10%,X6S,D9A!!!F3708!A!!!!
S!GND!C2M22!2!@baseboard_fab2_lib.baseboard_fab2(sch_1):page131_i27@mstr_discrete.cap(chips)!CAP_0402-1.0UF,6.3V,10%,X6S,D9A!!!F3708!B!!!!
S!P1V8_PCH_STBY!C3N22!1!@baseboard_fab2_lib.baseboard_fab2(sch_1):page130_i53@mstr_discrete.cap(chips)!CAP_0402-1.0UF,6.3V,10%,X6S,D9A!!!F3652!A!!!!
S!GND!C3N22!2!@baseboard_fab2_lib.baseboard_fab2(sch_1):page130_i53@mstr_discrete.cap(chips)!CAP_0402-1.0UF,6.3V,10%,X6S,D9A!!!F3652!B!!!!
S!P3V3_STBY!C3N23!1!@baseboard_fab2_lib.baseboard_fab2(sch_1):page130_i42@mstr_discrete.cap(chips)!CAP_0402-1.0UF,6.3V,10%,X6S,D9A!!!F3651!A!!!!
S!GND!C3N23!2!@baseboard_fab2_lib.baseboard_fab2(sch_1):page130_i42@mstr_discrete.cap(chips)!CAP_0402-1.0UF,6.3V,10%,X6S,D9A!!!F3651!B!!!!
S!P1V8_PCH_STBY!C2N16!1!@baseboard_fab2_lib.baseboard_fab2(sch_1):page130_i52@mstr_discrete.cap(chips)!CAP_0402-1.0UF,6.3V,10%,X6S,D9A!!!F3695!A!!!!
S!GND!C2N16!2!@baseboard_fab2_lib.baseboard_fab2(sch_1):page130_i52@mstr_discrete.cap(chips)!CAP_0402-1.0UF,6.3V,10%,X6S,D9A!!!F3695!B!!!!
S!P3V3_STBY!C2N26!1!@baseboard_fab2_lib.baseboard_fab2(sch_1):page130_i4@mstr_discrete.cap(chips)!CAP_0402-1.0UF,6.3V,10%,X6S,D9A!!!F3690!A!!!!
S!GND!C2N26!2!@baseboard_fab2_lib.baseboard_fab2(sch_1):page130_i4@mstr_discrete.cap(chips)!CAP_0402-1.0UF,6.3V,10%,X6S,D9A!!!F3690!B!!!!
S!P1V8_PCH_STBY!C3N25!1!@baseboard_fab2_lib.baseboard_fab2(sch_1):page130_i50@mstr_discrete.cap(chips)!CAP_0402-1.0UF,6.3V,10%,X6S,D9A!!!F3650!A!!!!
S!GND!C3N25!2!@baseboard_fab2_lib.baseboard_fab2(sch_1):page130_i50@mstr_discrete.cap(chips)!CAP_0402-1.0UF,6.3V,10%,X6S,D9A!!!F3650!B!!!!
S!P3V3_STBY_BMC_ADCAV33!C1U18!1!@baseboard_fab2_lib.baseboard_fab2(sch_1):page149_i141@mstr_discrete.cap(chips)!CAP_0402-1.0UF,6.3V,10%,X6S,D9A!!!F3719!A!!!!
S!GND!C1U18!2!@baseboard_fab2_lib.baseboard_fab2(sch_1):page149_i141@mstr_discrete.cap(chips)!CAP_0402-1.0UF,6.3V,10%,X6S,D9A!!!F3719!B!!!!
S!P5V_STBY!C1C18!1!@baseboard_fab2_lib.baseboard_fab2(sch_1):page209_i21@mstr_discrete.cap(chips)!CAP_0402-1.0UF,6.3V,10%,X6S,D9A!!!F3748!A!!!!
S!GND!C1C18!2!@baseboard_fab2_lib.baseboard_fab2(sch_1):page209_i21@mstr_discrete.cap(chips)!CAP_0402-1.0UF,6.3V,10%,X6S,D9A!!!F3748!B!!!!
S!P3V3!C2T33!1!@baseboard_fab2_lib.baseboard_fab2(sch_1):page93_i72@mstr_discrete.cap(chips)!CAP_0402-1.0UF,6.3V,10%,X6S,D9A!!!F3684!A!!!!
S!GND!C2T33!2!@baseboard_fab2_lib.baseboard_fab2(sch_1):page93_i72@mstr_discrete.cap(chips)!CAP_0402-1.0UF,6.3V,10%,X6S,D9A!!!F3684!B!!!!
S!P3V3_STBY!C2T28!1!@baseboard_fab2_lib.baseboard_fab2(sch_1):page101_i116@mstr_discrete.cap(chips)!CAP_0402-1.0UF,6.3V,10%,X6S,D9A!!!F3686!A!!!!
S!GND!C2T28!2!@baseboard_fab2_lib.baseboard_fab2(sch_1):page101_i116@mstr_discrete.cap(chips)!CAP_0402-1.0UF,6.3V,10%,X6S,D9A!!!F3686!B!!!!
S!P3V3_STBY_MNG_CPU!C2T19!1!@baseboard_fab2_lib.baseboard_fab2(sch_1):page101_i106@mstr_discrete.cap(chips)!CAP_0402-1.0UF,6.3V,10%,X6S,D9A!!!F3687!A!!!!
S!GND!C2T19!2!@baseboard_fab2_lib.baseboard_fab2(sch_1):page101_i106@mstr_discrete.cap(chips)!CAP_0402-1.0UF,6.3V,10%,X6S,D9A!!!F3687!B!!!!
S!P3V3_STBY_MNG_RMII!C2T38!1!@baseboard_fab2_lib.baseboard_fab2(sch_1):page101_i97@mstr_discrete.cap(chips)!CAP_0402-1.0UF,6.3V,10%,X6S,D9A!!!F3683!A!!!!
S!GND!C2T38!2!@baseboard_fab2_lib.baseboard_fab2(sch_1):page101_i97@mstr_discrete.cap(chips)!CAP_0402-1.0UF,6.3V,10%,X6S,D9A!!!F3683!B!!!!
S!P3V3_STBY_MNG_RGMII!C2T31!1!@baseboard_fab2_lib.baseboard_fab2(sch_1):page101_i89@mstr_discrete.cap(chips)!CAP_0402-1.0UF,6.3V,10%,X6S,D9A!!!F3685!A!!!!
S!GND!C2T31!2!@baseboard_fab2_lib.baseboard_fab2(sch_1):page101_i89@mstr_discrete.cap(chips)!CAP_0402-1.0UF,6.3V,10%,X6S,D9A!!!F3685!B!!!!
S!P1V05_PCH_STBY!C3M21!1!@baseboard_fab2_lib.baseboard_fab2(sch_1):page127_i9@mstr_discrete.cap(chips)!CAP_0402-1.0UF,6.3V,10%,X6S,D9A!!!F3676!A!!!!
S!GND!C3M21!2!@baseboard_fab2_lib.baseboard_fab2(sch_1):page127_i9@mstr_discrete.cap(chips)!CAP_0402-1.0UF,6.3V,10%,X6S,D9A!!!F3676!B!!!!
S!P1V05_PCH_STBY!C3M22!1!@baseboard_fab2_lib.baseboard_fab2(sch_1):page127_i18@mstr_discrete.cap(chips)!CAP_0402-1.0UF,6.3V,10%,X6S,D9A!!!F3675!A!!!!
S!GND!C3M22!2!@baseboard_fab2_lib.baseboard_fab2(sch_1):page127_i18@mstr_discrete.cap(chips)!CAP_0402-1.0UF,6.3V,10%,X6S,D9A!!!F3675!B!!!!
S!P1V05_PCH_STBY!C3M30!1!@baseboard_fab2_lib.baseboard_fab2(sch_1):page127_i27@mstr_discrete.cap(chips)!CAP_0402-1.0UF,6.3V,10%,X6S,D9A!!!F3672!A!!!!
S!GND!C3M30!2!@baseboard_fab2_lib.baseboard_fab2(sch_1):page127_i27@mstr_discrete.cap(chips)!CAP_0402-1.0UF,6.3V,10%,X6S,D9A!!!F3672!B!!!!
S!P3V3_STBY!C3P42!1!@baseboard_fab2_lib.baseboard_fab2(sch_1):page96_i73@mstr_discrete.cap(chips)!CAP_0402-1.0UF,6.3V,10%,X6S,D9A!!!F3643!A!!!!
S!GND!C3P42!2!@baseboard_fab2_lib.baseboard_fab2(sch_1):page96_i73@mstr_discrete.cap(chips)!CAP_0402-1.0UF,6.3V,10%,X6S,D9A!!!F3643!B!!!!
S!P3V3_STBY!C4C3!1!@baseboard_fab2_lib.baseboard_fab2(sch_1):page96_i75@mstr_discrete.cap(chips)!CAP_0402-1.0UF,6.3V,10%,X6S,D9A!!!F3641!A!!!!
S!GND!C4C3!2!@baseboard_fab2_lib.baseboard_fab2(sch_1):page96_i75@mstr_discrete.cap(chips)!CAP_0402-1.0UF,6.3V,10%,X6S,D9A!!!F3641!B!!!!
S!P1V26_BMC_STBY!C1T28!1!@baseboard_fab2_lib.baseboard_fab2(sch_1):page149_i77@mstr_discrete.cap(chips)!CAP_0402-1.0UF,6.3V,10%,X6S,D9A!!!F3730!A!!!!
S!GND!C1T28!2!@baseboard_fab2_lib.baseboard_fab2(sch_1):page149_i77@mstr_discrete.cap(chips)!CAP_0402-1.0UF,6.3V,10%,X6S,D9A!!!F3730!B!!!!
S!P1V538_BMC_STBY!C1T32!1!@baseboard_fab2_lib.baseboard_fab2(sch_1):page149_i89@mstr_discrete.cap(chips)!CAP_0402-1.0UF,6.3V,10%,X6S,D9A!!!F3728!A!!!!
S!GND!C1T32!2!@baseboard_fab2_lib.baseboard_fab2(sch_1):page149_i89@mstr_discrete.cap(chips)!CAP_0402-1.0UF,6.3V,10%,X6S,D9A!!!F3728!B!!!!
S!P1V26_BMC_STBY!C1U6!1!@baseboard_fab2_lib.baseboard_fab2(sch_1):page149_i78@mstr_discrete.cap(chips)!CAP_0402-1.0UF,6.3V,10%,X6S,D9A!!!F3722!A!!!!
S!GND!C1U6!2!@baseboard_fab2_lib.baseboard_fab2(sch_1):page149_i78@mstr_discrete.cap(chips)!CAP_0402-1.0UF,6.3V,10%,X6S,D9A!!!F3722!B!!!!
S!P1V538_BMC_STBY!C1T55!1!@baseboard_fab2_lib.baseboard_fab2(sch_1):page149_i90@mstr_discrete.cap(chips)!CAP_0402-1.0UF,6.3V,10%,X6S,D9A!!!F3723!A!!!!
S!GND!C1T55!2!@baseboard_fab2_lib.baseboard_fab2(sch_1):page149_i90@mstr_discrete.cap(chips)!CAP_0402-1.0UF,6.3V,10%,X6S,D9A!!!F3723!B!!!!
S!P1V26_BMC_STBY!C1U7!1!@baseboard_fab2_lib.baseboard_fab2(sch_1):page149_i79@mstr_discrete.cap(chips)!CAP_0402-1.0UF,6.3V,10%,X6S,D9A!!!F3721!A!!!!
S!GND!C1U7!2!@baseboard_fab2_lib.baseboard_fab2(sch_1):page149_i79@mstr_discrete.cap(chips)!CAP_0402-1.0UF,6.3V,10%,X6S,D9A!!!F3721!B!!!!
S!P1V538_BMC_STBY!C1T46!1!@baseboard_fab2_lib.baseboard_fab2(sch_1):page149_i91@mstr_discrete.cap(chips)!CAP_0402-1.0UF,6.3V,10%,X6S,D9A!!!F3726!A!!!!
S!GND!C1T46!2!@baseboard_fab2_lib.baseboard_fab2(sch_1):page149_i91@mstr_discrete.cap(chips)!CAP_0402-1.0UF,6.3V,10%,X6S,D9A!!!F3726!B!!!!
S!P1V538_BMC_STBY!C1T31!1!@baseboard_fab2_lib.baseboard_fab2(sch_1):page149_i92@mstr_discrete.cap(chips)!CAP_0402-1.0UF,6.3V,10%,X6S,D9A!!!F3729!A!!!!
S!GND!C1T31!2!@baseboard_fab2_lib.baseboard_fab2(sch_1):page149_i92@mstr_discrete.cap(chips)!CAP_0402-1.0UF,6.3V,10%,X6S,D9A!!!F3729!B!!!!
S!P1V538_BMC_STBY!C1T35!1!@baseboard_fab2_lib.baseboard_fab2(sch_1):page149_i93@mstr_discrete.cap(chips)!CAP_0402-1.0UF,6.3V,10%,X6S,D9A!!!F3727!A!!!!
S!GND!C1T35!2!@baseboard_fab2_lib.baseboard_fab2(sch_1):page149_i93@mstr_discrete.cap(chips)!CAP_0402-1.0UF,6.3V,10%,X6S,D9A!!!F3727!B!!!!
S!P1V538_BMC_STBY!C1T49!1!@baseboard_fab2_lib.baseboard_fab2(sch_1):page149_i94@mstr_discrete.cap(chips)!CAP_0402-1.0UF,6.3V,10%,X6S,D9A!!!F3725!A!!!!
S!GND!C1T49!2!@baseboard_fab2_lib.baseboard_fab2(sch_1):page149_i94@mstr_discrete.cap(chips)!CAP_0402-1.0UF,6.3V,10%,X6S,D9A!!!F3725!B!!!!
S!P1V26_BMC_STBY_V1PLLAV12!C9F12!1!@baseboard_fab2_lib.baseboard_fab2(sch_1):page149_i106@mstr_discrete.cap(chips)!CAP_0402-1.0UF,6.3V,10%,X6S,D9A!!!F3608!A!!!!
S!GND!C9F12!2!@baseboard_fab2_lib.baseboard_fab2(sch_1):page149_i106@mstr_discrete.cap(chips)!CAP_0402-1.0UF,6.3V,10%,X6S,D9A!!!F3608!B!!!!
S!P3V3_STBY_BMC_HPLLAV33!C1T19!1!@baseboard_fab2_lib.baseboard_fab2(sch_1):page149_i121@mstr_discrete.cap(chips)!CAP_0402-1.0UF,6.3V,10%,X6S,D9A!!!F3732!A!!!!
S!GND!C1T19!2!@baseboard_fab2_lib.baseboard_fab2(sch_1):page149_i121@mstr_discrete.cap(chips)!CAP_0402-1.0UF,6.3V,10%,X6S,D9A!!!F3732!B!!!!
S!PVCCIO_CPU0!C1T21!1!@baseboard_fab2_lib.baseboard_fab2(sch_1):page148_i28@mstr_discrete.cap(chips)!CAP_0402-1.0UF,6.3V,10%,X6S,D9A!!!F3731!A!!!!
S!GND!C1T21!2!@baseboard_fab2_lib.baseboard_fab2(sch_1):page148_i28@mstr_discrete.cap(chips)!CAP_0402-1.0UF,6.3V,10%,X6S,D9A!!!F3731!B!!!!
S!P3V3_STBY!C1M37!1!@baseboard_fab2_lib.baseboard_fab2(sch_1):page112_i47@mstr_discrete.cap(chips)!CAP_0402-1.0UF,6.3V,10%,X6S,D9A!!!F3609!A!!!!
S!GND!C1M37!2!@baseboard_fab2_lib.baseboard_fab2(sch_1):page112_i47@mstr_discrete.cap(chips)!CAP_0402-1.0UF,6.3V,10%,X6S,D9A!!!F3609!B!!!!
S!P1V05_PCH_STBY!C3M31!1!@baseboard_fab2_lib.baseboard_fab2(sch_1):page127_i57@mstr_discrete.cap(chips)!CAP_0402-1.0UF,6.3V,10%,X6S,D9A!!!F3671!A!!!!
S!GND!C3M31!2!@baseboard_fab2_lib.baseboard_fab2(sch_1):page127_i57@mstr_discrete.cap(chips)!CAP_0402-1.0UF,6.3V,10%,X6S,D9A!!!F3671!B!!!!
S!P1V05_PCH_STBY_KR_PLL!C2N5!1!@baseboard_fab2_lib.baseboard_fab2(sch_1):page127_i65@mstr_discrete.cap(chips)!CAP_0402-1.0UF,6.3V,10%,X6S,D9A!!!F3703!A!!!!
S!GND!C2N5!2!@baseboard_fab2_lib.baseboard_fab2(sch_1):page127_i65@mstr_discrete.cap(chips)!CAP_0402-1.0UF,6.3V,10%,X6S,D9A!!!F3703!B!!!!
S!P1V05_PCH_STBY_WM20_PLL!C2M7!1!@baseboard_fab2_lib.baseboard_fab2(sch_1):page127_i44@mstr_discrete.cap(chips)!CAP_0402-1.0UF,6.3V,10%,X6S,D9A!!!F3716!A!!!!
S!GND!C2M7!2!@baseboard_fab2_lib.baseboard_fab2(sch_1):page127_i44@mstr_discrete.cap(chips)!CAP_0402-1.0UF,6.3V,10%,X6S,D9A!!!F3716!B!!!!
S!P1V05_PCH_STBY_WM26_PLL!C2M9!1!@baseboard_fab2_lib.baseboard_fab2(sch_1):page127_i50@mstr_discrete.cap(chips)!CAP_0402-1.0UF,6.3V,10%,X6S,D9A!!!F3714!A!!!!
S!GND!C2M9!2!@baseboard_fab2_lib.baseboard_fab2(sch_1):page127_i50@mstr_discrete.cap(chips)!CAP_0402-1.0UF,6.3V,10%,X6S,D9A!!!F3714!B!!!!
S!P5V_STBY!C4E25!1!@baseboard_fab2_lib.baseboard_fab2(sch_1):page202_i25@mstr_discrete.cap(chips)!CAP_0402-1.0UF,6.3V,10%,X6S,D9A!!!F3630!A!!!!
S!GND!C4E25!2!@baseboard_fab2_lib.baseboard_fab2(sch_1):page202_i25@mstr_discrete.cap(chips)!CAP_0402-1.0UF,6.3V,10%,X6S,D9A!!!F3630!B!!!!
S!P5V_STBY!C4E6!1!@baseboard_fab2_lib.baseboard_fab2(sch_1):page202_i19@mstr_discrete.cap(chips)!CAP_0402-1.0UF,6.3V,10%,X6S,D9A!!!F3629!A!!!!
S!GND!C4E6!2!@baseboard_fab2_lib.baseboard_fab2(sch_1):page202_i19@mstr_discrete.cap(chips)!CAP_0402-1.0UF,6.3V,10%,X6S,D9A!!!F3629!B!!!!
S!P5V_STBY!C4C14!1!@baseboard_fab2_lib.baseboard_fab2(sch_1):page204_i19@mstr_discrete.cap(chips)!CAP_0402-1.0UF,6.3V,10%,X6S,D9A!!!F3639!A!!!!
S!GND!C4C14!2!@baseboard_fab2_lib.baseboard_fab2(sch_1):page204_i19@mstr_discrete.cap(chips)!CAP_0402-1.0UF,6.3V,10%,X6S,D9A!!!F3639!B!!!!
S!P1V05_PCH_STBY!C1L5!1!@baseboard_fab2_lib.baseboard_fab2(sch_1):page111_i30@mstr_discrete.cap(chips)!CAP_0402-1.0UF,6.3V,10%,X6S,D9A!!!F3739!A!!!!
S!GND!C1L5!2!@baseboard_fab2_lib.baseboard_fab2(sch_1):page111_i30@mstr_discrete.cap(chips)!CAP_0402-1.0UF,6.3V,10%,X6S,D9A!!!F3739!B!!!!
S!P1V05_PCH_STBY!C9A6!1!@baseboard_fab2_lib.baseboard_fab2(sch_1):page111_i25@mstr_discrete.cap(chips)!CAP_0402-1.0UF,6.3V,10%,X6S,D9A!!!F3610!A!!!!
S!GND!C9A6!2!@baseboard_fab2_lib.baseboard_fab2(sch_1):page111_i25@mstr_discrete.cap(chips)!CAP_0402-1.0UF,6.3V,10%,X6S,D9A!!!F3610!B!!!!
S!P1V05_PCH_STBY!C3M42!1!@baseboard_fab2_lib.baseboard_fab2(sch_1):page131_i45@mstr_discrete.cap(chips)!CAP_0402-1.0UF,6.3V,10%,X6S,D9A!!!F3668!A!!!!
S!GND!C3M42!2!@baseboard_fab2_lib.baseboard_fab2(sch_1):page131_i45@mstr_discrete.cap(chips)!CAP_0402-1.0UF,6.3V,10%,X6S,D9A!!!F3668!B!!!!
S!P1V05_PCH_STBY!C3M39!1!@baseboard_fab2_lib.baseboard_fab2(sch_1):page131_i44@mstr_discrete.cap(chips)!CAP_0402-1.0UF,6.3V,10%,X6S,D9A!!!F3669!A!!!!
S!GND!C3M39!2!@baseboard_fab2_lib.baseboard_fab2(sch_1):page131_i44@mstr_discrete.cap(chips)!CAP_0402-1.0UF,6.3V,10%,X6S,D9A!!!F3669!B!!!!
S!RST_SRTCRST_N!C3N32!1!@baseboard_fab2_lib.baseboard_fab2(sch_1):page137_i20@mstr_discrete.cap(chips)!CAP_0402-1.0UF,6.3V,10%,X6S,D9A!!!F3649!A!!!!
S!GND!C3N32!2!@baseboard_fab2_lib.baseboard_fab2(sch_1):page137_i20@mstr_discrete.cap(chips)!CAP_0402-1.0UF,6.3V,10%,X6S,D9A!!!F3649!B!!!!
S!RST_RTCRST_N!C7C19!1!@baseboard_fab2_lib.baseboard_fab2(sch_1):page137_i14@mstr_discrete.cap(chips)!CAP_0402-1.0UF,6.3V,10%,X6S,D9A!!!F3619!A!!!!
S!GND!C7C19!2!@baseboard_fab2_lib.baseboard_fab2(sch_1):page137_i14@mstr_discrete.cap(chips)!CAP_0402-1.0UF,6.3V,10%,X6S,D9A!!!F3619!B!!!!
S!P3V3_STBY!C1T12!1!@baseboard_fab2_lib.baseboard_fab2(sch_1):page149_i8@mstr_discrete.cap(chips)!CAP_0402-1.0UF,6.3V,10%,X6S,D9A!!!F3733!A!!!!
S!GND!C1T12!2!@baseboard_fab2_lib.baseboard_fab2(sch_1):page149_i8@mstr_discrete.cap(chips)!CAP_0402-1.0UF,6.3V,10%,X6S,D9A!!!F3733!B!!!!
S!P3V3_STBY!C1U8!1!@baseboard_fab2_lib.baseboard_fab2(sch_1):page149_i19@mstr_discrete.cap(chips)!CAP_0402-1.0UF,6.3V,10%,X6S,D9A!!!F3720!A!!!!
S!GND!C1U8!2!@baseboard_fab2_lib.baseboard_fab2(sch_1):page149_i19@mstr_discrete.cap(chips)!CAP_0402-1.0UF,6.3V,10%,X6S,D9A!!!F3720!B!!!!
S!P5V_STBY!C7G35!1!@baseboard_fab2_lib.baseboard_fab2(sch_1):page216_i53@mstr_discrete.cap(chips)!CAP_0402-1.0UF,6.3V,10%,X6S,D9A!!!F3615!A!!!!
S!GND!C7G35!2!@baseboard_fab2_lib.baseboard_fab2(sch_1):page216_i53@mstr_discrete.cap(chips)!CAP_0402-1.0UF,6.3V,10%,X6S,D9A!!!F3615!B!!!!
S!P5V_STBY!C7G42!1!@baseboard_fab2_lib.baseboard_fab2(sch_1):page216_i73@mstr_discrete.cap(chips)!CAP_0402-1.0UF,6.3V,10%,X6S,D9A!!!F3614!A!!!!
S!GND!C7G42!2!@baseboard_fab2_lib.baseboard_fab2(sch_1):page216_i73@mstr_discrete.cap(chips)!CAP_0402-1.0UF,6.3V,10%,X6S,D9A!!!F3614!B!!!!
S!P5V_STBY!C7A18!1!@baseboard_fab2_lib.baseboard_fab2(sch_1):page219_i53@mstr_discrete.cap(chips)!CAP_0402-1.0UF,6.3V,10%,X6S,D9A!!!F3623!A!!!!
S!GND!C7A18!2!@baseboard_fab2_lib.baseboard_fab2(sch_1):page219_i53@mstr_discrete.cap(chips)!CAP_0402-1.0UF,6.3V,10%,X6S,D9A!!!F3623!B!!!!
S!P5V_STBY!C7A26!1!@baseboard_fab2_lib.baseboard_fab2(sch_1):page219_i73@mstr_discrete.cap(chips)!CAP_0402-1.0UF,6.3V,10%,X6S,D9A!!!F3622!A!!!!
S!GND!C7A26!2!@baseboard_fab2_lib.baseboard_fab2(sch_1):page219_i73@mstr_discrete.cap(chips)!CAP_0402-1.0UF,6.3V,10%,X6S,D9A!!!F3622!B!!!!
S!P5V_STBY!C1A2!1!@baseboard_fab2_lib.baseboard_fab2(sch_1):page227_i53@mstr_discrete.cap(chips)!CAP_0402-1.0UF,6.3V,10%,X6S,D9A!!!F3755!A!!!!
S!GND!C1A2!2!@baseboard_fab2_lib.baseboard_fab2(sch_1):page227_i53@mstr_discrete.cap(chips)!CAP_0402-1.0UF,6.3V,10%,X6S,D9A!!!F3755!B!!!!
S!P5V_STBY!C1A11!1!@baseboard_fab2_lib.baseboard_fab2(sch_1):page227_i73@mstr_discrete.cap(chips)!CAP_0402-1.0UF,6.3V,10%,X6S,D9A!!!F3754!A!!!!
S!GND!C1A11!2!@baseboard_fab2_lib.baseboard_fab2(sch_1):page227_i73@mstr_discrete.cap(chips)!CAP_0402-1.0UF,6.3V,10%,X6S,D9A!!!F3754!B!!!!
S!P5V_STBY!C1G4!1!@baseboard_fab2_lib.baseboard_fab2(sch_1):page224_i53@mstr_discrete.cap(chips)!CAP_0402-1.0UF,6.3V,10%,X6S,D9A!!!F3742!A!!!!
S!GND!C1G4!2!@baseboard_fab2_lib.baseboard_fab2(sch_1):page224_i53@mstr_discrete.cap(chips)!CAP_0402-1.0UF,6.3V,10%,X6S,D9A!!!F3742!B!!!!
S!P5V_STBY!C1F21!1!@baseboard_fab2_lib.baseboard_fab2(sch_1):page224_i73@mstr_discrete.cap(chips)!CAP_0402-1.0UF,6.3V,10%,X6S,D9A!!!F3743!A!!!!
S!GND!C1F21!2!@baseboard_fab2_lib.baseboard_fab2(sch_1):page224_i73@mstr_discrete.cap(chips)!CAP_0402-1.0UF,6.3V,10%,X6S,D9A!!!F3743!B!!!!
S!P5V_STBY!C1E23!1!@baseboard_fab2_lib.baseboard_fab2(sch_1):page207_i37@mstr_discrete.cap(chips)!CAP_0402-1.0UF,6.3V,10%,X6S,D9A!!!F3745!A!!!!
S!GND!C1E23!2!@baseboard_fab2_lib.baseboard_fab2(sch_1):page207_i37@mstr_discrete.cap(chips)!CAP_0402-1.0UF,6.3V,10%,X6S,D9A!!!F3745!B!!!!
S!P5V_STBY!C1E6!1!@baseboard_fab2_lib.baseboard_fab2(sch_1):page207_i29@mstr_discrete.cap(chips)!CAP_0402-1.0UF,6.3V,10%,X6S,D9A!!!F3744!A!!!!
S!GND!C1E6!2!@baseboard_fab2_lib.baseboard_fab2(sch_1):page207_i29@mstr_discrete.cap(chips)!CAP_0402-1.0UF,6.3V,10%,X6S,D9A!!!F3744!B!!!!
S!P5V_STBY!C1D15!1!@baseboard_fab2_lib.baseboard_fab2(sch_1):page208_i39@mstr_discrete.cap(chips)!CAP_0402-1.0UF,6.3V,10%,X6S,D9A!!!F3746!A!!!!
S!GND!C1D15!2!@baseboard_fab2_lib.baseboard_fab2(sch_1):page208_i39@mstr_discrete.cap(chips)!CAP_0402-1.0UF,6.3V,10%,X6S,D9A!!!F3746!B!!!!
S!P5V_STBY!C1D5!1!@baseboard_fab2_lib.baseboard_fab2(sch_1):page208_i47@mstr_discrete.cap(chips)!CAP_0402-1.0UF,6.3V,10%,X6S,D9A!!!F3747!A!!!!
S!GND!C1D5!2!@baseboard_fab2_lib.baseboard_fab2(sch_1):page208_i47@mstr_discrete.cap(chips)!CAP_0402-1.0UF,6.3V,10%,X6S,D9A!!!F3747!B!!!!
S!P5V_STBY!C1C3!1!@baseboard_fab2_lib.baseboard_fab2(sch_1):page210_i23@mstr_discrete.cap(chips)!CAP_0402-1.0UF,6.3V,10%,X6S,D9A!!!F3751!A!!!!
S!GND!C1C3!2!@baseboard_fab2_lib.baseboard_fab2(sch_1):page210_i23@mstr_discrete.cap(chips)!CAP_0402-1.0UF,6.3V,10%,X6S,D9A!!!F3751!B!!!!
S!P3V3_STBY!C1L20!1!@baseboard_fab2_lib.baseboard_fab2(sch_1):page113_i267@mstr_discrete.cap(chips)!CAP_0402LF-0.01UF,25V,10%,X7R,A!!!F3492!A!!!!
S!GND!C1L20!2!@baseboard_fab2_lib.baseboard_fab2(sch_1):page113_i267@mstr_discrete.cap(chips)!CAP_0402LF-0.01UF,25V,10%,X7R,A!!!F3492!B!!!!
S!P3V3_STBY!C1M35!1!@baseboard_fab2_lib.baseboard_fab2(sch_1):page113_i266@mstr_discrete.cap(chips)!CAP_0402LF-0.01UF,25V,10%,X7R,A!!!F3494!A!!!!
S!GND!C1M35!2!@baseboard_fab2_lib.baseboard_fab2(sch_1):page113_i266@mstr_discrete.cap(chips)!CAP_0402LF-0.01UF,25V,10%,X7R,A!!!F3494!B!!!!
S!P3V3_STBY!C1M34!1!@baseboard_fab2_lib.baseboard_fab2(sch_1):page113_i265@mstr_discrete.cap(chips)!CAP_0402LF-0.01UF,25V,10%,X7R,A!!!F3493!A!!!!
S!GND!C1M34!2!@baseboard_fab2_lib.baseboard_fab2(sch_1):page113_i265@mstr_discrete.cap(chips)!CAP_0402LF-0.01UF,25V,10%,X7R,A!!!F3493!B!!!!
S!FAN_TACH1!C9T1!1!@baseboard_fab2_lib.baseboard_fab2(sch_1):page161_i137@mstr_discrete.cap(chips)!CAP_0402LF-0.01UF,25V,10%,X7R,A!!!F3498!A!!!!
S!GND!C9T1!2!@baseboard_fab2_lib.baseboard_fab2(sch_1):page161_i137@mstr_discrete.cap(chips)!CAP_0402LF-0.01UF,25V,10%,X7R,A!!!F3498!B!!!!
S!FAN_TACH3!C1B17!1!@baseboard_fab2_lib.baseboard_fab2(sch_1):page161_i128@mstr_discrete.cap(chips)!CAP_0402LF-0.01UF,25V,10%,X7R,A!!!F3599!A!!!!
S!GND!C1B17!2!@baseboard_fab2_lib.baseboard_fab2(sch_1):page161_i128@mstr_discrete.cap(chips)!CAP_0402LF-0.01UF,25V,10%,X7R,A!!!F3599!B!!!!
S!P3V3_STBY!C1M31!1!@baseboard_fab2_lib.baseboard_fab2(sch_1):page113_i116@mstr_discrete.cap(chips)!CAP_0402LF-0.01UF,25V,10%,X7R,A!!!F3533!A!!!!
S!GND!C1M31!2!@baseboard_fab2_lib.baseboard_fab2(sch_1):page113_i116@mstr_discrete.cap(chips)!CAP_0402LF-0.01UF,25V,10%,X7R,A!!!F3533!B!!!!
S!P3V3_STBY!C1M28!1!@baseboard_fab2_lib.baseboard_fab2(sch_1):page113_i119@mstr_discrete.cap(chips)!CAP_0402LF-0.01UF,25V,10%,X7R,A!!!F3532!A!!!!
S!GND!C1M28!2!@baseboard_fab2_lib.baseboard_fab2(sch_1):page113_i119@mstr_discrete.cap(chips)!CAP_0402LF-0.01UF,25V,10%,X7R,A!!!F3532!B!!!!
S!P3V3_STBY!C1M30!1!@baseboard_fab2_lib.baseboard_fab2(sch_1):page112_i131@mstr_discrete.cap(chips)!CAP_0402LF-0.01UF,25V,10%,X7R,A!!!F3506!A!!!!
S!GND!C1M30!2!@baseboard_fab2_lib.baseboard_fab2(sch_1):page112_i131@mstr_discrete.cap(chips)!CAP_0402LF-0.01UF,25V,10%,X7R,A!!!F3506!B!!!!
S!SATA6G_RX_DN<0>!C2L31!1!@baseboard_fab2_lib.baseboard_fab2(sch_1):page174_i29@mstr_discrete.cap(chips)!CAP_0402LF-0.01UF,25V,10%,X7R,A!!!F3552!A!!!!
S!SATA6G_P8_RX_C_DN!C2L31!2!@baseboard_fab2_lib.baseboard_fab2(sch_1):page174_i29@mstr_discrete.cap(chips)!CAP_0402LF-0.01UF,25V,10%,X7R,A!!!F3552!B!!!!
S!SATA6G_RX_DN<1>!C2L29!1!@baseboard_fab2_lib.baseboard_fab2(sch_1):page174_i32@mstr_discrete.cap(chips)!CAP_0402LF-0.01UF,25V,10%,X7R,A!!!F3554!A!!!!
S!SATA6G_P9_RX_C_DN!C2L29!2!@baseboard_fab2_lib.baseboard_fab2(sch_1):page174_i32@mstr_discrete.cap(chips)!CAP_0402LF-0.01UF,25V,10%,X7R,A!!!F3554!B!!!!
S!SATA6G_RX_DN<2>!C2L36!1!@baseboard_fab2_lib.baseboard_fab2(sch_1):page174_i39@mstr_discrete.cap(chips)!CAP_0402LF-0.01UF,25V,10%,X7R,A!!!F3548!A!!!!
S!SATA6G_P10_RX_C_DN!C2L36!2!@baseboard_fab2_lib.baseboard_fab2(sch_1):page174_i39@mstr_discrete.cap(chips)!CAP_0402LF-0.01UF,25V,10%,X7R,A!!!F3548!B!!!!
S!SATA6G_RX_DN<3>!C2L34!1!@baseboard_fab2_lib.baseboard_fab2(sch_1):page174_i41@mstr_discrete.cap(chips)!CAP_0402LF-0.01UF,25V,10%,X7R,A!!!F3550!A!!!!
S!SATA6G_P11_RX_C_DN!C2L34!2!@baseboard_fab2_lib.baseboard_fab2(sch_1):page174_i41@mstr_discrete.cap(chips)!CAP_0402LF-0.01UF,25V,10%,X7R,A!!!F3550!B!!!!
S!SATA6G_RX_DP<0>!C2L30!1!@baseboard_fab2_lib.baseboard_fab2(sch_1):page174_i28@mstr_discrete.cap(chips)!CAP_0402LF-0.01UF,25V,10%,X7R,A!!!F3553!A!!!!
S!SATA6G_P8_RX_C_DP!C2L30!2!@baseboard_fab2_lib.baseboard_fab2(sch_1):page174_i28@mstr_discrete.cap(chips)!CAP_0402LF-0.01UF,25V,10%,X7R,A!!!F3553!B!!!!
S!SATA6G_RX_DP<1>!C2L28!1!@baseboard_fab2_lib.baseboard_fab2(sch_1):page174_i30@mstr_discrete.cap(chips)!CAP_0402LF-0.01UF,25V,10%,X7R,A!!!F3555!A!!!!
S!SATA6G_P9_RX_C_DP!C2L28!2!@baseboard_fab2_lib.baseboard_fab2(sch_1):page174_i30@mstr_discrete.cap(chips)!CAP_0402LF-0.01UF,25V,10%,X7R,A!!!F3555!B!!!!
S!SATA6G_RX_DP<2>!C2L35!1!@baseboard_fab2_lib.baseboard_fab2(sch_1):page174_i31@mstr_discrete.cap(chips)!CAP_0402LF-0.01UF,25V,10%,X7R,A!!!F3549!A!!!!
S!SATA6G_P10_RX_C_DP!C2L35!2!@baseboard_fab2_lib.baseboard_fab2(sch_1):page174_i31@mstr_discrete.cap(chips)!CAP_0402LF-0.01UF,25V,10%,X7R,A!!!F3549!B!!!!
S!SATA6G_RX_DP<3>!C2L33!1!@baseboard_fab2_lib.baseboard_fab2(sch_1):page174_i40@mstr_discrete.cap(chips)!CAP_0402LF-0.01UF,25V,10%,X7R,A!!!F3551!A!!!!
S!SATA6G_P11_RX_C_DP!C2L33!2!@baseboard_fab2_lib.baseboard_fab2(sch_1):page174_i40@mstr_discrete.cap(chips)!CAP_0402LF-0.01UF,25V,10%,X7R,A!!!F3551!B!!!!
S!SATA6G_P10_TX_C_DP!C1L12!1!@baseboard_fab2_lib.baseboard_fab2(sch_1):page174_i19@mstr_discrete.cap(chips)!CAP_0402LF-0.01UF,25V,10%,X7R,A!!!F3587!A!!!!
S!SATA6G_TX_DP<2>!C1L12!2!@baseboard_fab2_lib.baseboard_fab2(sch_1):page174_i19@mstr_discrete.cap(chips)!CAP_0402LF-0.01UF,25V,10%,X7R,A!!!F3587!B!!!!
S!SATA6G_P11_TX_C_DP!C1L14!1!@baseboard_fab2_lib.baseboard_fab2(sch_1):page174_i20@mstr_discrete.cap(chips)!CAP_0402LF-0.01UF,25V,10%,X7R,A!!!F3585!A!!!!
S!SATA6G_TX_DP<3>!C1L14!2!@baseboard_fab2_lib.baseboard_fab2(sch_1):page174_i20@mstr_discrete.cap(chips)!CAP_0402LF-0.01UF,25V,10%,X7R,A!!!F3585!B!!!!
S!SATA6G_P8_TX_C_DP!C1L2!1!@baseboard_fab2_lib.baseboard_fab2(sch_1):page174_i9@mstr_discrete.cap(chips)!CAP_0402LF-0.01UF,25V,10%,X7R,A!!!F3591!A!!!!
S!SATA6G_TX_DP<0>!C1L2!2!@baseboard_fab2_lib.baseboard_fab2(sch_1):page174_i9@mstr_discrete.cap(chips)!CAP_0402LF-0.01UF,25V,10%,X7R,A!!!F3591!B!!!!
S!SATA6G_P9_TX_C_DP!C1L6!1!@baseboard_fab2_lib.baseboard_fab2(sch_1):page174_i13@mstr_discrete.cap(chips)!CAP_0402LF-0.01UF,25V,10%,X7R,A!!!F3589!A!!!!
S!SATA6G_TX_DP<1>!C1L6!2!@baseboard_fab2_lib.baseboard_fab2(sch_1):page174_i13@mstr_discrete.cap(chips)!CAP_0402LF-0.01UF,25V,10%,X7R,A!!!F3589!B!!!!
S!SATA6G_P10_TX_C_DN!C1L13!1!@baseboard_fab2_lib.baseboard_fab2(sch_1):page174_i14@mstr_discrete.cap(chips)!CAP_0402LF-0.01UF,25V,10%,X7R,A!!!F3586!A!!!!
S!SATA6G_TX_DN<2>!C1L13!2!@baseboard_fab2_lib.baseboard_fab2(sch_1):page174_i14@mstr_discrete.cap(chips)!CAP_0402LF-0.01UF,25V,10%,X7R,A!!!F3586!B!!!!
S!SATA6G_P11_TX_C_DN!C1L15!1!@baseboard_fab2_lib.baseboard_fab2(sch_1):page174_i18@mstr_discrete.cap(chips)!CAP_0402LF-0.01UF,25V,10%,X7R,A!!!F3584!A!!!!
S!SATA6G_TX_DN<3>!C1L15!2!@baseboard_fab2_lib.baseboard_fab2(sch_1):page174_i18@mstr_discrete.cap(chips)!CAP_0402LF-0.01UF,25V,10%,X7R,A!!!F3584!B!!!!
S!SATA6G_P8_TX_C_DN!C1L3!1!@baseboard_fab2_lib.baseboard_fab2(sch_1):page174_i8@mstr_discrete.cap(chips)!CAP_0402LF-0.01UF,25V,10%,X7R,A!!!F3590!A!!!!
S!SATA6G_TX_DN<0>!C1L3!2!@baseboard_fab2_lib.baseboard_fab2(sch_1):page174_i8@mstr_discrete.cap(chips)!CAP_0402LF-0.01UF,25V,10%,X7R,A!!!F3590!B!!!!
S!SATA6G_P9_TX_C_DN!C1L7!1!@baseboard_fab2_lib.baseboard_fab2(sch_1):page174_i12@mstr_discrete.cap(chips)!CAP_0402LF-0.01UF,25V,10%,X7R,A!!!F3588!A!!!!
S!SATA6G_TX_DN<1>!C1L7!2!@baseboard_fab2_lib.baseboard_fab2(sch_1):page174_i12@mstr_discrete.cap(chips)!CAP_0402LF-0.01UF,25V,10%,X7R,A!!!F3588!B!!!!
S!SATA6G_PCH_PCIE_UP_SATA_RXN<6>!C2L14!1!@baseboard_fab2_lib.baseboard_fab2(sch_1):page173_i208@mstr_discrete.cap(chips)!CAP_0402LF-0.01UF,25V,10%,X7R,A!!!F3568!A!!!!
S!SATA6G_P6_RX_C_DN!C2L14!2!@baseboard_fab2_lib.baseboard_fab2(sch_1):page173_i208@mstr_discrete.cap(chips)!CAP_0402LF-0.01UF,25V,10%,X7R,A!!!F3568!B!!!!
S!SATA6G_PCH_PCIE_UP_SATA_RXN<7>!C2L5!1!@baseboard_fab2_lib.baseboard_fab2(sch_1):page173_i209@mstr_discrete.cap(chips)!CAP_0402LF-0.01UF,25V,10%,X7R,A!!!F3575!A!!!!
S!SATA6G_P7_RX_C_DN!C2L5!2!@baseboard_fab2_lib.baseboard_fab2(sch_1):page173_i209@mstr_discrete.cap(chips)!CAP_0402LF-0.01UF,25V,10%,X7R,A!!!F3575!B!!!!
S!SATA6G_PCH_PCIE_UP_SATA_RXN<4>!C2L18!1!@baseboard_fab2_lib.baseboard_fab2(sch_1):page173_i197@mstr_discrete.cap(chips)!CAP_0402LF-0.01UF,25V,10%,X7R,A!!!F3564!A!!!!
S!SATA6G_P4_RX_C_DN!C2L18!2!@baseboard_fab2_lib.baseboard_fab2(sch_1):page173_i197@mstr_discrete.cap(chips)!CAP_0402LF-0.01UF,25V,10%,X7R,A!!!F3564!B!!!!
S!SATA6G_PCH_PCIE_UP_SATA_RXN<5>!C2L9!1!@baseboard_fab2_lib.baseboard_fab2(sch_1):page173_i207@mstr_discrete.cap(chips)!CAP_0402LF-0.01UF,25V,10%,X7R,A!!!F3572!A!!!!
S!SATA6G_P5_RX_C_DN!C2L9!2!@baseboard_fab2_lib.baseboard_fab2(sch_1):page173_i207@mstr_discrete.cap(chips)!CAP_0402LF-0.01UF,25V,10%,X7R,A!!!F3572!B!!!!
S!SATA6G_PCH_PCIE_UP_SATA_RXP<4>!C2L20!1!@baseboard_fab2_lib.baseboard_fab2(sch_1):page173_i195@mstr_discrete.cap(chips)!CAP_0402LF-0.01UF,25V,10%,X7R,A!!!F3562!A!!!!
S!SATA6G_P4_RX_C_DP!C2L20!2!@baseboard_fab2_lib.baseboard_fab2(sch_1):page173_i195@mstr_discrete.cap(chips)!CAP_0402LF-0.01UF,25V,10%,X7R,A!!!F3562!B!!!!
S!SATA6G_PCH_PCIE_UP_SATA_RXP<5>!C2L12!1!@baseboard_fab2_lib.baseboard_fab2(sch_1):page173_i196@mstr_discrete.cap(chips)!CAP_0402LF-0.01UF,25V,10%,X7R,A!!!F3570!A!!!!
S!SATA6G_P5_RX_C_DP!C2L12!2!@baseboard_fab2_lib.baseboard_fab2(sch_1):page173_i196@mstr_discrete.cap(chips)!CAP_0402LF-0.01UF,25V,10%,X7R,A!!!F3570!B!!!!
S!SATA6G_PCH_PCIE_UP_SATA_RXP<6>!C2L16!1!@baseboard_fab2_lib.baseboard_fab2(sch_1):page173_i205@mstr_discrete.cap(chips)!CAP_0402LF-0.01UF,25V,10%,X7R,A!!!F3566!A!!!!
S!SATA6G_P6_RX_C_DP!C2L16!2!@baseboard_fab2_lib.baseboard_fab2(sch_1):page173_i205@mstr_discrete.cap(chips)!CAP_0402LF-0.01UF,25V,10%,X7R,A!!!F3566!B!!!!
S!SATA6G_PCH_PCIE_UP_SATA_RXP<7>!C2L7!1!@baseboard_fab2_lib.baseboard_fab2(sch_1):page173_i206@mstr_discrete.cap(chips)!CAP_0402LF-0.01UF,25V,10%,X7R,A!!!F3573!A!!!!
S!SATA6G_P7_RX_C_DP!C2L7!2!@baseboard_fab2_lib.baseboard_fab2(sch_1):page173_i206@mstr_discrete.cap(chips)!CAP_0402LF-0.01UF,25V,10%,X7R,A!!!F3573!B!!!!
S!SATA6G_P4_TX_C_DP!C2L47!1!@baseboard_fab2_lib.baseboard_fab2(sch_1):page173_i239@mstr_discrete.cap(chips)!CAP_0402LF-0.01UF,25V,10%,X7R,A!!!F3539!A!!!!
S!SATA6G_PCH_PCIE_UP_SATA_TXP<4>!C2L47!2!@baseboard_fab2_lib.baseboard_fab2(sch_1):page173_i239@mstr_discrete.cap(chips)!CAP_0402LF-0.01UF,25V,10%,X7R,A!!!F3539!B!!!!
S!SATA6G_P5_TX_C_DP!C2L27!1!@baseboard_fab2_lib.baseboard_fab2(sch_1):page173_i240@mstr_discrete.cap(chips)!CAP_0402LF-0.01UF,25V,10%,X7R,A!!!F3556!A!!!!
S!SATA6G_PCH_PCIE_UP_SATA_TXP<5>!C2L27!2!@baseboard_fab2_lib.baseboard_fab2(sch_1):page173_i240@mstr_discrete.cap(chips)!CAP_0402LF-0.01UF,25V,10%,X7R,A!!!F3556!B!!!!
S!SATA6G_P6_TX_C_DP!C2L48!1!@baseboard_fab2_lib.baseboard_fab2(sch_1):page173_i257@mstr_discrete.cap(chips)!CAP_0402LF-0.01UF,25V,10%,X7R,A!!!F3538!A!!!!
S!SATA6G_PCH_PCIE_UP_SATA_TXP<6>!C2L48!2!@baseboard_fab2_lib.baseboard_fab2(sch_1):page173_i257@mstr_discrete.cap(chips)!CAP_0402LF-0.01UF,25V,10%,X7R,A!!!F3538!B!!!!
S!SATA6G_P7_TX_C_DP!C2L24!1!@baseboard_fab2_lib.baseboard_fab2(sch_1):page173_i258@mstr_discrete.cap(chips)!CAP_0402LF-0.01UF,25V,10%,X7R,A!!!F3558!A!!!!
S!SATA6G_PCH_PCIE_UP_SATA_TXP<7>!C2L24!2!@baseboard_fab2_lib.baseboard_fab2(sch_1):page173_i258@mstr_discrete.cap(chips)!CAP_0402LF-0.01UF,25V,10%,X7R,A!!!F3558!B!!!!
S!SATA6G_P4_TX_C_DN!C2L37!1!@baseboard_fab2_lib.baseboard_fab2(sch_1):page173_i238@mstr_discrete.cap(chips)!CAP_0402LF-0.01UF,25V,10%,X7R,A!!!F3547!A!!!!
S!SATA6G_PCH_PCIE_UP_SATA_TXN<4>!C2L37!2!@baseboard_fab2_lib.baseboard_fab2(sch_1):page173_i238@mstr_discrete.cap(chips)!CAP_0402LF-0.01UF,25V,10%,X7R,A!!!F3547!B!!!!
S!SATA6G_P5_TX_C_DN!C2L26!1!@baseboard_fab2_lib.baseboard_fab2(sch_1):page173_i255@mstr_discrete.cap(chips)!CAP_0402LF-0.01UF,25V,10%,X7R,A!!!F3557!A!!!!
S!SATA6G_PCH_PCIE_UP_SATA_TXN<5>!C2L26!2!@baseboard_fab2_lib.baseboard_fab2(sch_1):page173_i255@mstr_discrete.cap(chips)!CAP_0402LF-0.01UF,25V,10%,X7R,A!!!F3557!B!!!!
S!SATA6G_P6_TX_C_DN!C2L38!1!@baseboard_fab2_lib.baseboard_fab2(sch_1):page173_i256@mstr_discrete.cap(chips)!CAP_0402LF-0.01UF,25V,10%,X7R,A!!!F3546!A!!!!
S!SATA6G_PCH_PCIE_UP_SATA_TXN<6>!C2L38!2!@baseboard_fab2_lib.baseboard_fab2(sch_1):page173_i256@mstr_discrete.cap(chips)!CAP_0402LF-0.01UF,25V,10%,X7R,A!!!F3546!B!!!!
S!SATA6G_P7_TX_C_DN!C2L21!1!@baseboard_fab2_lib.baseboard_fab2(sch_1):page173_i259@mstr_discrete.cap(chips)!CAP_0402LF-0.01UF,25V,10%,X7R,A!!!F3561!A!!!!
S!SATA6G_PCH_PCIE_UP_SATA_TXN<7>!C2L21!2!@baseboard_fab2_lib.baseboard_fab2(sch_1):page173_i259@mstr_discrete.cap(chips)!CAP_0402LF-0.01UF,25V,10%,X7R,A!!!F3561!B!!!!
S!P3V3_STBY!C2P8!1!@baseboard_fab2_lib.baseboard_fab2(sch_1):page192_i1@mstr_discrete.cap(chips)!CAP_0402LF-0.01UF,25V,10%,X7R,A!!!F3531!A!!!!
S!GND!C2P8!2!@baseboard_fab2_lib.baseboard_fab2(sch_1):page192_i1@mstr_discrete.cap(chips)!CAP_0402LF-0.01UF,25V,10%,X7R,A!!!F3531!B!!!!
S!M_A_VREF!C4F10!1!@baseboard_fab2_lib.baseboard_fab2(sch_1):page43_i272@mstr_discrete.cap(chips)!CAP_0402LF-0.01UF,25V,10%,X7R,A!!!F3522!A!!!!
S!GND!C4F10!2!@baseboard_fab2_lib.baseboard_fab2(sch_1):page43_i272@mstr_discrete.cap(chips)!CAP_0402LF-0.01UF,25V,10%,X7R,A!!!F3522!B!!!!
S!M_B_VREF!C4G3!1!@baseboard_fab2_lib.baseboard_fab2(sch_1):page45_i179@mstr_discrete.cap(chips)!CAP_0402LF-0.01UF,25V,10%,X7R,A!!!F3520!A!!!!
S!GND!C4G3!2!@baseboard_fab2_lib.baseboard_fab2(sch_1):page45_i179@mstr_discrete.cap(chips)!CAP_0402LF-0.01UF,25V,10%,X7R,A!!!F3520!B!!!!
S!M_H_VREF!C9U7!1!@baseboard_fab2_lib.baseboard_fab2(sch_1):page79_i178@mstr_discrete.cap(chips)!CAP_0402LF-0.01UF,25V,10%,X7R,A!!!F3496!A!!!!
S!GND!C9U7!2!@baseboard_fab2_lib.baseboard_fab2(sch_1):page79_i178@mstr_discrete.cap(chips)!CAP_0402LF-0.01UF,25V,10%,X7R,A!!!F3496!B!!!!
S!M_G_VREF!C1F22!1!@baseboard_fab2_lib.baseboard_fab2(sch_1):page77_i181@mstr_discrete.cap(chips)!CAP_0402LF-0.01UF,25V,10%,X7R,A!!!F3596!A!!!!
S!GND!C1F22!2!@baseboard_fab2_lib.baseboard_fab2(sch_1):page77_i181@mstr_discrete.cap(chips)!CAP_0402LF-0.01UF,25V,10%,X7R,A!!!F3596!B!!!!
S!M_C_VREF!C4G19!1!@baseboard_fab2_lib.baseboard_fab2(sch_1):page47_i188@mstr_discrete.cap(chips)!CAP_0402LF-0.01UF,25V,10%,X7R,A!!!F3518!A!!!!
S!GND!C4G19!2!@baseboard_fab2_lib.baseboard_fab2(sch_1):page47_i188@mstr_discrete.cap(chips)!CAP_0402LF-0.01UF,25V,10%,X7R,A!!!F3518!B!!!!
S!M_C_VREF!C6U17!1!@baseboard_fab2_lib.baseboard_fab2(sch_1):page48_i176@mstr_discrete.cap(chips)!CAP_0402LF-0.01UF,25V,10%,X7R,A!!!F3509!A!!!!
S!GND!C6U17!2!@baseboard_fab2_lib.baseboard_fab2(sch_1):page48_i176@mstr_discrete.cap(chips)!CAP_0402LF-0.01UF,25V,10%,X7R,A!!!F3509!B!!!!
S!M_D_VREF!C4B12!1!@baseboard_fab2_lib.baseboard_fab2(sch_1):page49_i179@mstr_discrete.cap(chips)!CAP_0402LF-0.01UF,25V,10%,X7R,A!!!F3524!A!!!!
S!GND!C4B12!2!@baseboard_fab2_lib.baseboard_fab2(sch_1):page49_i179@mstr_discrete.cap(chips)!CAP_0402LF-0.01UF,25V,10%,X7R,A!!!F3524!B!!!!
S!M_E_VREF!C6L6!1!@baseboard_fab2_lib.baseboard_fab2(sch_1):page51_i175@mstr_discrete.cap(chips)!CAP_0402LF-0.01UF,25V,10%,X7R,A!!!F3515!A!!!!
S!GND!C6L6!2!@baseboard_fab2_lib.baseboard_fab2(sch_1):page51_i175@mstr_discrete.cap(chips)!CAP_0402LF-0.01UF,25V,10%,X7R,A!!!F3515!B!!!!
S!M_M_VREF!C9L1!1!@baseboard_fab2_lib.baseboard_fab2(sch_1):page88_i177@mstr_discrete.cap(chips)!CAP_0402LF-0.01UF,25V,10%,X7R,A!!!F3504!A!!!!
S!GND!C9L1!2!@baseboard_fab2_lib.baseboard_fab2(sch_1):page88_i177@mstr_discrete.cap(chips)!CAP_0402LF-0.01UF,25V,10%,X7R,A!!!F3504!B!!!!
S!M_M_VREF!C1A5!1!@baseboard_fab2_lib.baseboard_fab2(sch_1):page87_i178@mstr_discrete.cap(chips)!CAP_0402LF-0.01UF,25V,10%,X7R,A!!!F3603!A!!!!
S!GND!C1A5!2!@baseboard_fab2_lib.baseboard_fab2(sch_1):page87_i178@mstr_discrete.cap(chips)!CAP_0402LF-0.01UF,25V,10%,X7R,A!!!F3603!B!!!!
S!M_F_VREF!C6L1!1!@baseboard_fab2_lib.baseboard_fab2(sch_1):page53_i178@mstr_discrete.cap(chips)!CAP_0402LF-0.01UF,25V,10%,X7R,A!!!F3517!A!!!!
S!GND!C6L1!2!@baseboard_fab2_lib.baseboard_fab2(sch_1):page53_i178@mstr_discrete.cap(chips)!CAP_0402LF-0.01UF,25V,10%,X7R,A!!!F3517!B!!!!
S!M_K_VREF!C1B9!1!@baseboard_fab2_lib.baseboard_fab2(sch_1):page83_i176@mstr_discrete.cap(chips)!CAP_0402LF-0.01UF,25V,10%,X7R,A!!!F3601!A!!!!
S!GND!C1B9!2!@baseboard_fab2_lib.baseboard_fab2(sch_1):page83_i176@mstr_discrete.cap(chips)!CAP_0402LF-0.01UF,25V,10%,X7R,A!!!F3601!B!!!!
S!M_F_VREF!C4A5!1!@baseboard_fab2_lib.baseboard_fab2(sch_1):page54_i179@mstr_discrete.cap(chips)!CAP_0402LF-0.01UF,25V,10%,X7R,A!!!F3526!A!!!!
S!GND!C4A5!2!@baseboard_fab2_lib.baseboard_fab2(sch_1):page54_i179@mstr_discrete.cap(chips)!CAP_0402LF-0.01UF,25V,10%,X7R,A!!!F3526!B!!!!
S!M_J_VREF!C1G19!1!@baseboard_fab2_lib.baseboard_fab2(sch_1):page82_i180@mstr_discrete.cap(chips)!CAP_0402LF-0.01UF,25V,10%,X7R,A!!!F3592!A!!!!
S!GND!C1G19!2!@baseboard_fab2_lib.baseboard_fab2(sch_1):page82_i180@mstr_discrete.cap(chips)!CAP_0402LF-0.01UF,25V,10%,X7R,A!!!F3592!B!!!!
S!M_K_VREF!C9M1!1!@baseboard_fab2_lib.baseboard_fab2(sch_1):page84_i4@mstr_discrete.cap(chips)!CAP_0402LF-0.01UF,25V,10%,X7R,A!!!F3500!A!!!!
S!GND!C9M1!2!@baseboard_fab2_lib.baseboard_fab2(sch_1):page84_i4@mstr_discrete.cap(chips)!CAP_0402LF-0.01UF,25V,10%,X7R,A!!!F3500!B!!!!
S!M_L_VREF!C1A17!1!@baseboard_fab2_lib.baseboard_fab2(sch_1):page86_i182@mstr_discrete.cap(chips)!CAP_0402LF-0.01UF,25V,10%,X7R,A!!!F3602!A!!!!
S!GND!C1A17!2!@baseboard_fab2_lib.baseboard_fab2(sch_1):page86_i182@mstr_discrete.cap(chips)!CAP_0402LF-0.01UF,25V,10%,X7R,A!!!F3602!B!!!!
S!M_G_VREF!C9T7!1!@baseboard_fab2_lib.baseboard_fab2(sch_1):page78_i2@mstr_discrete.cap(chips)!CAP_0402LF-0.01UF,25V,10%,X7R,A!!!F3497!A!!!!
S!GND!C9T7!2!@baseboard_fab2_lib.baseboard_fab2(sch_1):page78_i2@mstr_discrete.cap(chips)!CAP_0402LF-0.01UF,25V,10%,X7R,A!!!F3497!B!!!!
S!M_H_VREF!C1G10!1!@baseboard_fab2_lib.baseboard_fab2(sch_1):page80_i3@mstr_discrete.cap(chips)!CAP_0402LF-0.01UF,25V,10%,X7R,A!!!F3594!A!!!!
S!GND!C1G10!2!@baseboard_fab2_lib.baseboard_fab2(sch_1):page80_i3@mstr_discrete.cap(chips)!CAP_0402LF-0.01UF,25V,10%,X7R,A!!!F3594!B!!!!
S!M_E_VREF!C4A18!1!@baseboard_fab2_lib.baseboard_fab2(sch_1):page52_i3@mstr_discrete.cap(chips)!CAP_0402LF-0.01UF,25V,10%,X7R,A!!!F3525!A!!!!
S!GND!C4A18!2!@baseboard_fab2_lib.baseboard_fab2(sch_1):page52_i3@mstr_discrete.cap(chips)!CAP_0402LF-0.01UF,25V,10%,X7R,A!!!F3525!B!!!!
S!M_A_VREF!C6T1!1!@baseboard_fab2_lib.baseboard_fab2(sch_1):page44_i2@mstr_discrete.cap(chips)!CAP_0402LF-0.01UF,25V,10%,X7R,A!!!F3511!A!!!!
S!GND!C6T1!2!@baseboard_fab2_lib.baseboard_fab2(sch_1):page44_i2@mstr_discrete.cap(chips)!CAP_0402LF-0.01UF,25V,10%,X7R,A!!!F3511!B!!!!
S!M_B_VREF!C6U9!1!@baseboard_fab2_lib.baseboard_fab2(sch_1):page46_i5@mstr_discrete.cap(chips)!CAP_0402LF-0.01UF,25V,10%,X7R,A!!!F3510!A!!!!
S!GND!C6U9!2!@baseboard_fab2_lib.baseboard_fab2(sch_1):page46_i5@mstr_discrete.cap(chips)!CAP_0402LF-0.01UF,25V,10%,X7R,A!!!F3510!B!!!!
S!M_D_VREF!C6M1!1!@baseboard_fab2_lib.baseboard_fab2(sch_1):page50_i177@mstr_discrete.cap(chips)!CAP_0402LF-0.01UF,25V,10%,X7R,A!!!F3513!A!!!!
S!GND!C6M1!2!@baseboard_fab2_lib.baseboard_fab2(sch_1):page50_i177@mstr_discrete.cap(chips)!CAP_0402LF-0.01UF,25V,10%,X7R,A!!!F3513!B!!!!
S!M_J_VREF!C9U10!1!@baseboard_fab2_lib.baseboard_fab2(sch_1):page81_i178@mstr_discrete.cap(chips)!CAP_0402LF-0.01UF,25V,10%,X7R,A!!!F3495!A!!!!
S!GND!C9U10!2!@baseboard_fab2_lib.baseboard_fab2(sch_1):page81_i178@mstr_discrete.cap(chips)!CAP_0402LF-0.01UF,25V,10%,X7R,A!!!F3495!B!!!!
S!M_L_VREF!C9L7!1!@baseboard_fab2_lib.baseboard_fab2(sch_1):page85_i181@mstr_discrete.cap(chips)!CAP_0402LF-0.01UF,25V,10%,X7R,A!!!F3502!A!!!!
S!GND!C9L7!2!@baseboard_fab2_lib.baseboard_fab2(sch_1):page85_i181@mstr_discrete.cap(chips)!CAP_0402LF-0.01UF,25V,10%,X7R,A!!!F3502!B!!!!
S!P3V3_STBY!C8F5!1!@baseboard_fab2_lib.baseboard_fab2(sch_1):page162_i28@mstr_discrete.cap(chips)!CAP_0402LF-0.01UF,25V,10%,X7R,A!!!F3507!A!!!!
S!GND!C8F5!2!@baseboard_fab2_lib.baseboard_fab2(sch_1):page162_i28@mstr_discrete.cap(chips)!CAP_0402LF-0.01UF,25V,10%,X7R,A!!!F3507!B!!!!
S!P3V3_STBY!C7F1!1!@baseboard_fab2_lib.baseboard_fab2(sch_1):page153_i131@mstr_discrete.cap(chips)!CAP_0402LF-0.01UF,25V,10%,X7R,A!!!F3508!A!!!!
S!GND!C7F1!2!@baseboard_fab2_lib.baseboard_fab2(sch_1):page153_i131@mstr_discrete.cap(chips)!CAP_0402LF-0.01UF,25V,10%,X7R,A!!!F3508!B!!!!
S!P3V3_STBY!C3T5!1!@baseboard_fab2_lib.baseboard_fab2(sch_1):page153_i136@mstr_discrete.cap(chips)!CAP_0402LF-0.01UF,25V,10%,X7R,A!!!F3527!A!!!!
S!GND!C3T5!2!@baseboard_fab2_lib.baseboard_fab2(sch_1):page153_i136@mstr_discrete.cap(chips)!CAP_0402LF-0.01UF,25V,10%,X7R,A!!!F3527!B!!!!
S!SATA6G_PCH_PCIE_UP_SATA_RXN<0>!C2L17!1!@baseboard_fab2_lib.baseboard_fab2(sch_1):page173_i174@mstr_discrete.cap(chips)!CAP_0402LF-0.01UF,25V,10%,X7R,A!!!F3565!A!!!!
S!SATA6G_P0_RX_C_DN!C2L17!2!@baseboard_fab2_lib.baseboard_fab2(sch_1):page173_i174@mstr_discrete.cap(chips)!CAP_0402LF-0.01UF,25V,10%,X7R,A!!!F3565!B!!!!
S!SATA6G_PCH_PCIE_UP_SATA_RXN<1>!C2L6!1!@baseboard_fab2_lib.baseboard_fab2(sch_1):page173_i166@mstr_discrete.cap(chips)!CAP_0402LF-0.01UF,25V,10%,X7R,A!!!F3574!A!!!!
S!SATA6G_P1_RX_C_DN!C2L6!2!@baseboard_fab2_lib.baseboard_fab2(sch_1):page173_i166@mstr_discrete.cap(chips)!CAP_0402LF-0.01UF,25V,10%,X7R,A!!!F3574!B!!!!
S!SATA6G_PCH_PCIE_UP_SATA_RXN<2>!C2L13!1!@baseboard_fab2_lib.baseboard_fab2(sch_1):page173_i165@mstr_discrete.cap(chips)!CAP_0402LF-0.01UF,25V,10%,X7R,A!!!F3569!A!!!!
S!SATA6G_P2_RX_C_DN!C2L13!2!@baseboard_fab2_lib.baseboard_fab2(sch_1):page173_i165@mstr_discrete.cap(chips)!CAP_0402LF-0.01UF,25V,10%,X7R,A!!!F3569!B!!!!
S!SATA6G_PCH_PCIE_UP_SATA_RXN<3>!C2L3!1!@baseboard_fab2_lib.baseboard_fab2(sch_1):page173_i194@mstr_discrete.cap(chips)!CAP_0402LF-0.01UF,25V,10%,X7R,A!!!F3577!A!!!!
S!SATA6G_P3_RX_C_DN!C2L3!2!@baseboard_fab2_lib.baseboard_fab2(sch_1):page173_i194@mstr_discrete.cap(chips)!CAP_0402LF-0.01UF,25V,10%,X7R,A!!!F3577!B!!!!
S!SATA6G_PCH_PCIE_UP_SATA_RXP<0>!C2L19!1!@baseboard_fab2_lib.baseboard_fab2(sch_1):page173_i172@mstr_discrete.cap(chips)!CAP_0402LF-0.01UF,25V,10%,X7R,A!!!F3563!A!!!!
S!SATA6G_P0_RX_C_DP!C2L19!2!@baseboard_fab2_lib.baseboard_fab2(sch_1):page173_i172@mstr_discrete.cap(chips)!CAP_0402LF-0.01UF,25V,10%,X7R,A!!!F3563!B!!!!
S!SATA6G_PCH_PCIE_UP_SATA_RXP<1>!C2L10!1!@baseboard_fab2_lib.baseboard_fab2(sch_1):page173_i173@mstr_discrete.cap(chips)!CAP_0402LF-0.01UF,25V,10%,X7R,A!!!F3571!A!!!!
S!SATA6G_P1_RX_C_DP!C2L10!2!@baseboard_fab2_lib.baseboard_fab2(sch_1):page173_i173@mstr_discrete.cap(chips)!CAP_0402LF-0.01UF,25V,10%,X7R,A!!!F3571!B!!!!
S!SATA6G_PCH_PCIE_UP_SATA_RXP<2>!C2L15!1!@baseboard_fab2_lib.baseboard_fab2(sch_1):page173_i191@mstr_discrete.cap(chips)!CAP_0402LF-0.01UF,25V,10%,X7R,A!!!F3567!A!!!!
S!SATA6G_P2_RX_C_DP!C2L15!2!@baseboard_fab2_lib.baseboard_fab2(sch_1):page173_i191@mstr_discrete.cap(chips)!CAP_0402LF-0.01UF,25V,10%,X7R,A!!!F3567!B!!!!
S!SATA6G_PCH_PCIE_UP_SATA_RXP<3>!C2L4!1!@baseboard_fab2_lib.baseboard_fab2(sch_1):page173_i192@mstr_discrete.cap(chips)!CAP_0402LF-0.01UF,25V,10%,X7R,A!!!F3576!A!!!!
S!SATA6G_P3_RX_C_DP!C2L4!2!@baseboard_fab2_lib.baseboard_fab2(sch_1):page173_i192@mstr_discrete.cap(chips)!CAP_0402LF-0.01UF,25V,10%,X7R,A!!!F3576!B!!!!
S!SATA6G_P2_TX_C_DP!C2L41!1!@baseboard_fab2_lib.baseboard_fab2(sch_1):page173_i242@mstr_discrete.cap(chips)!CAP_0402LF-0.01UF,25V,10%,X7R,A!!!F3543!A!!!!
S!SATA6G_PCH_PCIE_UP_SATA_TXP<2>!C2L41!2!@baseboard_fab2_lib.baseboard_fab2(sch_1):page173_i242@mstr_discrete.cap(chips)!CAP_0402LF-0.01UF,25V,10%,X7R,A!!!F3543!B!!!!
S!SATA6G_P3_TX_C_DP!C2L23!1!@baseboard_fab2_lib.baseboard_fab2(sch_1):page173_i241@mstr_discrete.cap(chips)!CAP_0402LF-0.01UF,25V,10%,X7R,A!!!F3559!A!!!!
S!SATA6G_PCH_PCIE_UP_SATA_TXP<3>!C2L23!2!@baseboard_fab2_lib.baseboard_fab2(sch_1):page173_i241@mstr_discrete.cap(chips)!CAP_0402LF-0.01UF,25V,10%,X7R,A!!!F3559!B!!!!
S!SATA6G_P0_TX_C_DP!C2L39!1!@baseboard_fab2_lib.baseboard_fab2(sch_1):page173_i221@mstr_discrete.cap(chips)!CAP_0402LF-0.01UF,25V,10%,X7R,A!!!F3545!A!!!!
S!SATA6G_PCH_PCIE_UP_SATA_TXP<0>!C2L39!2!@baseboard_fab2_lib.baseboard_fab2(sch_1):page173_i221@mstr_discrete.cap(chips)!CAP_0402LF-0.01UF,25V,10%,X7R,A!!!F3545!B!!!!
S!SATA6G_P1_TX_C_DP!C2L43!1!@baseboard_fab2_lib.baseboard_fab2(sch_1):page173_i222@mstr_discrete.cap(chips)!CAP_0402LF-0.01UF,25V,10%,X7R,A!!!F3541!A!!!!
S!SATA6G_PCH_PCIE_UP_SATA_TXP<1>!C2L43!2!@baseboard_fab2_lib.baseboard_fab2(sch_1):page173_i222@mstr_discrete.cap(chips)!CAP_0402LF-0.01UF,25V,10%,X7R,A!!!F3541!B!!!!
S!SATA6G_P2_TX_C_DN!C2L42!1!@baseboard_fab2_lib.baseboard_fab2(sch_1):page173_i233@mstr_discrete.cap(chips)!CAP_0402LF-0.01UF,25V,10%,X7R,A!!!F3542!A!!!!
S!SATA6G_PCH_PCIE_UP_SATA_TXN<2>!C2L42!2!@baseboard_fab2_lib.baseboard_fab2(sch_1):page173_i233@mstr_discrete.cap(chips)!CAP_0402LF-0.01UF,25V,10%,X7R,A!!!F3542!B!!!!
S!SATA6G_P3_TX_C_DN!C2L22!1!@baseboard_fab2_lib.baseboard_fab2(sch_1):page173_i234@mstr_discrete.cap(chips)!CAP_0402LF-0.01UF,25V,10%,X7R,A!!!F3560!A!!!!
S!SATA6G_PCH_PCIE_UP_SATA_TXN<3>!C2L22!2!@baseboard_fab2_lib.baseboard_fab2(sch_1):page173_i234@mstr_discrete.cap(chips)!CAP_0402LF-0.01UF,25V,10%,X7R,A!!!F3560!B!!!!
S!SATA6G_P0_TX_C_DN!C2L40!1!@baseboard_fab2_lib.baseboard_fab2(sch_1):page173_i220@mstr_discrete.cap(chips)!CAP_0402LF-0.01UF,25V,10%,X7R,A!!!F3544!A!!!!
S!SATA6G_PCH_PCIE_UP_SATA_TXN<0>!C2L40!2!@baseboard_fab2_lib.baseboard_fab2(sch_1):page173_i220@mstr_discrete.cap(chips)!CAP_0402LF-0.01UF,25V,10%,X7R,A!!!F3544!B!!!!
S!SATA6G_P1_TX_C_DN!C2L44!1!@baseboard_fab2_lib.baseboard_fab2(sch_1):page173_i228@mstr_discrete.cap(chips)!CAP_0402LF-0.01UF,25V,10%,X7R,A!!!F3540!A!!!!
S!SATA6G_PCH_PCIE_UP_SATA_TXN<1>!C2L44!2!@baseboard_fab2_lib.baseboard_fab2(sch_1):page173_i228@mstr_discrete.cap(chips)!CAP_0402LF-0.01UF,25V,10%,X7R,A!!!F3540!B!!!!
S!FAN_TACH0!C1F9!1!@baseboard_fab2_lib.baseboard_fab2(sch_1):page161_i46@mstr_discrete.cap(chips)!CAP_0402LF-0.01UF,25V,10%,X7R,A!!!F3598!A!!!!
S!GND!C1F9!2!@baseboard_fab2_lib.baseboard_fab2(sch_1):page161_i46@mstr_discrete.cap(chips)!CAP_0402LF-0.01UF,25V,10%,X7R,A!!!F3598!B!!!!
S!FAN_TACH2!C1B15!1!@baseboard_fab2_lib.baseboard_fab2(sch_1):page161_i68@mstr_discrete.cap(chips)!CAP_0402LF-0.01UF,25V,10%,X7R,A!!!F3600!A!!!!
S!GND!C1B15!2!@baseboard_fab2_lib.baseboard_fab2(sch_1):page161_i68@mstr_discrete.cap(chips)!CAP_0402LF-0.01UF,25V,10%,X7R,A!!!F3600!B!!!!
S!P3V3_STBY_MNG_CPU!C2T18!1!@baseboard_fab2_lib.baseboard_fab2(sch_1):page101_i104@mstr_discrete.cap(chips)!CAP_0402LF-0.01UF,25V,10%,X7R,A!!!F3530!A!!!!
S!GND!C2T18!2!@baseboard_fab2_lib.baseboard_fab2(sch_1):page101_i104@mstr_discrete.cap(chips)!CAP_0402LF-0.01UF,25V,10%,X7R,A!!!F3530!B!!!!
S!P3V3_STBY_MNG_RMII!C2T37!1!@baseboard_fab2_lib.baseboard_fab2(sch_1):page101_i99@mstr_discrete.cap(chips)!CAP_0402LF-0.01UF,25V,10%,X7R,A!!!F3528!A!!!!
S!GND!C2T37!2!@baseboard_fab2_lib.baseboard_fab2(sch_1):page101_i99@mstr_discrete.cap(chips)!CAP_0402LF-0.01UF,25V,10%,X7R,A!!!F3528!B!!!!
S!P3V3_STBY_MNG_RGMII!C2T27!1!@baseboard_fab2_lib.baseboard_fab2(sch_1):page101_i90@mstr_discrete.cap(chips)!CAP_0402LF-0.01UF,25V,10%,X7R,A!!!F3529!A!!!!
S!GND!C2T27!2!@baseboard_fab2_lib.baseboard_fab2(sch_1):page101_i90@mstr_discrete.cap(chips)!CAP_0402LF-0.01UF,25V,10%,X7R,A!!!F3529!B!!!!
S!M_H_CPU_VREF!C1G8!1!@baseboard_fab2_lib.baseboard_fab2(sch_1):page100_i26@mstr_discrete.cap(chips)!CAP_0402LF-0.01UF,25V,10%,X7R,A!!!F3595!A!!!!
S!GND!C1G8!2!@baseboard_fab2_lib.baseboard_fab2(sch_1):page100_i26@mstr_discrete.cap(chips)!CAP_0402LF-0.01UF,25V,10%,X7R,A!!!F3595!B!!!!
S!M_J_CPU_VREF!C1G18!1!@baseboard_fab2_lib.baseboard_fab2(sch_1):page100_i42@mstr_discrete.cap(chips)!CAP_0402LF-0.01UF,25V,10%,X7R,A!!!F3593!A!!!!
S!GND!C1G18!2!@baseboard_fab2_lib.baseboard_fab2(sch_1):page100_i42@mstr_discrete.cap(chips)!CAP_0402LF-0.01UF,25V,10%,X7R,A!!!F3593!B!!!!
S!M_L_CPU_VREF!C9L8!1!@baseboard_fab2_lib.baseboard_fab2(sch_1):page100_i30@mstr_discrete.cap(chips)!CAP_0402LF-0.01UF,25V,10%,X7R,A!!!F3501!A!!!!
S!GND!C9L8!2!@baseboard_fab2_lib.baseboard_fab2(sch_1):page100_i30@mstr_discrete.cap(chips)!CAP_0402LF-0.01UF,25V,10%,X7R,A!!!F3501!B!!!!
S!M_M_CPU_VREF!C9L3!1!@baseboard_fab2_lib.baseboard_fab2(sch_1):page100_i46@mstr_discrete.cap(chips)!CAP_0402LF-0.01UF,25V,10%,X7R,A!!!F3503!A!!!!
S!GND!C9L3!2!@baseboard_fab2_lib.baseboard_fab2(sch_1):page100_i46@mstr_discrete.cap(chips)!CAP_0402LF-0.01UF,25V,10%,X7R,A!!!F3503!B!!!!
S!M_E_CPU_VREF!C6L7!1!@baseboard_fab2_lib.baseboard_fab2(sch_1):page98_i59@mstr_discrete.cap(chips)!CAP_0402LF-0.01UF,25V,10%,X7R,A!!!F3514!A!!!!
S!GND!C6L7!2!@baseboard_fab2_lib.baseboard_fab2(sch_1):page98_i59@mstr_discrete.cap(chips)!CAP_0402LF-0.01UF,25V,10%,X7R,A!!!F3514!B!!!!
S!M_B_CPU_VREF!C4G1!1!@baseboard_fab2_lib.baseboard_fab2(sch_1):page98_i43@mstr_discrete.cap(chips)!CAP_0402LF-0.01UF,25V,10%,X7R,A!!!F3521!A!!!!
S!GND!C4G1!2!@baseboard_fab2_lib.baseboard_fab2(sch_1):page98_i43@mstr_discrete.cap(chips)!CAP_0402LF-0.01UF,25V,10%,X7R,A!!!F3521!B!!!!
S!M_C_CPU_VREF!C4G17!1!@baseboard_fab2_lib.baseboard_fab2(sch_1):page98_i51@mstr_discrete.cap(chips)!CAP_0402LF-0.01UF,25V,10%,X7R,A!!!F3519!A!!!!
S!GND!C4G17!2!@baseboard_fab2_lib.baseboard_fab2(sch_1):page98_i51@mstr_discrete.cap(chips)!CAP_0402LF-0.01UF,25V,10%,X7R,A!!!F3519!B!!!!
S!M_F_CPU_VREF!C6L2!1!@baseboard_fab2_lib.baseboard_fab2(sch_1):page98_i67@mstr_discrete.cap(chips)!CAP_0402LF-0.01UF,25V,10%,X7R,A!!!F3516!A!!!!
S!GND!C6L2!2!@baseboard_fab2_lib.baseboard_fab2(sch_1):page98_i67@mstr_discrete.cap(chips)!CAP_0402LF-0.01UF,25V,10%,X7R,A!!!F3516!B!!!!
S!P1V538_BMC_STBY!C1T39!1!@baseboard_fab2_lib.baseboard_fab2(sch_1):page151_i64@mstr_discrete.cap(chips)!CAP_0402LF-0.01UF,25V,10%,X7R,A!!!F3579!A!!!!
S!M_BMC_DDR3_MVREF!C1T39!2!@baseboard_fab2_lib.baseboard_fab2(sch_1):page151_i64@mstr_discrete.cap(chips)!CAP_0402LF-0.01UF,25V,10%,X7R,A!!!F3579!B!!!!
S!M_BMC_DDR3_MVREF!C1T41!1!@baseboard_fab2_lib.baseboard_fab2(sch_1):page151_i63@mstr_discrete.cap(chips)!CAP_0402LF-0.01UF,25V,10%,X7R,A!!!F3578!A!!!!
S!GND!C1T41!2!@baseboard_fab2_lib.baseboard_fab2(sch_1):page151_i63@mstr_discrete.cap(chips)!CAP_0402LF-0.01UF,25V,10%,X7R,A!!!F3578!B!!!!
S!P1V26_BMC_STBY!C1T34!1!@baseboard_fab2_lib.baseboard_fab2(sch_1):page149_i80@mstr_discrete.cap(chips)!CAP_0402LF-0.01UF,25V,10%,X7R,A!!!F3581!A!!!!
S!GND!C1T34!2!@baseboard_fab2_lib.baseboard_fab2(sch_1):page149_i80@mstr_discrete.cap(chips)!CAP_0402LF-0.01UF,25V,10%,X7R,A!!!F3581!B!!!!
S!P1V26_BMC_STBY!C1T24!1!@baseboard_fab2_lib.baseboard_fab2(sch_1):page149_i81@mstr_discrete.cap(chips)!CAP_0402LF-0.01UF,25V,10%,X7R,A!!!F3583!A!!!!
S!GND!C1T24!2!@baseboard_fab2_lib.baseboard_fab2(sch_1):page149_i81@mstr_discrete.cap(chips)!CAP_0402LF-0.01UF,25V,10%,X7R,A!!!F3583!B!!!!
S!P1V26_BMC_STBY!C1T27!1!@baseboard_fab2_lib.baseboard_fab2(sch_1):page149_i82@mstr_discrete.cap(chips)!CAP_0402LF-0.01UF,25V,10%,X7R,A!!!F3582!A!!!!
S!GND!C1T27!2!@baseboard_fab2_lib.baseboard_fab2(sch_1):page149_i82@mstr_discrete.cap(chips)!CAP_0402LF-0.01UF,25V,10%,X7R,A!!!F3582!B!!!!
S!P1V26_BMC_STBY!C1T36!1!@baseboard_fab2_lib.baseboard_fab2(sch_1):page149_i83@mstr_discrete.cap(chips)!CAP_0402LF-0.01UF,25V,10%,X7R,A!!!F3580!A!!!!
S!GND!C1T36!2!@baseboard_fab2_lib.baseboard_fab2(sch_1):page149_i83@mstr_discrete.cap(chips)!CAP_0402LF-0.01UF,25V,10%,X7R,A!!!F3580!B!!!!
S!M_D_CPU_VREF!C6M2!1!@baseboard_fab2_lib.baseboard_fab2(sch_1):page98_i33@mstr_discrete.cap(chips)!CAP_0402LF-0.01UF,25V,10%,X7R,A!!!F3512!A!!!!
S!GND!C6M2!2!@baseboard_fab2_lib.baseboard_fab2(sch_1):page98_i33@mstr_discrete.cap(chips)!CAP_0402LF-0.01UF,25V,10%,X7R,A!!!F3512!B!!!!
S!M_A_CPU_VREF!C4F9!1!@baseboard_fab2_lib.baseboard_fab2(sch_1):page98_i7@mstr_discrete.cap(chips)!CAP_0402LF-0.01UF,25V,10%,X7R,A!!!F3523!A!!!!
S!GND!C4F9!2!@baseboard_fab2_lib.baseboard_fab2(sch_1):page98_i7@mstr_discrete.cap(chips)!CAP_0402LF-0.01UF,25V,10%,X7R,A!!!F3523!B!!!!
S!P3V3_STBY!C1M36!1!@baseboard_fab2_lib.baseboard_fab2(sch_1):page112_i42@mstr_discrete.cap(chips)!CAP_0402LF-0.01UF,25V,10%,X7R,A!!!F3505!A!!!!
S!GND!C1M36!2!@baseboard_fab2_lib.baseboard_fab2(sch_1):page112_i42@mstr_discrete.cap(chips)!CAP_0402LF-0.01UF,25V,10%,X7R,A!!!F3505!B!!!!
S!SATA6G_S1_TX_C_DP!C2L52!1!@baseboard_fab2_lib.baseboard_fab2(sch_1):page172_i6@mstr_discrete.cap(chips)!CAP_0402LF-0.01UF,25V,10%,X7R,A!!!F3534!A!!!!
S!SATA6G_S1_TX_DP!C2L52!2!@baseboard_fab2_lib.baseboard_fab2(sch_1):page172_i6@mstr_discrete.cap(chips)!CAP_0402LF-0.01UF,25V,10%,X7R,A!!!F3534!B!!!!
S!SATA6G_S1_RX_C_DN!C2L49!1!@baseboard_fab2_lib.baseboard_fab2(sch_1):page172_i5@mstr_discrete.cap(chips)!CAP_0402LF-0.01UF,25V,10%,X7R,A!!!F3537!A!!!!
S!SATA6G_S1_RX_DN!C2L49!2!@baseboard_fab2_lib.baseboard_fab2(sch_1):page172_i5@mstr_discrete.cap(chips)!CAP_0402LF-0.01UF,25V,10%,X7R,A!!!F3537!B!!!!
S!SATA6G_S1_TX_C_DN!C2L51!1!@baseboard_fab2_lib.baseboard_fab2(sch_1):page172_i8@mstr_discrete.cap(chips)!CAP_0402LF-0.01UF,25V,10%,X7R,A!!!F3535!A!!!!
S!SATA6G_S1_TX_DN!C2L51!2!@baseboard_fab2_lib.baseboard_fab2(sch_1):page172_i8@mstr_discrete.cap(chips)!CAP_0402LF-0.01UF,25V,10%,X7R,A!!!F3535!B!!!!
S!SATA6G_S1_RX_C_DP!C2L50!1!@baseboard_fab2_lib.baseboard_fab2(sch_1):page172_i7@mstr_discrete.cap(chips)!CAP_0402LF-0.01UF,25V,10%,X7R,A!!!F3536!A!!!!
S!SATA6G_S1_RX_DP!C2L50!2!@baseboard_fab2_lib.baseboard_fab2(sch_1):page172_i7@mstr_discrete.cap(chips)!CAP_0402LF-0.01UF,25V,10%,X7R,A!!!F3536!B!!!!
S!M_G_CPU_VREF!C1F19!1!@baseboard_fab2_lib.baseboard_fab2(sch_1):page100_i8@mstr_discrete.cap(chips)!CAP_0402LF-0.01UF,25V,10%,X7R,A!!!F3597!A!!!!
S!GND!C1F19!2!@baseboard_fab2_lib.baseboard_fab2(sch_1):page100_i8@mstr_discrete.cap(chips)!CAP_0402LF-0.01UF,25V,10%,X7R,A!!!F3597!B!!!!
S!M_K_CPU_VREF!C9M2!1!@baseboard_fab2_lib.baseboard_fab2(sch_1):page100_i15@mstr_discrete.cap(chips)!CAP_0402LF-0.01UF,25V,10%,X7R,A!!!F3499!A!!!!
S!GND!C9M2!2!@baseboard_fab2_lib.baseboard_fab2(sch_1):page100_i15@mstr_discrete.cap(chips)!CAP_0402LF-0.01UF,25V,10%,X7R,A!!!F3499!B!!!!
S!VR_FET_SW_P12V_PVCCIN_CPU1_R!C1B16!1!@baseboard_fab2_lib.baseboard_fab2(sch_1):page209_i30@mstr_discrete.cap(chips)!CAP_0402LF-0.1UF,16V,10%,EMPTYA!!!F3489!A!!!!
S!GND!C1B16!2!@baseboard_fab2_lib.baseboard_fab2(sch_1):page209_i30@mstr_discrete.cap(chips)!CAP_0402LF-0.1UF,16V,10%,EMPTYA!!!F3489!B!!!!
S!P1V8_BMC_STBY_PCIE!C1T17!1!@baseboard_fab2_lib.baseboard_fab2(sch_1):page149_i151@mstr_discrete.cap(chips)!CAP_0402LF-0.1UF,16V,10%,EMPTYA!!!F3487!A!!!!
S!GND!C1T17!2!@baseboard_fab2_lib.baseboard_fab2(sch_1):page149_i151@mstr_discrete.cap(chips)!CAP_0402LF-0.1UF,16V,10%,EMPTYA!!!F3487!B!!!!
S!VR_FET_SW_P12V_PVCCIN_CPU0_R!C4C2!1!@baseboard_fab2_lib.baseboard_fab2(sch_1):page204_i51@mstr_discrete.cap(chips)!CAP_0402LF-0.1UF,16V,10%,EMPTYA!!!F3482!A!!!!
S!GND!C4C2!2!@baseboard_fab2_lib.baseboard_fab2(sch_1):page204_i51@mstr_discrete.cap(chips)!CAP_0402LF-0.1UF,16V,10%,EMPTYA!!!F3482!B!!!!
S!P1V8_BMC_STBY_PCIEA!C9F15!1!@baseboard_fab2_lib.baseboard_fab2(sch_1):page149_i160@mstr_discrete.cap(chips)!CAP_0402LF-0.1UF,16V,10%,EMPTYA!!!F3481!A!!!!
S!GND!C9F15!2!@baseboard_fab2_lib.baseboard_fab2(sch_1):page149_i160@mstr_discrete.cap(chips)!CAP_0402LF-0.1UF,16V,10%,EMPTYA!!!F3481!B!!!!
S!P2E_SSB_BMC_RX_DN!C9F16!1!@baseboard_fab2_lib.baseboard_fab2(sch_1):page145_i202@mstr_discrete.cap(chips)!CAP_0402LF-0.1UF,16V,10%,EMPTYA!!!F3480!A!!!!
S!P2E_SSB_BMC_RX_C_DN!C9F16!2!@baseboard_fab2_lib.baseboard_fab2(sch_1):page145_i202@mstr_discrete.cap(chips)!CAP_0402LF-0.1UF,16V,10%,EMPTYA!!!F3480!B!!!!
S!P2E_SSB_BMC_RX_DP!C9F17!1!@baseboard_fab2_lib.baseboard_fab2(sch_1):page145_i201@mstr_discrete.cap(chips)!CAP_0402LF-0.1UF,16V,10%,EMPTYA!!!F3479!A!!!!
S!P2E_SSB_BMC_RX_C_DP!C9F17!2!@baseboard_fab2_lib.baseboard_fab2(sch_1):page145_i201@mstr_discrete.cap(chips)!CAP_0402LF-0.1UF,16V,10%,EMPTYA!!!F3479!B!!!!
S!P2E_SSB_BMC_TX_DP!C2M4!1!@baseboard_fab2_lib.baseboard_fab2(sch_1):page116_i182@mstr_discrete.cap(chips)!CAP_0402LF-0.1UF,16V,10%,EMPTYA!!!F3485!A!!!!
S!P2E_SSB_BMC_TX_C_DP!C2M4!2!@baseboard_fab2_lib.baseboard_fab2(sch_1):page116_i182@mstr_discrete.cap(chips)!CAP_0402LF-0.1UF,16V,10%,EMPTYA!!!F3485!B!!!!
S!P2E_SSB_BMC_TX_DN!C2M3!1!@baseboard_fab2_lib.baseboard_fab2(sch_1):page116_i183@mstr_discrete.cap(chips)!CAP_0402LF-0.1UF,16V,10%,EMPTYA!!!F3486!A!!!!
S!P2E_SSB_BMC_TX_C_DN!C2M3!2!@baseboard_fab2_lib.baseboard_fab2(sch_1):page116_i183@mstr_discrete.cap(chips)!CAP_0402LF-0.1UF,16V,10%,EMPTYA!!!F3486!B!!!!
S!VSENSE_PVCCIO_CPU1_SKT_VSEN!C3D27!1!@baseboard_fab2_lib.baseboard_fab2(sch_1):page214_i96@mstr_discrete.cap(chips)!CAP_0402LF-0.1UF,16V,10%,EMPTYA!!!F3484!A!!!!
S!VSENSE_PVCCIO_CPU1_SKT_VRTN!C3D27!2!@baseboard_fab2_lib.baseboard_fab2(sch_1):page214_i96@mstr_discrete.cap(chips)!CAP_0402LF-0.1UF,16V,10%,EMPTYA!!!F3484!B!!!!
S!VSENSE_PVCCIO_CPU0_SKT_VSEN!C3P1!1!@baseboard_fab2_lib.baseboard_fab2(sch_1):page212_i60@mstr_discrete.cap(chips)!CAP_0402LF-0.1UF,16V,10%,EMPTYA!!!F3483!A!!!!
S!VSENSE_PVCCIO_CPU0_SKT_VRTN!C3P1!2!@baseboard_fab2_lib.baseboard_fab2(sch_1):page212_i60@mstr_discrete.cap(chips)!CAP_0402LF-0.1UF,16V,10%,EMPTYA!!!F3483!B!!!!
S!A_HSC_VOUT!C9P12!1!@baseboard_fab2_lib.baseboard_fab2(sch_1):page199_i67@mstr_discrete.cap(chips)!CAP_0402LF-0.1UF,16V,10%,EMPTYA!!!F3478!A!!!!
S!AGND_HSC!C9P12!2!@baseboard_fab2_lib.baseboard_fab2(sch_1):page199_i67@mstr_discrete.cap(chips)!CAP_0402LF-0.1UF,16V,10%,EMPTYA!!!F3478!B!!!!
S!A_HSC_MON!C9P17!1!@baseboard_fab2_lib.baseboard_fab2(sch_1):page200_i36@mstr_discrete.cap(chips)!CAP_0402LF-0.1UF,16V,10%,EMPTYA!!!F3476!A!!!!
S!AGND_HSC!C9P17!2!@baseboard_fab2_lib.baseboard_fab2(sch_1):page200_i36@mstr_discrete.cap(chips)!CAP_0402LF-0.1UF,16V,10%,EMPTYA!!!F3476!B!!!!
S!A_HSC_MOP!C9P16!1!@baseboard_fab2_lib.baseboard_fab2(sch_1):page200_i40@mstr_discrete.cap(chips)!CAP_0402LF-0.1UF,16V,10%,EMPTYA!!!F3477!A!!!!
S!AGND_HSC!C9P16!2!@baseboard_fab2_lib.baseboard_fab2(sch_1):page200_i40@mstr_discrete.cap(chips)!CAP_0402LF-0.1UF,16V,10%,EMPTYA!!!F3477!B!!!!
S!A_HSC_MON!C1D22!1!@baseboard_fab2_lib.baseboard_fab2(sch_1):page200_i42@mstr_discrete.cap(chips)!CAP_0402LF-0.1UF,16V,10%,EMPTYA!!!F3488!A!!!!
S!A_HSC_MOP!C1D22!2!@baseboard_fab2_lib.baseboard_fab2(sch_1):page200_i42@mstr_discrete.cap(chips)!CAP_0402LF-0.1UF,16V,10%,EMPTYA!!!F3488!B!!!!
S!JTAG_MCP_TMS_R1!C1M33!1!@baseboard_fab2_lib.baseboard_fab2(sch_1):page113_i248@mstr_discrete.cap(chips)!CAP_0402LF-0.1UF,16V,10%,X7R,AA!!!F3216!A!!!!
S!GND!C1M33!2!@baseboard_fab2_lib.baseboard_fab2(sch_1):page113_i248@mstr_discrete.cap(chips)!CAP_0402LF-0.1UF,16V,10%,X7R,AA!!!F3216!B!!!!
S!JTAG_MCP_CPU1_TDI_R!C6M6!1!@baseboard_fab2_lib.baseboard_fab2(sch_1):page113_i250@mstr_discrete.cap(chips)!CAP_0402LF-0.1UF,16V,10%,X7R,AA!!!F3215!A!!!!
S!GND!C6M6!2!@baseboard_fab2_lib.baseboard_fab2(sch_1):page113_i250@mstr_discrete.cap(chips)!CAP_0402LF-0.1UF,16V,10%,X7R,AA!!!F3215!B!!!!
S!P3V3_STBY!C9F23!1!@baseboard_fab2_lib.baseboard_fab2(sch_1):page145_i258@mstr_discrete.cap(chips)!CAP_0402LF-0.1UF,16V,10%,X7R,AA!!!F3213!A!!!!
S!GND!C9F23!2!@baseboard_fab2_lib.baseboard_fab2(sch_1):page145_i258@mstr_discrete.cap(chips)!CAP_0402LF-0.1UF,16V,10%,X7R,AA!!!F3213!B!!!!
S!JTAG_MCP_CPU0_TDI_R!C4R2!1!@baseboard_fab2_lib.baseboard_fab2(sch_1):page113_i246@mstr_discrete.cap(chips)!CAP_0402LF-0.1UF,16V,10%,X7R,AA!!!F3214!A!!!!
S!GND!C4R2!2!@baseboard_fab2_lib.baseboard_fab2(sch_1):page113_i246@mstr_discrete.cap(chips)!CAP_0402LF-0.1UF,16V,10%,X7R,AA!!!F3214!B!!!!
S!KR_P3_OCP_RX_DP!C8C8!1!@baseboard_fab2_lib.baseboard_fab2(sch_1):page188_i64@mstr_discrete.cap(chips)!CAP_0402LF-0.1UF,16V,10%,X7R,AA!!!F3224!A!!!!
S!KR_P3_OCP_RX_C_DP!C8C8!2!@baseboard_fab2_lib.baseboard_fab2(sch_1):page188_i64@mstr_discrete.cap(chips)!CAP_0402LF-0.1UF,16V,10%,X7R,AA!!!F3224!B!!!!
S!KR_P3_OCP_RX_DN!C8C9!1!@baseboard_fab2_lib.baseboard_fab2(sch_1):page188_i68@mstr_discrete.cap(chips)!CAP_0402LF-0.1UF,16V,10%,X7R,AA!!!F3223!A!!!!
S!KR_P3_OCP_RX_C_DN!C8C9!2!@baseboard_fab2_lib.baseboard_fab2(sch_1):page188_i68@mstr_discrete.cap(chips)!CAP_0402LF-0.1UF,16V,10%,X7R,AA!!!F3223!B!!!!
S!KR_P2_OCP_RX_DP!C8C11!1!@baseboard_fab2_lib.baseboard_fab2(sch_1):page188_i72@mstr_discrete.cap(chips)!CAP_0402LF-0.1UF,16V,10%,X7R,AA!!!F3222!A!!!!
S!KR_P2_OCP_RX_C_DP!C8C11!2!@baseboard_fab2_lib.baseboard_fab2(sch_1):page188_i72@mstr_discrete.cap(chips)!CAP_0402LF-0.1UF,16V,10%,X7R,AA!!!F3222!B!!!!
S!KR_P2_OCP_RX_DN!C8C10!1!@baseboard_fab2_lib.baseboard_fab2(sch_1):page188_i73@mstr_discrete.cap(chips)!CAP_0402LF-0.1UF,16V,10%,X7R,AA!!!F3221!A!!!!
S!KR_P2_OCP_RX_C_DN!C8C10!2!@baseboard_fab2_lib.baseboard_fab2(sch_1):page188_i73@mstr_discrete.cap(chips)!CAP_0402LF-0.1UF,16V,10%,X7R,AA!!!F3221!B!!!!
S!KR_P1_OCP_RX_DP!C8C12!1!@baseboard_fab2_lib.baseboard_fab2(sch_1):page188_i80@mstr_discrete.cap(chips)!CAP_0402LF-0.1UF,16V,10%,X7R,AA!!!F3220!A!!!!
S!KR_P1_OCP_RX_C_DP!C8C12!2!@baseboard_fab2_lib.baseboard_fab2(sch_1):page188_i80@mstr_discrete.cap(chips)!CAP_0402LF-0.1UF,16V,10%,X7R,AA!!!F3220!B!!!!
S!KR_P1_OCP_RX_DN!C8C13!1!@baseboard_fab2_lib.baseboard_fab2(sch_1):page188_i81@mstr_discrete.cap(chips)!CAP_0402LF-0.1UF,16V,10%,X7R,AA!!!F3219!A!!!!
S!KR_P1_OCP_RX_C_DN!C8C13!2!@baseboard_fab2_lib.baseboard_fab2(sch_1):page188_i81@mstr_discrete.cap(chips)!CAP_0402LF-0.1UF,16V,10%,X7R,AA!!!F3219!B!!!!
S!KR_P0_OCP_RX_DP!C8C15!1!@baseboard_fab2_lib.baseboard_fab2(sch_1):page188_i82@mstr_discrete.cap(chips)!CAP_0402LF-0.1UF,16V,10%,X7R,AA!!!F3218!A!!!!
S!KR_P0_OCP_RX_C_DP!C8C15!2!@baseboard_fab2_lib.baseboard_fab2(sch_1):page188_i82@mstr_discrete.cap(chips)!CAP_0402LF-0.1UF,16V,10%,X7R,AA!!!F3218!B!!!!
S!KR_P0_OCP_RX_DN!C8C14!1!@baseboard_fab2_lib.baseboard_fab2(sch_1):page188_i86@mstr_discrete.cap(chips)!CAP_0402LF-0.1UF,16V,10%,X7R,AA!!!F3217!A!!!!
S!KR_P0_OCP_RX_C_DN!C8C14!2!@baseboard_fab2_lib.baseboard_fab2(sch_1):page188_i86@mstr_discrete.cap(chips)!CAP_0402LF-0.1UF,16V,10%,X7R,AA!!!F3217!B!!!!
S!P12V_STBY!C2P12!1!@baseboard_fab2_lib.baseboard_fab2(sch_1):page188_i23@mstr_discrete.cap(chips)!CAP_0402LF-0.1UF,16V,10%,X7R,AA!!!F3326!A!!!!
S!GND!C2P12!2!@baseboard_fab2_lib.baseboard_fab2(sch_1):page188_i23@mstr_discrete.cap(chips)!CAP_0402LF-0.1UF,16V,10%,X7R,AA!!!F3326!B!!!!
S!P12V_STBY!C2P11!1!@baseboard_fab2_lib.baseboard_fab2(sch_1):page188_i21@mstr_discrete.cap(chips)!CAP_0402LF-0.1UF,16V,10%,X7R,AA!!!F3307!A!!!!
S!GND!C2P11!2!@baseboard_fab2_lib.baseboard_fab2(sch_1):page188_i21@mstr_discrete.cap(chips)!CAP_0402LF-0.1UF,16V,10%,X7R,AA!!!F3307!B!!!!
S!P12V_STBY!C2R15!1!@baseboard_fab2_lib.baseboard_fab2(sch_1):page188_i2@mstr_discrete.cap(chips)!CAP_0402LF-0.1UF,16V,10%,X7R,AA!!!F3306!A!!!!
S!GND!C2R15!2!@baseboard_fab2_lib.baseboard_fab2(sch_1):page188_i2@mstr_discrete.cap(chips)!CAP_0402LF-0.1UF,16V,10%,X7R,AA!!!F3306!B!!!!
S!P12V_STBY!C2P13!1!@baseboard_fab2_lib.baseboard_fab2(sch_1):page188_i57@mstr_discrete.cap(chips)!CAP_0402LF-0.1UF,16V,10%,X7R,AA!!!F3294!A!!!!
S!GND!C2P13!2!@baseboard_fab2_lib.baseboard_fab2(sch_1):page188_i57@mstr_discrete.cap(chips)!CAP_0402LF-0.1UF,16V,10%,X7R,AA!!!F3294!B!!!!
S!P12V_STBY!C2P14!1!@baseboard_fab2_lib.baseboard_fab2(sch_1):page188_i56@mstr_discrete.cap(chips)!CAP_0402LF-0.1UF,16V,10%,X7R,AA!!!F3273!A!!!!
S!GND!C2P14!2!@baseboard_fab2_lib.baseboard_fab2(sch_1):page188_i56@mstr_discrete.cap(chips)!CAP_0402LF-0.1UF,16V,10%,X7R,AA!!!F3273!B!!!!
S!P12V_STBY!C2P15!1!@baseboard_fab2_lib.baseboard_fab2(sch_1):page188_i55@mstr_discrete.cap(chips)!CAP_0402LF-0.1UF,16V,10%,X7R,AA!!!F3258!A!!!!
S!GND!C2P15!2!@baseboard_fab2_lib.baseboard_fab2(sch_1):page188_i55@mstr_discrete.cap(chips)!CAP_0402LF-0.1UF,16V,10%,X7R,AA!!!F3258!B!!!!
S!P12V_STBY!C2P16!1!@baseboard_fab2_lib.baseboard_fab2(sch_1):page188_i53@mstr_discrete.cap(chips)!CAP_0402LF-0.1UF,16V,10%,X7R,AA!!!F3228!A!!!!
S!GND!C2P16!2!@baseboard_fab2_lib.baseboard_fab2(sch_1):page188_i53@mstr_discrete.cap(chips)!CAP_0402LF-0.1UF,16V,10%,X7R,AA!!!F3228!B!!!!
S!P12V_STBY!C2R16!1!@baseboard_fab2_lib.baseboard_fab2(sch_1):page188_i40@mstr_discrete.cap(chips)!CAP_0402LF-0.1UF,16V,10%,X7R,AA!!!F3227!A!!!!
S!GND!C2R16!2!@baseboard_fab2_lib.baseboard_fab2(sch_1):page188_i40@mstr_discrete.cap(chips)!CAP_0402LF-0.1UF,16V,10%,X7R,AA!!!F3227!B!!!!
S!P12V_STBY!C2R17!1!@baseboard_fab2_lib.baseboard_fab2(sch_1):page188_i25@mstr_discrete.cap(chips)!CAP_0402LF-0.1UF,16V,10%,X7R,AA!!!F3226!A!!!!
S!GND!C2R17!2!@baseboard_fab2_lib.baseboard_fab2(sch_1):page188_i25@mstr_discrete.cap(chips)!CAP_0402LF-0.1UF,16V,10%,X7R,AA!!!F3226!B!!!!
S!P12V_STBY!C2R18!1!@baseboard_fab2_lib.baseboard_fab2(sch_1):page188_i3@mstr_discrete.cap(chips)!CAP_0402LF-0.1UF,16V,10%,X7R,AA!!!F3225!A!!!!
S!GND!C2R18!2!@baseboard_fab2_lib.baseboard_fab2(sch_1):page188_i3@mstr_discrete.cap(chips)!CAP_0402LF-0.1UF,16V,10%,X7R,AA!!!F3225!B!!!!
S!P3V3_STBY!C7D1!1!@baseboard_fab2_lib.baseboard_fab2(sch_1):page118_i136@mstr_discrete.cap(chips)!CAP_0402LF-0.1UF,16V,10%,X7R,AA!!!F3287!A!!!!
S!GND!C7D1!2!@baseboard_fab2_lib.baseboard_fab2(sch_1):page118_i136@mstr_discrete.cap(chips)!CAP_0402LF-0.1UF,16V,10%,X7R,AA!!!F3287!B!!!!
S!A_HSC_PSET!C1D21!1!@baseboard_fab2_lib.baseboard_fab2(sch_1):page199_i121@mstr_discrete.cap(chips)!CAP_0402LF-0.1UF,16V,10%,X7R,AA!!!F3462!A!!!!
S!AGND_HSC!C1D21!2!@baseboard_fab2_lib.baseboard_fab2(sch_1):page199_i121@mstr_discrete.cap(chips)!CAP_0402LF-0.1UF,16V,10%,X7R,AA!!!F3462!B!!!!
S!VR_PVDDQ_GHJ_AIINSEN!C9U12!1!@baseboard_fab2_lib.baseboard_fab2(sch_1):page223_i92@mstr_discrete.cap(chips)!CAP_0402LF-0.1UF,16V,10%,X7R,AA!!!F3229!A!!!!
S!GND!C9U12!2!@baseboard_fab2_lib.baseboard_fab2(sch_1):page223_i92@mstr_discrete.cap(chips)!CAP_0402LF-0.1UF,16V,10%,X7R,AA!!!F3229!B!!!!
S!VR_PVDDQ_DEF_AIINSEN!C3L31!1!@baseboard_fab2_lib.baseboard_fab2(sch_1):page218_i77@mstr_discrete.cap(chips)!CAP_0402LF-0.1UF,16V,10%,X7R,AA!!!F3324!A!!!!
S!GND!C3L31!2!@baseboard_fab2_lib.baseboard_fab2(sch_1):page218_i77@mstr_discrete.cap(chips)!CAP_0402LF-0.1UF,16V,10%,X7R,AA!!!F3324!B!!!!
S!VR_PVDDQ_ABC_AIINSEN!C3U10!1!@baseboard_fab2_lib.baseboard_fab2(sch_1):page215_i360@mstr_discrete.cap(chips)!CAP_0402LF-0.1UF,16V,10%,X7R,AA!!!F3310!A!!!!
S!GND!C3U10!2!@baseboard_fab2_lib.baseboard_fab2(sch_1):page215_i360@mstr_discrete.cap(chips)!CAP_0402LF-0.1UF,16V,10%,X7R,AA!!!F3310!B!!!!
S!VR_PVDDQ_KLM_AIINSEN!C9M11!1!@baseboard_fab2_lib.baseboard_fab2(sch_1):page226_i92@mstr_discrete.cap(chips)!CAP_0402LF-0.1UF,16V,10%,X7R,AA!!!F3471!A!!!!
S!GND!C9M11!2!@baseboard_fab2_lib.baseboard_fab2(sch_1):page226_i92@mstr_discrete.cap(chips)!CAP_0402LF-0.1UF,16V,10%,X7R,AA!!!F3471!B!!!!
S!P3V3_STBY!C7E4!1!@baseboard_fab2_lib.baseboard_fab2(sch_1):page95_i115@mstr_discrete.cap(chips)!CAP_0402LF-0.1UF,16V,10%,X7R,AA!!!F3282!A!!!!
S!GND!C7E4!2!@baseboard_fab2_lib.baseboard_fab2(sch_1):page95_i115@mstr_discrete.cap(chips)!CAP_0402LF-0.1UF,16V,10%,X7R,AA!!!F3282!B!!!!
S!P3V3_STBY!C9F7!1!@baseboard_fab2_lib.baseboard_fab2(sch_1):page155_i184@mstr_discrete.cap(chips)!CAP_0402LF-0.1UF,16V,10%,X7R,AA!!!F3247!A!!!!
S!GND!C9F7!2!@baseboard_fab2_lib.baseboard_fab2(sch_1):page155_i184@mstr_discrete.cap(chips)!CAP_0402LF-0.1UF,16V,10%,X7R,AA!!!F3247!B!!!!
S!P3V3_STBY!C9F11!1!@baseboard_fab2_lib.baseboard_fab2(sch_1):page151_i90@mstr_discrete.cap(chips)!CAP_0402LF-0.1UF,16V,10%,X7R,AA!!!F3246!A!!!!
S!GND!C9F11!2!@baseboard_fab2_lib.baseboard_fab2(sch_1):page151_i90@mstr_discrete.cap(chips)!CAP_0402LF-0.1UF,16V,10%,X7R,AA!!!F3246!B!!!!
S!P3V3_STBY!C8F16!1!@baseboard_fab2_lib.baseboard_fab2(sch_1):page156_i275@mstr_discrete.cap(chips)!CAP_0402LF-0.1UF,16V,10%,X7R,AA!!!F3260!A!!!!
S!GND!C8F16!2!@baseboard_fab2_lib.baseboard_fab2(sch_1):page156_i275@mstr_discrete.cap(chips)!CAP_0402LF-0.1UF,16V,10%,X7R,AA!!!F3260!B!!!!
S!P3V3_STBY!C2T35!1!@baseboard_fab2_lib.baseboard_fab2(sch_1):page156_i273@mstr_discrete.cap(chips)!CAP_0402LF-0.1UF,16V,10%,X7R,AA!!!F3355!A!!!!
S!GND!C2T35!2!@baseboard_fab2_lib.baseboard_fab2(sch_1):page156_i273@mstr_discrete.cap(chips)!CAP_0402LF-0.1UF,16V,10%,X7R,AA!!!F3355!B!!!!
S!P3V3_STBY!C1L11!1!@baseboard_fab2_lib.baseboard_fab2(sch_1):page111_i87@mstr_discrete.cap(chips)!CAP_0402LF-0.1UF,16V,10%,X7R,AA!!!F3445!A!!!!
S!GND!C1L11!2!@baseboard_fab2_lib.baseboard_fab2(sch_1):page111_i87@mstr_discrete.cap(chips)!CAP_0402LF-0.1UF,16V,10%,X7R,AA!!!F3445!B!!!!
S!P3V3_STBY!C8E1!1!@baseboard_fab2_lib.baseboard_fab2(sch_1):page181_i253@mstr_discrete.cap(chips)!CAP_0402LF-0.1UF,16V,10%,X7R,AA!!!F3265!A!!!!
S!GND!C8E1!2!@baseboard_fab2_lib.baseboard_fab2(sch_1):page181_i253@mstr_discrete.cap(chips)!CAP_0402LF-0.1UF,16V,10%,X7R,AA!!!F3265!B!!!!
S!P3V3_STBY!C2T12!1!@baseboard_fab2_lib.baseboard_fab2(sch_1):page154_i132@mstr_discrete.cap(chips)!CAP_0402LF-0.1UF,16V,10%,X7R,AA!!!F3367!A!!!!
S!GND!C2T12!2!@baseboard_fab2_lib.baseboard_fab2(sch_1):page154_i132@mstr_discrete.cap(chips)!CAP_0402LF-0.1UF,16V,10%,X7R,AA!!!F3367!B!!!!
S!P3V3_STBY!C2T8!1!@baseboard_fab2_lib.baseboard_fab2(sch_1):page154_i135@mstr_discrete.cap(chips)!CAP_0402LF-0.1UF,16V,10%,X7R,AA!!!F3368!A!!!!
S!GND!C2T8!2!@baseboard_fab2_lib.baseboard_fab2(sch_1):page154_i135@mstr_discrete.cap(chips)!CAP_0402LF-0.1UF,16V,10%,X7R,AA!!!F3368!B!!!!
S!P3V3_STBY!C8D1!1!@baseboard_fab2_lib.baseboard_fab2(sch_1):page157_i376@mstr_discrete.cap(chips)!CAP_0402LF-0.1UF,16V,10%,X7R,AA!!!F3267!A!!!!
S!GND!C8D1!2!@baseboard_fab2_lib.baseboard_fab2(sch_1):page157_i376@mstr_discrete.cap(chips)!CAP_0402LF-0.1UF,16V,10%,X7R,AA!!!F3267!B!!!!
S!P3V3_STBY!C2T3!1!@baseboard_fab2_lib.baseboard_fab2(sch_1):page157_i370@mstr_discrete.cap(chips)!CAP_0402LF-0.1UF,16V,10%,X7R,AA!!!F3371!A!!!!
S!GND!C2T3!2!@baseboard_fab2_lib.baseboard_fab2(sch_1):page157_i370@mstr_discrete.cap(chips)!CAP_0402LF-0.1UF,16V,10%,X7R,AA!!!F3371!B!!!!
S!P3V3_DB1200!C6P9!1!@baseboard_fab2_lib.baseboard_fab2(sch_1):page102_i79@mstr_discrete.cap(chips)!CAP_0402LF-0.1UF,16V,10%,X7R,AA!!!F3299!A!!!!
S!GND!C6P9!2!@baseboard_fab2_lib.baseboard_fab2(sch_1):page102_i79@mstr_discrete.cap(chips)!CAP_0402LF-0.1UF,16V,10%,X7R,AA!!!F3299!B!!!!
S!P3V3_STBY_MNG!C2T34!1!@baseboard_fab2_lib.baseboard_fab2(sch_1):page101_i109@mstr_discrete.cap(chips)!CAP_0402LF-0.1UF,16V,10%,X7R,AA!!!F3356!A!!!!
S!GND!C2T34!2!@baseboard_fab2_lib.baseboard_fab2(sch_1):page101_i109@mstr_discrete.cap(chips)!CAP_0402LF-0.1UF,16V,10%,X7R,AA!!!F3356!B!!!!
S!P3V3_STBY!C9P11!1!@baseboard_fab2_lib.baseboard_fab2(sch_1):page200_i201@mstr_discrete.cap(chips)!CAP_0402LF-0.1UF,16V,10%,X7R,AA!!!F3235!A!!!!
S!GND!C9P11!2!@baseboard_fab2_lib.baseboard_fab2(sch_1):page200_i201@mstr_discrete.cap(chips)!CAP_0402LF-0.1UF,16V,10%,X7R,AA!!!F3235!B!!!!
S!P3V3_STBY!C8E8!1!@baseboard_fab2_lib.baseboard_fab2(sch_1):page136_i128@mstr_discrete.cap(chips)!CAP_0402LF-0.1UF,16V,10%,X7R,AA!!!F3262!A!!!!
S!GND!C8E8!2!@baseboard_fab2_lib.baseboard_fab2(sch_1):page136_i128@mstr_discrete.cap(chips)!CAP_0402LF-0.1UF,16V,10%,X7R,AA!!!F3262!B!!!!
S!A_HSC_UV!C1D26!1!@baseboard_fab2_lib.baseboard_fab2(sch_1):page199_i107@mstr_discrete.cap(chips)!CAP_0402LF-0.1UF,16V,10%,X7R,AA!!!F3461!A!!!!
S!AGND_HSC!C1D26!2!@baseboard_fab2_lib.baseboard_fab2(sch_1):page199_i107@mstr_discrete.cap(chips)!CAP_0402LF-0.1UF,16V,10%,X7R,AA!!!F3461!B!!!!
S!P12V_STBY!C1D9!1!@baseboard_fab2_lib.baseboard_fab2(sch_1):page200_i187@mstr_discrete.cap(chips)!CAP_0402LF-0.1UF,16V,10%,X7R,AA!!!F3465!A!!!!
S!AGND_HSC!C1D9!2!@baseboard_fab2_lib.baseboard_fab2(sch_1):page200_i187@mstr_discrete.cap(chips)!CAP_0402LF-0.1UF,16V,10%,X7R,AA!!!F3465!B!!!!
S!P12V_STBY!C9P6!1!@baseboard_fab2_lib.baseboard_fab2(sch_1):page200_i185@mstr_discrete.cap(chips)!CAP_0402LF-0.1UF,16V,10%,X7R,AA!!!F3236!A!!!!
S!AGND_HSC!C9P6!2!@baseboard_fab2_lib.baseboard_fab2(sch_1):page200_i185@mstr_discrete.cap(chips)!CAP_0402LF-0.1UF,16V,10%,X7R,AA!!!F3236!B!!!!
S!A_HSC_ISET!C9P15!1!@baseboard_fab2_lib.baseboard_fab2(sch_1):page199_i105@mstr_discrete.cap(chips)!CAP_0402LF-0.1UF,16V,10%,X7R,AA!!!F3234!A!!!!
S!AGND_HSC!C9P15!2!@baseboard_fab2_lib.baseboard_fab2(sch_1):page199_i105@mstr_discrete.cap(chips)!CAP_0402LF-0.1UF,16V,10%,X7R,AA!!!F3234!B!!!!
S!VR_FET_SW_P12V_STBY_PVPP_DEF!C7B6!1!@baseboard_fab2_lib.baseboard_fab2(sch_1):page232_i252@mstr_discrete.cap(chips)!CAP_0402LF-0.1UF,16V,10%,X7R,AA!!!F3289!A!!!!
S!GND!C7B6!2!@baseboard_fab2_lib.baseboard_fab2(sch_1):page232_i252@mstr_discrete.cap(chips)!CAP_0402LF-0.1UF,16V,10%,X7R,AA!!!F3289!B!!!!
S!VR_FET_SW_P12V_STBY_PVPP_ABC!C7F6!1!@baseboard_fab2_lib.baseboard_fab2(sch_1):page231_i205@mstr_discrete.cap(chips)!CAP_0402LF-0.1UF,16V,10%,X7R,AA!!!F3278!A!!!!
S!GND!C7F6!2!@baseboard_fab2_lib.baseboard_fab2(sch_1):page231_i205@mstr_discrete.cap(chips)!CAP_0402LF-0.1UF,16V,10%,X7R,AA!!!F3278!B!!!!
S!VR_FET_SW_P12V_STBY_PVPP_GHJ!C6U5!1!@baseboard_fab2_lib.baseboard_fab2(sch_1):page233_i242@mstr_discrete.cap(chips)!CAP_0402LF-0.1UF,16V,10%,X7R,AA!!!F3295!A!!!!
S!GND!C6U5!2!@baseboard_fab2_lib.baseboard_fab2(sch_1):page233_i242@mstr_discrete.cap(chips)!CAP_0402LF-0.1UF,16V,10%,X7R,AA!!!F3295!B!!!!
S!VR_FET_SW_P12V_STBY_PVPP_KLM!C4A20!1!@baseboard_fab2_lib.baseboard_fab2(sch_1):page234_i199@mstr_discrete.cap(chips)!CAP_0402LF-0.1UF,16V,10%,X7R,AA!!!F3325!A!!!!
S!GND!C4A20!2!@baseboard_fab2_lib.baseboard_fab2(sch_1):page234_i199@mstr_discrete.cap(chips)!CAP_0402LF-0.1UF,16V,10%,X7R,AA!!!F3325!B!!!!
S!P1V8_MCP_CPU0!C1M29!1!@baseboard_fab2_lib.baseboard_fab2(sch_1):page113_i147@mstr_discrete.cap(chips)!CAP_0402LF-0.1UF,16V,10%,X7R,AA!!!F3386!A!!!!
S!GND!C1M29!2!@baseboard_fab2_lib.baseboard_fab2(sch_1):page113_i147@mstr_discrete.cap(chips)!CAP_0402LF-0.1UF,16V,10%,X7R,AA!!!F3386!B!!!!
S!P3V3_STBY!C1R28!1!@baseboard_fab2_lib.baseboard_fab2(sch_1):page170_i49@mstr_discrete.cap(chips)!CAP_0402LF-0.1UF,16V,10%,X7R,AA!!!F3427!A!!!!
S!GND!C1R28!2!@baseboard_fab2_lib.baseboard_fab2(sch_1):page170_i49@mstr_discrete.cap(chips)!CAP_0402LF-0.1UF,16V,10%,X7R,AA!!!F3427!B!!!!
S!P3V3_STBY!C2P1!1!@baseboard_fab2_lib.baseboard_fab2(sch_1):page170_i8@mstr_discrete.cap(chips)!CAP_0402LF-0.1UF,16V,10%,X7R,AA!!!F3385!A!!!!
S!GND!C2P1!2!@baseboard_fab2_lib.baseboard_fab2(sch_1):page170_i8@mstr_discrete.cap(chips)!CAP_0402LF-0.1UF,16V,10%,X7R,AA!!!F3385!B!!!!
S!P3V3_STBY!C8D2!1!@baseboard_fab2_lib.baseboard_fab2(sch_1):page170_i33@mstr_discrete.cap(chips)!CAP_0402LF-0.1UF,16V,10%,X7R,AA!!!F3266!A!!!!
S!GND!C8D2!2!@baseboard_fab2_lib.baseboard_fab2(sch_1):page170_i33@mstr_discrete.cap(chips)!CAP_0402LF-0.1UF,16V,10%,X7R,AA!!!F3266!B!!!!
S!P3V3_STBY!C1R27!1!@baseboard_fab2_lib.baseboard_fab2(sch_1):page170_i30@mstr_discrete.cap(chips)!CAP_0402LF-0.1UF,16V,10%,X7R,AA!!!F3428!A!!!!
S!GND!C1R27!2!@baseboard_fab2_lib.baseboard_fab2(sch_1):page170_i30@mstr_discrete.cap(chips)!CAP_0402LF-0.1UF,16V,10%,X7R,AA!!!F3428!B!!!!
S!P3V3!C2T29!1!@baseboard_fab2_lib.baseboard_fab2(sch_1):page185_i120@mstr_discrete.cap(chips)!CAP_0402LF-0.1UF,16V,10%,X7R,AA!!!F3359!A!!!!
S!GND!C2T29!2!@baseboard_fab2_lib.baseboard_fab2(sch_1):page185_i120@mstr_discrete.cap(chips)!CAP_0402LF-0.1UF,16V,10%,X7R,AA!!!F3359!B!!!!
S!P3V3!C2T24!1!@baseboard_fab2_lib.baseboard_fab2(sch_1):page185_i129@mstr_discrete.cap(chips)!CAP_0402LF-0.1UF,16V,10%,X7R,AA!!!F3362!A!!!!
S!GND!C2T24!2!@baseboard_fab2_lib.baseboard_fab2(sch_1):page185_i129@mstr_discrete.cap(chips)!CAP_0402LF-0.1UF,16V,10%,X7R,AA!!!F3362!B!!!!
S!P3V3!C2T5!1!@baseboard_fab2_lib.baseboard_fab2(sch_1):page185_i135@mstr_discrete.cap(chips)!CAP_0402LF-0.1UF,16V,10%,X7R,AA!!!F3369!A!!!!
S!GND!C2T5!2!@baseboard_fab2_lib.baseboard_fab2(sch_1):page185_i135@mstr_discrete.cap(chips)!CAP_0402LF-0.1UF,16V,10%,X7R,AA!!!F3369!B!!!!
S!P3V3!C2T26!1!@baseboard_fab2_lib.baseboard_fab2(sch_1):page185_i123@mstr_discrete.cap(chips)!CAP_0402LF-0.1UF,16V,10%,X7R,AA!!!F3360!A!!!!
S!GND!C2T26!2!@baseboard_fab2_lib.baseboard_fab2(sch_1):page185_i123@mstr_discrete.cap(chips)!CAP_0402LF-0.1UF,16V,10%,X7R,AA!!!F3360!B!!!!
S!P3V3!C2T15!1!@baseboard_fab2_lib.baseboard_fab2(sch_1):page185_i127@mstr_discrete.cap(chips)!CAP_0402LF-0.1UF,16V,10%,X7R,AA!!!F3366!A!!!!
S!GND!C2T15!2!@baseboard_fab2_lib.baseboard_fab2(sch_1):page185_i127@mstr_discrete.cap(chips)!CAP_0402LF-0.1UF,16V,10%,X7R,AA!!!F3366!B!!!!
S!P3V3!C2T4!1!@baseboard_fab2_lib.baseboard_fab2(sch_1):page185_i132@mstr_discrete.cap(chips)!CAP_0402LF-0.1UF,16V,10%,X7R,AA!!!F3370!A!!!!
S!GND!C2T4!2!@baseboard_fab2_lib.baseboard_fab2(sch_1):page185_i132@mstr_discrete.cap(chips)!CAP_0402LF-0.1UF,16V,10%,X7R,AA!!!F3370!B!!!!
S!P3V3!C2T21!1!@baseboard_fab2_lib.baseboard_fab2(sch_1):page185_i124@mstr_discrete.cap(chips)!CAP_0402LF-0.1UF,16V,10%,X7R,AA!!!F3363!A!!!!
S!GND!C2T21!2!@baseboard_fab2_lib.baseboard_fab2(sch_1):page185_i124@mstr_discrete.cap(chips)!CAP_0402LF-0.1UF,16V,10%,X7R,AA!!!F3363!B!!!!
S!P3V3!C2T16!1!@baseboard_fab2_lib.baseboard_fab2(sch_1):page185_i126@mstr_discrete.cap(chips)!CAP_0402LF-0.1UF,16V,10%,X7R,AA!!!F3365!A!!!!
S!GND!C2T16!2!@baseboard_fab2_lib.baseboard_fab2(sch_1):page185_i126@mstr_discrete.cap(chips)!CAP_0402LF-0.1UF,16V,10%,X7R,AA!!!F3365!B!!!!
S!P3V3!C2T2!1!@baseboard_fab2_lib.baseboard_fab2(sch_1):page185_i131@mstr_discrete.cap(chips)!CAP_0402LF-0.1UF,16V,10%,X7R,AA!!!F3372!A!!!!
S!GND!C2T2!2!@baseboard_fab2_lib.baseboard_fab2(sch_1):page185_i131@mstr_discrete.cap(chips)!CAP_0402LF-0.1UF,16V,10%,X7R,AA!!!F3372!B!!!!
S!P3V3_STBY!C9F19!1!@baseboard_fab2_lib.baseboard_fab2(sch_1):page183_i7@mstr_discrete.cap(chips)!CAP_0402LF-0.1UF,16V,10%,X7R,AA!!!F3244!A!!!!
S!GND!C9F19!2!@baseboard_fab2_lib.baseboard_fab2(sch_1):page183_i7@mstr_discrete.cap(chips)!CAP_0402LF-0.1UF,16V,10%,X7R,AA!!!F3244!B!!!!
S!P3V3_STBY!C2U22!1!@baseboard_fab2_lib.baseboard_fab2(sch_1):page108_i318@mstr_discrete.cap(chips)!CAP_0402LF-0.1UF,16V,10%,X7R,AA!!!F3350!A!!!!
S!GND!C2U22!2!@baseboard_fab2_lib.baseboard_fab2(sch_1):page108_i318@mstr_discrete.cap(chips)!CAP_0402LF-0.1UF,16V,10%,X7R,AA!!!F3350!B!!!!
S!P3V3_STBY!C2U23!1!@baseboard_fab2_lib.baseboard_fab2(sch_1):page108_i315@mstr_discrete.cap(chips)!CAP_0402LF-0.1UF,16V,10%,X7R,AA!!!F3349!A!!!!
S!GND!C2U23!2!@baseboard_fab2_lib.baseboard_fab2(sch_1):page108_i315@mstr_discrete.cap(chips)!CAP_0402LF-0.1UF,16V,10%,X7R,AA!!!F3349!B!!!!
S!P3V3_STBY!C9F5!1!@baseboard_fab2_lib.baseboard_fab2(sch_1):page239_i71@mstr_discrete.cap(chips)!CAP_0402LF-0.1UF,16V,10%,X7R,AA!!!F3248!A!!!!
S!GND!C9F5!2!@baseboard_fab2_lib.baseboard_fab2(sch_1):page239_i71@mstr_discrete.cap(chips)!CAP_0402LF-0.1UF,16V,10%,X7R,AA!!!F3248!B!!!!
S!P5V_STBY_DGB_FS!C9A1!1!@baseboard_fab2_lib.baseboard_fab2(sch_1):page155_i127@mstr_discrete.cap(chips)!CAP_0402LF-0.1UF,16V,10%,X7R,AA!!!F3257!A!!!!
S!GND!C9A1!2!@baseboard_fab2_lib.baseboard_fab2(sch_1):page155_i127@mstr_discrete.cap(chips)!CAP_0402LF-0.1UF,16V,10%,X7R,AA!!!F3257!B!!!!
S!P3V3_STBY!C8E2!1!@baseboard_fab2_lib.baseboard_fab2(sch_1):page170_i40@mstr_discrete.cap(chips)!CAP_0402LF-0.1UF,16V,10%,X7R,AA!!!F3264!A!!!!
S!GND!C8E2!2!@baseboard_fab2_lib.baseboard_fab2(sch_1):page170_i40@mstr_discrete.cap(chips)!CAP_0402LF-0.1UF,16V,10%,X7R,AA!!!F3264!B!!!!
S!P3V3!C3F2!1!@baseboard_fab2_lib.baseboard_fab2(sch_1):page104_i34@mstr_discrete.cap(chips)!CAP_0402LF-0.1UF,16V,10%,X7R,AA!!!F3342!A!!!!
S!GND!C3F2!2!@baseboard_fab2_lib.baseboard_fab2(sch_1):page104_i34@mstr_discrete.cap(chips)!CAP_0402LF-0.1UF,16V,10%,X7R,AA!!!F3342!B!!!!
S!P3V3!C6F1!1!@baseboard_fab2_lib.baseboard_fab2(sch_1):page104_i25@mstr_discrete.cap(chips)!CAP_0402LF-0.1UF,16V,10%,X7R,AA!!!F3305!A!!!!
S!GND!C6F1!2!@baseboard_fab2_lib.baseboard_fab2(sch_1):page104_i25@mstr_discrete.cap(chips)!CAP_0402LF-0.1UF,16V,10%,X7R,AA!!!F3305!B!!!!
S!P3V3_STBY!C2P7!1!@baseboard_fab2_lib.baseboard_fab2(sch_1):page192_i20@mstr_discrete.cap(chips)!CAP_0402LF-0.1UF,16V,10%,X7R,AA!!!F3379!A!!!!
S!GND!C2P7!2!@baseboard_fab2_lib.baseboard_fab2(sch_1):page192_i20@mstr_discrete.cap(chips)!CAP_0402LF-0.1UF,16V,10%,X7R,AA!!!F3379!B!!!!
S!P3V3_STBY!C2R3!1!@baseboard_fab2_lib.baseboard_fab2(sch_1):page192_i19@mstr_discrete.cap(chips)!CAP_0402LF-0.1UF,16V,10%,X7R,AA!!!F3376!A!!!!
S!GND!C2R3!2!@baseboard_fab2_lib.baseboard_fab2(sch_1):page192_i19@mstr_discrete.cap(chips)!CAP_0402LF-0.1UF,16V,10%,X7R,AA!!!F3376!B!!!!
S!P3V3_STBY!C3P47!1!@baseboard_fab2_lib.baseboard_fab2(sch_1):page192_i12@mstr_discrete.cap(chips)!CAP_0402LF-0.1UF,16V,10%,X7R,AA!!!F3334!A!!!!
S!GND!C3P47!2!@baseboard_fab2_lib.baseboard_fab2(sch_1):page192_i12@mstr_discrete.cap(chips)!CAP_0402LF-0.1UF,16V,10%,X7R,AA!!!F3334!B!!!!
S!P3V3_STBY!C3P52!1!@baseboard_fab2_lib.baseboard_fab2(sch_1):page192_i17@mstr_discrete.cap(chips)!CAP_0402LF-0.1UF,16V,10%,X7R,AA!!!F3330!A!!!!
S!GND!C3P52!2!@baseboard_fab2_lib.baseboard_fab2(sch_1):page192_i17@mstr_discrete.cap(chips)!CAP_0402LF-0.1UF,16V,10%,X7R,AA!!!F3330!B!!!!
S!P3V3_STBY!C3P51!1!@baseboard_fab2_lib.baseboard_fab2(sch_1):page192_i11@mstr_discrete.cap(chips)!CAP_0402LF-0.1UF,16V,10%,X7R,AA!!!F3331!A!!!!
S!GND!C3P51!2!@baseboard_fab2_lib.baseboard_fab2(sch_1):page192_i11@mstr_discrete.cap(chips)!CAP_0402LF-0.1UF,16V,10%,X7R,AA!!!F3331!B!!!!
S!P3V3_STBY!C2P6!1!@baseboard_fab2_lib.baseboard_fab2(sch_1):page192_i18@mstr_discrete.cap(chips)!CAP_0402LF-0.1UF,16V,10%,X7R,AA!!!F3380!A!!!!
S!GND!C2P6!2!@baseboard_fab2_lib.baseboard_fab2(sch_1):page192_i18@mstr_discrete.cap(chips)!CAP_0402LF-0.1UF,16V,10%,X7R,AA!!!F3380!B!!!!
S!P3V3_STBY!C2R5!1!@baseboard_fab2_lib.baseboard_fab2(sch_1):page192_i15@mstr_discrete.cap(chips)!CAP_0402LF-0.1UF,16V,10%,X7R,AA!!!F3374!A!!!!
S!GND!C2R5!2!@baseboard_fab2_lib.baseboard_fab2(sch_1):page192_i15@mstr_discrete.cap(chips)!CAP_0402LF-0.1UF,16V,10%,X7R,AA!!!F3374!B!!!!
S!P3V3_STBY!C3R3!1!@baseboard_fab2_lib.baseboard_fab2(sch_1):page192_i7@mstr_discrete.cap(chips)!CAP_0402LF-0.1UF,16V,10%,X7R,AA!!!F3327!A!!!!
S!GND!C3R3!2!@baseboard_fab2_lib.baseboard_fab2(sch_1):page192_i7@mstr_discrete.cap(chips)!CAP_0402LF-0.1UF,16V,10%,X7R,AA!!!F3327!B!!!!
S!P3V3_STBY!C2R1!1!@baseboard_fab2_lib.baseboard_fab2(sch_1):page192_i8@mstr_discrete.cap(chips)!CAP_0402LF-0.1UF,16V,10%,X7R,AA!!!F3378!A!!!!
S!GND!C2R1!2!@baseboard_fab2_lib.baseboard_fab2(sch_1):page192_i8@mstr_discrete.cap(chips)!CAP_0402LF-0.1UF,16V,10%,X7R,AA!!!F3378!B!!!!
S!P3V3_STBY!C3P43!1!@baseboard_fab2_lib.baseboard_fab2(sch_1):page192_i6@mstr_discrete.cap(chips)!CAP_0402LF-0.1UF,16V,10%,X7R,AA!!!F3336!A!!!!
S!GND!C3P43!2!@baseboard_fab2_lib.baseboard_fab2(sch_1):page192_i6@mstr_discrete.cap(chips)!CAP_0402LF-0.1UF,16V,10%,X7R,AA!!!F3336!B!!!!
S!P3V3_STBY!C2P5!1!@baseboard_fab2_lib.baseboard_fab2(sch_1):page192_i3@mstr_discrete.cap(chips)!CAP_0402LF-0.1UF,16V,10%,X7R,AA!!!F3381!A!!!!
S!GND!C2P5!2!@baseboard_fab2_lib.baseboard_fab2(sch_1):page192_i3@mstr_discrete.cap(chips)!CAP_0402LF-0.1UF,16V,10%,X7R,AA!!!F3381!B!!!!
S!P3V3_STBY!C2P4!1!@baseboard_fab2_lib.baseboard_fab2(sch_1):page192_i16@mstr_discrete.cap(chips)!CAP_0402LF-0.1UF,16V,10%,X7R,AA!!!F3382!A!!!!
S!GND!C2P4!2!@baseboard_fab2_lib.baseboard_fab2(sch_1):page192_i16@mstr_discrete.cap(chips)!CAP_0402LF-0.1UF,16V,10%,X7R,AA!!!F3382!B!!!!
S!P3V3_STBY!C2P2!1!@baseboard_fab2_lib.baseboard_fab2(sch_1):page192_i9@mstr_discrete.cap(chips)!CAP_0402LF-0.1UF,16V,10%,X7R,AA!!!F3384!A!!!!
S!GND!C2P2!2!@baseboard_fab2_lib.baseboard_fab2(sch_1):page192_i9@mstr_discrete.cap(chips)!CAP_0402LF-0.1UF,16V,10%,X7R,AA!!!F3384!B!!!!
S!P3V3_STBY!C3R1!1!@baseboard_fab2_lib.baseboard_fab2(sch_1):page192_i4@mstr_discrete.cap(chips)!CAP_0402LF-0.1UF,16V,10%,X7R,AA!!!F3329!A!!!!
S!GND!C3R1!2!@baseboard_fab2_lib.baseboard_fab2(sch_1):page192_i4@mstr_discrete.cap(chips)!CAP_0402LF-0.1UF,16V,10%,X7R,AA!!!F3329!B!!!!
S!P3V3_STBY!C3R2!1!@baseboard_fab2_lib.baseboard_fab2(sch_1):page192_i10@mstr_discrete.cap(chips)!CAP_0402LF-0.1UF,16V,10%,X7R,AA!!!F3328!A!!!!
S!GND!C3R2!2!@baseboard_fab2_lib.baseboard_fab2(sch_1):page192_i10@mstr_discrete.cap(chips)!CAP_0402LF-0.1UF,16V,10%,X7R,AA!!!F3328!B!!!!
S!P3V3_STBY!C2R4!1!@baseboard_fab2_lib.baseboard_fab2(sch_1):page192_i21@mstr_discrete.cap(chips)!CAP_0402LF-0.1UF,16V,10%,X7R,AA!!!F3375!A!!!!
S!GND!C2R4!2!@baseboard_fab2_lib.baseboard_fab2(sch_1):page192_i21@mstr_discrete.cap(chips)!CAP_0402LF-0.1UF,16V,10%,X7R,AA!!!F3375!B!!!!
S!P3V3_STBY!C2R2!1!@baseboard_fab2_lib.baseboard_fab2(sch_1):page192_i28@mstr_discrete.cap(chips)!CAP_0402LF-0.1UF,16V,10%,X7R,AA!!!F3377!A!!!!
S!GND!C2R2!2!@baseboard_fab2_lib.baseboard_fab2(sch_1):page192_i28@mstr_discrete.cap(chips)!CAP_0402LF-0.1UF,16V,10%,X7R,AA!!!F3377!B!!!!
S!P3V3_STBY!C2P3!1!@baseboard_fab2_lib.baseboard_fab2(sch_1):page192_i22@mstr_discrete.cap(chips)!CAP_0402LF-0.1UF,16V,10%,X7R,AA!!!F3383!A!!!!
S!GND!C2P3!2!@baseboard_fab2_lib.baseboard_fab2(sch_1):page192_i22@mstr_discrete.cap(chips)!CAP_0402LF-0.1UF,16V,10%,X7R,AA!!!F3383!B!!!!
S!P3V3_STBY!C3P44!1!@baseboard_fab2_lib.baseboard_fab2(sch_1):page192_i23@mstr_discrete.cap(chips)!CAP_0402LF-0.1UF,16V,10%,X7R,AA!!!F3335!A!!!!
S!GND!C3P44!2!@baseboard_fab2_lib.baseboard_fab2(sch_1):page192_i23@mstr_discrete.cap(chips)!CAP_0402LF-0.1UF,16V,10%,X7R,AA!!!F3335!B!!!!
S!P3V3_STBY!C3P48!1!@baseboard_fab2_lib.baseboard_fab2(sch_1):page192_i25@mstr_discrete.cap(chips)!CAP_0402LF-0.1UF,16V,10%,X7R,AA!!!F3333!A!!!!
S!GND!C3P48!2!@baseboard_fab2_lib.baseboard_fab2(sch_1):page192_i25@mstr_discrete.cap(chips)!CAP_0402LF-0.1UF,16V,10%,X7R,AA!!!F3333!B!!!!
S!P3V3_DB1200_R!C4D22!1!@baseboard_fab2_lib.baseboard_fab2(sch_1):page102_i28@mstr_discrete.cap(chips)!CAP_0402LF-0.1UF,16V,10%,X7R,AA!!!F3319!A!!!!
S!GND!C4D22!2!@baseboard_fab2_lib.baseboard_fab2(sch_1):page102_i28@mstr_discrete.cap(chips)!CAP_0402LF-0.1UF,16V,10%,X7R,AA!!!F3319!B!!!!
S!P3V3_DB1200_A!C4D24!1!@baseboard_fab2_lib.baseboard_fab2(sch_1):page102_i18@mstr_discrete.cap(chips)!CAP_0402LF-0.1UF,16V,10%,X7R,AA!!!F3318!A!!!!
S!GND!C4D24!2!@baseboard_fab2_lib.baseboard_fab2(sch_1):page102_i18@mstr_discrete.cap(chips)!CAP_0402LF-0.1UF,16V,10%,X7R,AA!!!F3318!B!!!!
S!P3V3_DB1200!C6P4!1!@baseboard_fab2_lib.baseboard_fab2(sch_1):page102_i11@mstr_discrete.cap(chips)!CAP_0402LF-0.1UF,16V,10%,X7R,AA!!!F3302!A!!!!
S!GND!C6P4!2!@baseboard_fab2_lib.baseboard_fab2(sch_1):page102_i11@mstr_discrete.cap(chips)!CAP_0402LF-0.1UF,16V,10%,X7R,AA!!!F3302!B!!!!
S!P3V3_DB1200!C6P6!1!@baseboard_fab2_lib.baseboard_fab2(sch_1):page102_i12@mstr_discrete.cap(chips)!CAP_0402LF-0.1UF,16V,10%,X7R,AA!!!F3300!A!!!!
S!GND!C6P6!2!@baseboard_fab2_lib.baseboard_fab2(sch_1):page102_i12@mstr_discrete.cap(chips)!CAP_0402LF-0.1UF,16V,10%,X7R,AA!!!F3300!B!!!!
S!P3V3_DB1200!C6P10!1!@baseboard_fab2_lib.baseboard_fab2(sch_1):page102_i13@mstr_discrete.cap(chips)!CAP_0402LF-0.1UF,16V,10%,X7R,AA!!!F3298!A!!!!
S!GND!C6P10!2!@baseboard_fab2_lib.baseboard_fab2(sch_1):page102_i13@mstr_discrete.cap(chips)!CAP_0402LF-0.1UF,16V,10%,X7R,AA!!!F3298!B!!!!
S!P3V3_DB1200!C6P5!1!@baseboard_fab2_lib.baseboard_fab2(sch_1):page102_i14@mstr_discrete.cap(chips)!CAP_0402LF-0.1UF,16V,10%,X7R,AA!!!F3301!A!!!!
S!GND!C6P5!2!@baseboard_fab2_lib.baseboard_fab2(sch_1):page102_i14@mstr_discrete.cap(chips)!CAP_0402LF-0.1UF,16V,10%,X7R,AA!!!F3301!B!!!!
S!P3V3_DB1200!C6P12!1!@baseboard_fab2_lib.baseboard_fab2(sch_1):page102_i15@mstr_discrete.cap(chips)!CAP_0402LF-0.1UF,16V,10%,X7R,AA!!!F3296!A!!!!
S!GND!C6P12!2!@baseboard_fab2_lib.baseboard_fab2(sch_1):page102_i15@mstr_discrete.cap(chips)!CAP_0402LF-0.1UF,16V,10%,X7R,AA!!!F3296!B!!!!
S!P3V3_DB1200!C6P11!1!@baseboard_fab2_lib.baseboard_fab2(sch_1):page102_i16@mstr_discrete.cap(chips)!CAP_0402LF-0.1UF,16V,10%,X7R,AA!!!F3297!A!!!!
S!GND!C6P11!2!@baseboard_fab2_lib.baseboard_fab2(sch_1):page102_i16@mstr_discrete.cap(chips)!CAP_0402LF-0.1UF,16V,10%,X7R,AA!!!F3297!B!!!!
S!P3V3_STBY!C9A3!1!@baseboard_fab2_lib.baseboard_fab2(sch_1):page175_i40@mstr_discrete.cap(chips)!CAP_0402LF-0.1UF,16V,10%,X7R,AA!!!F3255!A!!!!
S!GND!C9A3!2!@baseboard_fab2_lib.baseboard_fab2(sch_1):page175_i40@mstr_discrete.cap(chips)!CAP_0402LF-0.1UF,16V,10%,X7R,AA!!!F3255!B!!!!
S!P3V3_STBY!C1L9!1!@baseboard_fab2_lib.baseboard_fab2(sch_1):page175_i38@mstr_discrete.cap(chips)!CAP_0402LF-0.1UF,16V,10%,X7R,AA!!!F3446!A!!!!
S!GND!C1L9!2!@baseboard_fab2_lib.baseboard_fab2(sch_1):page175_i38@mstr_discrete.cap(chips)!CAP_0402LF-0.1UF,16V,10%,X7R,AA!!!F3446!B!!!!
S!P3V3_STBY!C1L17!1!@baseboard_fab2_lib.baseboard_fab2(sch_1):page175_i37@mstr_discrete.cap(chips)!CAP_0402LF-0.1UF,16V,10%,X7R,AA!!!F3444!A!!!!
S!GND!C1L17!2!@baseboard_fab2_lib.baseboard_fab2(sch_1):page175_i37@mstr_discrete.cap(chips)!CAP_0402LF-0.1UF,16V,10%,X7R,AA!!!F3444!B!!!!
S!P5V_STBY!C1L4!1!@baseboard_fab2_lib.baseboard_fab2(sch_1):page175_i64@mstr_discrete.cap(chips)!CAP_0402LF-0.1UF,16V,10%,X7R,AA!!!F3448!A!!!!
S!GND!C1L4!2!@baseboard_fab2_lib.baseboard_fab2(sch_1):page175_i64@mstr_discrete.cap(chips)!CAP_0402LF-0.1UF,16V,10%,X7R,AA!!!F3448!B!!!!
S!P5V_STBY!C9M6!1!@baseboard_fab2_lib.baseboard_fab2(sch_1):page198_i67@mstr_discrete.cap(chips)!CAP_0402LF-0.1UF,16V,10%,X7R,AA!!!F3238!A!!!!
S!GND!C9M6!2!@baseboard_fab2_lib.baseboard_fab2(sch_1):page198_i67@mstr_discrete.cap(chips)!CAP_0402LF-0.1UF,16V,10%,X7R,AA!!!F3238!B!!!!
S!P12V_STBY!C9M9!1!@baseboard_fab2_lib.baseboard_fab2(sch_1):page198_i76@mstr_discrete.cap(chips)!CAP_0402LF-0.1UF,16V,10%,X7R,AA!!!F3237!A!!!!
S!GND!C9M9!2!@baseboard_fab2_lib.baseboard_fab2(sch_1):page198_i76@mstr_discrete.cap(chips)!CAP_0402LF-0.1UF,16V,10%,X7R,AA!!!F3237!B!!!!
S!P12V_FAN!C1B19!1!@baseboard_fab2_lib.baseboard_fab2(sch_1):page198_i64@mstr_discrete.cap(chips)!CAP_0402LF-0.1UF,16V,10%,X7R,AA!!!F3470!A!!!!
S!GND!C1B19!2!@baseboard_fab2_lib.baseboard_fab2(sch_1):page198_i64@mstr_discrete.cap(chips)!CAP_0402LF-0.1UF,16V,10%,X7R,AA!!!F3470!B!!!!
S!VR_PVNN_PCH_VDD!C2L11!1!@baseboard_fab2_lib.baseboard_fab2(sch_1):page235_i169@mstr_discrete.cap(chips)!CAP_0402LF-0.1UF,16V,10%,X7R,AA!!!F3389!A!!!!
S!GND!C2L11!2!@baseboard_fab2_lib.baseboard_fab2(sch_1):page235_i169@mstr_discrete.cap(chips)!CAP_0402LF-0.1UF,16V,10%,X7R,AA!!!F3389!B!!!!
S!P3V3_STBY!C8E18!1!@baseboard_fab2_lib.baseboard_fab2(sch_1):page154_i14@mstr_discrete.cap(chips)!CAP_0402LF-0.1UF,16V,10%,X7R,AA!!!F3261!A!!!!
S!GND!C8E18!2!@baseboard_fab2_lib.baseboard_fab2(sch_1):page154_i14@mstr_discrete.cap(chips)!CAP_0402LF-0.1UF,16V,10%,X7R,AA!!!F3261!B!!!!
S!P3V3_STBY!C1T10!1!@baseboard_fab2_lib.baseboard_fab2(sch_1):page158_i70@mstr_discrete.cap(chips)!CAP_0402LF-0.1UF,16V,10%,X7R,AA!!!F3421!A!!!!
S!GND!C1T10!2!@baseboard_fab2_lib.baseboard_fab2(sch_1):page158_i70@mstr_discrete.cap(chips)!CAP_0402LF-0.1UF,16V,10%,X7R,AA!!!F3421!B!!!!
S!P3V3_STBY!C1E22!1!@baseboard_fab2_lib.baseboard_fab2(sch_1):page161_i113@mstr_discrete.cap(chips)!CAP_0402LF-0.1UF,16V,10%,X7R,AA!!!F3453!A!!!!
S!GND!C1E22!2!@baseboard_fab2_lib.baseboard_fab2(sch_1):page161_i113@mstr_discrete.cap(chips)!CAP_0402LF-0.1UF,16V,10%,X7R,AA!!!F3453!B!!!!
S!P3V3_STBY!C2P9!1!@baseboard_fab2_lib.baseboard_fab2(sch_1):page185_i117@mstr_discrete.cap(chips)!CAP_0402LF-0.1UF,16V,10%,X7R,AA!!!F3268!A!!!!
S!GND!C2P9!2!@baseboard_fab2_lib.baseboard_fab2(sch_1):page185_i117@mstr_discrete.cap(chips)!CAP_0402LF-0.1UF,16V,10%,X7R,AA!!!F3268!B!!!!
S!P3V3_STBY!C7E3!1!@baseboard_fab2_lib.baseboard_fab2(sch_1):page95_i92@mstr_discrete.cap(chips)!CAP_0402LF-0.1UF,16V,10%,X7R,AA!!!F3283!A!!!!
S!GND!C7E3!2!@baseboard_fab2_lib.baseboard_fab2(sch_1):page95_i92@mstr_discrete.cap(chips)!CAP_0402LF-0.1UF,16V,10%,X7R,AA!!!F3283!B!!!!
S!VR_PVNN_P1V05_PCH_VD12!C8A8!1!@baseboard_fab2_lib.baseboard_fab2(sch_1):page235_i145@mstr_discrete.cap(chips)!CAP_0402LF-0.1UF,16V,10%,X7R,AA!!!F3272!A!!!!
S!GND!C8A8!2!@baseboard_fab2_lib.baseboard_fab2(sch_1):page235_i145@mstr_discrete.cap(chips)!CAP_0402LF-0.1UF,16V,10%,X7R,AA!!!F3272!B!!!!
S!VR_FET_SW_P12V_STBY_PVDDQ_DEF!C7A40!1!@baseboard_fab2_lib.baseboard_fab2(sch_1):page236_i35@mstr_discrete.cap(chips)!CAP_0402LF-0.1UF,16V,10%,X7R,AA!!!F3341!A!!!!
S!GND!C7A40!2!@baseboard_fab2_lib.baseboard_fab2(sch_1):page236_i35@mstr_discrete.cap(chips)!CAP_0402LF-0.1UF,16V,10%,X7R,AA!!!F3341!B!!!!
S!VR_FET_SW_P12V_STBY_PVDDQ_DEF!C7A39!1!@baseboard_fab2_lib.baseboard_fab2(sch_1):page236_i20@mstr_discrete.cap(chips)!CAP_0402LF-0.1UF,16V,10%,X7R,AA!!!F3340!A!!!!
S!GND!C7A39!2!@baseboard_fab2_lib.baseboard_fab2(sch_1):page236_i20@mstr_discrete.cap(chips)!CAP_0402LF-0.1UF,16V,10%,X7R,AA!!!F3340!B!!!!
S!P3V3_STBY!C2T1!1!@baseboard_fab2_lib.baseboard_fab2(sch_1):page154_i94@mstr_discrete.cap(chips)!CAP_0402LF-0.1UF,16V,10%,X7R,AA!!!F3373!A!!!!
S!GND!C2T1!2!@baseboard_fab2_lib.baseboard_fab2(sch_1):page154_i94@mstr_discrete.cap(chips)!CAP_0402LF-0.1UF,16V,10%,X7R,AA!!!F3373!B!!!!
S!P3V3_STBY!C8E5!1!@baseboard_fab2_lib.baseboard_fab2(sch_1):page142_i20@mstr_discrete.cap(chips)!CAP_0402LF-0.1UF,16V,10%,X7R,AA!!!F3263!A!!!!
S!GND!C8E5!2!@baseboard_fab2_lib.baseboard_fab2(sch_1):page142_i20@mstr_discrete.cap(chips)!CAP_0402LF-0.1UF,16V,10%,X7R,AA!!!F3263!B!!!!
S!P0V7_GTL2014_2!C1U22!1!@baseboard_fab2_lib.baseboard_fab2(sch_1):page152_i27@mstr_discrete.cap(chips)!CAP_0402LF-0.1UF,16V,10%,X7R,AA!!!F3390!A!!!!
S!GND!C1U22!2!@baseboard_fab2_lib.baseboard_fab2(sch_1):page152_i27@mstr_discrete.cap(chips)!CAP_0402LF-0.1UF,16V,10%,X7R,AA!!!F3390!B!!!!
S!VR_PVCCIO_CPU0_VD12!C3P5!1!@baseboard_fab2_lib.baseboard_fab2(sch_1):page211_i13@mstr_discrete.cap(chips)!CAP_0402LF-0.1UF,16V,10%,X7R,AA!!!F3338!A!!!!
S!GND!C3P5!2!@baseboard_fab2_lib.baseboard_fab2(sch_1):page211_i13@mstr_discrete.cap(chips)!CAP_0402LF-0.1UF,16V,10%,X7R,AA!!!F3338!B!!!!
S!VR_FET_SW_P12V_STBY_PVCCIO_CPU0!C7C11!1!@baseboard_fab2_lib.baseboard_fab2(sch_1):page212_i38@mstr_discrete.cap(chips)!CAP_0402LF-0.1UF,16V,10%,X7R,AA!!!F3288!A!!!!
S!GND!C7C11!2!@baseboard_fab2_lib.baseboard_fab2(sch_1):page212_i38@mstr_discrete.cap(chips)!CAP_0402LF-0.1UF,16V,10%,X7R,AA!!!F3288!B!!!!
S!VR_PVCCIO_CPU1_VD12!C4D32!1!@baseboard_fab2_lib.baseboard_fab2(sch_1):page213_i11@mstr_discrete.cap(chips)!CAP_0402LF-0.1UF,16V,10%,X7R,AA!!!F3316!A!!!!
S!GND!C4D32!2!@baseboard_fab2_lib.baseboard_fab2(sch_1):page213_i11@mstr_discrete.cap(chips)!CAP_0402LF-0.1UF,16V,10%,X7R,AA!!!F3316!B!!!!
S!VR_FET_SW_P12V_STBY_PVCCIN_CPU0!C4E13!1!@baseboard_fab2_lib.baseboard_fab2(sch_1):page214_i77@mstr_discrete.cap(chips)!CAP_0402LF-0.1UF,16V,10%,X7R,AA!!!F3312!A!!!!
S!GND!C4E13!2!@baseboard_fab2_lib.baseboard_fab2(sch_1):page214_i77@mstr_discrete.cap(chips)!CAP_0402LF-0.1UF,16V,10%,X7R,AA!!!F3312!B!!!!
S!VR_PVCCIO_CPU0_VDD!C3P7!1!@baseboard_fab2_lib.baseboard_fab2(sch_1):page211_i22@mstr_discrete.cap(chips)!CAP_0402LF-0.1UF,16V,10%,X7R,AA!!!F3337!A!!!!
S!GND!C3P7!2!@baseboard_fab2_lib.baseboard_fab2(sch_1):page211_i22@mstr_discrete.cap(chips)!CAP_0402LF-0.1UF,16V,10%,X7R,AA!!!F3337!B!!!!
S!VR_PVCCIO_CPU1_VDD!C4D38!1!@baseboard_fab2_lib.baseboard_fab2(sch_1):page213_i35@mstr_discrete.cap(chips)!CAP_0402LF-0.1UF,16V,10%,X7R,AA!!!F3314!A!!!!
S!GND!C4D38!2!@baseboard_fab2_lib.baseboard_fab2(sch_1):page213_i35@mstr_discrete.cap(chips)!CAP_0402LF-0.1UF,16V,10%,X7R,AA!!!F3314!B!!!!
S!P3V3_STBY!C2U27!1!@baseboard_fab2_lib.baseboard_fab2(sch_1):page161_i90@mstr_discrete.cap(chips)!CAP_0402LF-0.1UF,16V,10%,X7R,AA!!!F3346!A!!!!
S!GND!C2U27!2!@baseboard_fab2_lib.baseboard_fab2(sch_1):page161_i90@mstr_discrete.cap(chips)!CAP_0402LF-0.1UF,16V,10%,X7R,AA!!!F3346!B!!!!
S!P3V3_STBY!C2U28!1!@baseboard_fab2_lib.baseboard_fab2(sch_1):page161_i93@mstr_discrete.cap(chips)!CAP_0402LF-0.1UF,16V,10%,X7R,AA!!!F3345!A!!!!
S!GND!C2U28!2!@baseboard_fab2_lib.baseboard_fab2(sch_1):page161_i93@mstr_discrete.cap(chips)!CAP_0402LF-0.1UF,16V,10%,X7R,AA!!!F3345!B!!!!
S!P3V3_FB_ADC128_VCC!C9G19!1!@baseboard_fab2_lib.baseboard_fab2(sch_1):page165_i61@mstr_discrete.cap(chips)!CAP_0402LF-0.1UF,16V,10%,X7R,AA!!!F3240!A!!!!
S!GND!C9G19!2!@baseboard_fab2_lib.baseboard_fab2(sch_1):page165_i61@mstr_discrete.cap(chips)!CAP_0402LF-0.1UF,16V,10%,X7R,AA!!!F3240!B!!!!
S!VR_FET_SW_P12V_STBY_PVCCIN_CPU0!C4D35!1!@baseboard_fab2_lib.baseboard_fab2(sch_1):page203_i46@mstr_discrete.cap(chips)!CAP_0402LF-0.1UF,16V,10%,X7R,AA!!!F3315!A!!!!
S!GND!C4D35!2!@baseboard_fab2_lib.baseboard_fab2(sch_1):page203_i46@mstr_discrete.cap(chips)!CAP_0402LF-0.1UF,16V,10%,X7R,AA!!!F3315!B!!!!
S!VR_FET_SW_P12V_STBY_PVCCIN_CPU0!C4D11!1!@baseboard_fab2_lib.baseboard_fab2(sch_1):page203_i52@mstr_discrete.cap(chips)!CAP_0402LF-0.1UF,16V,10%,X7R,AA!!!F3321!A!!!!
S!GND!C4D11!2!@baseboard_fab2_lib.baseboard_fab2(sch_1):page203_i52@mstr_discrete.cap(chips)!CAP_0402LF-0.1UF,16V,10%,X7R,AA!!!F3321!B!!!!
S!P1V538_BMC_STBY!C1U10!1!@baseboard_fab2_lib.baseboard_fab2(sch_1):page151_i86@mstr_discrete.cap(chips)!CAP_0402LF-0.1UF,16V,10%,X7R,AA!!!F3396!A!!!!
S!GND!C1U10!2!@baseboard_fab2_lib.baseboard_fab2(sch_1):page151_i86@mstr_discrete.cap(chips)!CAP_0402LF-0.1UF,16V,10%,X7R,AA!!!F3396!B!!!!
S!P1V538_BMC_STBY!C1U14!1!@baseboard_fab2_lib.baseboard_fab2(sch_1):page151_i84@mstr_discrete.cap(chips)!CAP_0402LF-0.1UF,16V,10%,X7R,AA!!!F3393!A!!!!
S!GND!C1U14!2!@baseboard_fab2_lib.baseboard_fab2(sch_1):page151_i84@mstr_discrete.cap(chips)!CAP_0402LF-0.1UF,16V,10%,X7R,AA!!!F3393!B!!!!
S!P1V538_BMC_STBY!C1T54!1!@baseboard_fab2_lib.baseboard_fab2(sch_1):page151_i83@mstr_discrete.cap(chips)!CAP_0402LF-0.1UF,16V,10%,X7R,AA!!!F3401!A!!!!
S!GND!C1T54!2!@baseboard_fab2_lib.baseboard_fab2(sch_1):page151_i83@mstr_discrete.cap(chips)!CAP_0402LF-0.1UF,16V,10%,X7R,AA!!!F3401!B!!!!
S!P1V538_BMC_STBY!C1T53!1!@baseboard_fab2_lib.baseboard_fab2(sch_1):page151_i82@mstr_discrete.cap(chips)!CAP_0402LF-0.1UF,16V,10%,X7R,AA!!!F3402!A!!!!
S!GND!C1T53!2!@baseboard_fab2_lib.baseboard_fab2(sch_1):page151_i82@mstr_discrete.cap(chips)!CAP_0402LF-0.1UF,16V,10%,X7R,AA!!!F3402!B!!!!
S!P1V538_BMC_STBY!C1U16!1!@baseboard_fab2_lib.baseboard_fab2(sch_1):page151_i81@mstr_discrete.cap(chips)!CAP_0402LF-0.1UF,16V,10%,X7R,AA!!!F3391!A!!!!
S!GND!C1U16!2!@baseboard_fab2_lib.baseboard_fab2(sch_1):page151_i81@mstr_discrete.cap(chips)!CAP_0402LF-0.1UF,16V,10%,X7R,AA!!!F3391!B!!!!
S!P1V538_BMC_STBY!C1T33!1!@baseboard_fab2_lib.baseboard_fab2(sch_1):page151_i80@mstr_discrete.cap(chips)!CAP_0402LF-0.1UF,16V,10%,X7R,AA!!!F3412!A!!!!
S!GND!C1T33!2!@baseboard_fab2_lib.baseboard_fab2(sch_1):page151_i80@mstr_discrete.cap(chips)!CAP_0402LF-0.1UF,16V,10%,X7R,AA!!!F3412!B!!!!
S!P1V538_BMC_STBY!C1T40!1!@baseboard_fab2_lib.baseboard_fab2(sch_1):page151_i76@mstr_discrete.cap(chips)!CAP_0402LF-0.1UF,16V,10%,X7R,AA!!!F3409!A!!!!
S!GND!C1T40!2!@baseboard_fab2_lib.baseboard_fab2(sch_1):page151_i76@mstr_discrete.cap(chips)!CAP_0402LF-0.1UF,16V,10%,X7R,AA!!!F3409!B!!!!
S!P1V538_BMC_STBY!C1U13!1!@baseboard_fab2_lib.baseboard_fab2(sch_1):page151_i79@mstr_discrete.cap(chips)!CAP_0402LF-0.1UF,16V,10%,X7R,AA!!!F3394!A!!!!
S!GND!C1U13!2!@baseboard_fab2_lib.baseboard_fab2(sch_1):page151_i79@mstr_discrete.cap(chips)!CAP_0402LF-0.1UF,16V,10%,X7R,AA!!!F3394!B!!!!
S!P1V538_BMC_STBY!C1U15!1!@baseboard_fab2_lib.baseboard_fab2(sch_1):page151_i78@mstr_discrete.cap(chips)!CAP_0402LF-0.1UF,16V,10%,X7R,AA!!!F3392!A!!!!
S!GND!C1U15!2!@baseboard_fab2_lib.baseboard_fab2(sch_1):page151_i78@mstr_discrete.cap(chips)!CAP_0402LF-0.1UF,16V,10%,X7R,AA!!!F3392!B!!!!
S!M_BMC_DDR3_MVREF!C1T48!1!@baseboard_fab2_lib.baseboard_fab2(sch_1):page151_i58@mstr_discrete.cap(chips)!CAP_0402LF-0.1UF,16V,10%,X7R,AA!!!F3405!A!!!!
S!GND!C1T48!2!@baseboard_fab2_lib.baseboard_fab2(sch_1):page151_i58@mstr_discrete.cap(chips)!CAP_0402LF-0.1UF,16V,10%,X7R,AA!!!F3405!B!!!!
S!P12V_FAN!C1E20!1!@baseboard_fab2_lib.baseboard_fab2(sch_1):page161_i4@mstr_discrete.cap(chips)!CAP_0402LF-0.1UF,16V,10%,X7R,AA!!!F3454!A!!!!
S!GND!C1E20!2!@baseboard_fab2_lib.baseboard_fab2(sch_1):page161_i4@mstr_discrete.cap(chips)!CAP_0402LF-0.1UF,16V,10%,X7R,AA!!!F3454!B!!!!
S!P12V_FAN!C9M5!1!@baseboard_fab2_lib.baseboard_fab2(sch_1):page161_i26@mstr_discrete.cap(chips)!CAP_0402LF-0.1UF,16V,10%,X7R,AA!!!F3239!A!!!!
S!GND!C9M5!2!@baseboard_fab2_lib.baseboard_fab2(sch_1):page161_i26@mstr_discrete.cap(chips)!CAP_0402LF-0.1UF,16V,10%,X7R,AA!!!F3239!B!!!!
S!P12V_STBY!C7E5!1!@baseboard_fab2_lib.baseboard_fab2(sch_1):page198_i52@mstr_discrete.cap(chips)!CAP_0402LF-0.1UF,16V,10%,X7R,AA!!!F3281!A!!!!
S!GND!C7E5!2!@baseboard_fab2_lib.baseboard_fab2(sch_1):page198_i52@mstr_discrete.cap(chips)!CAP_0402LF-0.1UF,16V,10%,X7R,AA!!!F3281!B!!!!
S!P12V!C7E9!1!@baseboard_fab2_lib.baseboard_fab2(sch_1):page198_i49@mstr_discrete.cap(chips)!CAP_0402LF-0.1UF,16V,10%,X7R,AA!!!F3279!A!!!!
S!GND!C7E9!2!@baseboard_fab2_lib.baseboard_fab2(sch_1):page198_i49@mstr_discrete.cap(chips)!CAP_0402LF-0.1UF,16V,10%,X7R,AA!!!F3279!B!!!!
S!P3V3_STBY!C2T36!1!@baseboard_fab2_lib.baseboard_fab2(sch_1):page198_i43@mstr_discrete.cap(chips)!CAP_0402LF-0.1UF,16V,10%,X7R,AA!!!F3354!A!!!!
S!GND!C2T36!2!@baseboard_fab2_lib.baseboard_fab2(sch_1):page198_i43@mstr_discrete.cap(chips)!CAP_0402LF-0.1UF,16V,10%,X7R,AA!!!F3354!B!!!!
S!P3V3!C2U19!1!@baseboard_fab2_lib.baseboard_fab2(sch_1):page198_i46@mstr_discrete.cap(chips)!CAP_0402LF-0.1UF,16V,10%,X7R,AA!!!F3353!A!!!!
S!GND!C2U19!2!@baseboard_fab2_lib.baseboard_fab2(sch_1):page198_i46@mstr_discrete.cap(chips)!CAP_0402LF-0.1UF,16V,10%,X7R,AA!!!F3353!B!!!!
S!P5V_STBY!C8B5!1!@baseboard_fab2_lib.baseboard_fab2(sch_1):page198_i37@mstr_discrete.cap(chips)!CAP_0402LF-0.1UF,16V,10%,X7R,AA!!!F3271!A!!!!
S!GND!C8B5!2!@baseboard_fab2_lib.baseboard_fab2(sch_1):page198_i37@mstr_discrete.cap(chips)!CAP_0402LF-0.1UF,16V,10%,X7R,AA!!!F3271!B!!!!
S!P5V!C8B7!1!@baseboard_fab2_lib.baseboard_fab2(sch_1):page198_i41@mstr_discrete.cap(chips)!CAP_0402LF-0.1UF,16V,10%,X7R,AA!!!F3270!A!!!!
S!GND!C8B7!2!@baseboard_fab2_lib.baseboard_fab2(sch_1):page198_i41@mstr_discrete.cap(chips)!CAP_0402LF-0.1UF,16V,10%,X7R,AA!!!F3270!B!!!!
S!P5V_STBY!C8F17!1!@baseboard_fab2_lib.baseboard_fab2(sch_1):page198_i24@mstr_discrete.cap(chips)!CAP_0402LF-0.1UF,16V,10%,X7R,AA!!!F3259!A!!!!
S!GND!C8F17!2!@baseboard_fab2_lib.baseboard_fab2(sch_1):page198_i24@mstr_discrete.cap(chips)!CAP_0402LF-0.1UF,16V,10%,X7R,AA!!!F3259!B!!!!
S!P5V_STBY!C8E19!1!@baseboard_fab2_lib.baseboard_fab2(sch_1):page198_i28@mstr_discrete.cap(chips)!CAP_0402LF-0.1UF,16V,10%,X7R,AA!!!F3280!A!!!!
S!GND!C8E19!2!@baseboard_fab2_lib.baseboard_fab2(sch_1):page198_i28@mstr_discrete.cap(chips)!CAP_0402LF-0.1UF,16V,10%,X7R,AA!!!F3280!B!!!!
S!P5V_STBY!C8B8!1!@baseboard_fab2_lib.baseboard_fab2(sch_1):page198_i26@mstr_discrete.cap(chips)!CAP_0402LF-0.1UF,16V,10%,X7R,AA!!!F3269!A!!!!
S!GND!C8B8!2!@baseboard_fab2_lib.baseboard_fab2(sch_1):page198_i26@mstr_discrete.cap(chips)!CAP_0402LF-0.1UF,16V,10%,X7R,AA!!!F3269!B!!!!
S!A_PVCCRTC_EXT_CAP!C3N29!1!@baseboard_fab2_lib.baseboard_fab2(sch_1):page130_i16@mstr_discrete.cap(chips)!CAP_0402LF-0.1UF,16V,10%,X7R,AA!!!F3339!A!!!!
S!GND!C3N29!2!@baseboard_fab2_lib.baseboard_fab2(sch_1):page130_i16@mstr_discrete.cap(chips)!CAP_0402LF-0.1UF,16V,10%,X7R,AA!!!F3339!B!!!!
S!P3V3_STBY_BMC_HPLLAV33!C1T23!1!@baseboard_fab2_lib.baseboard_fab2(sch_1):page149_i147@mstr_discrete.cap(chips)!CAP_0402LF-0.1UF,16V,10%,X7R,AA!!!F3417!A!!!!
S!GND!C1T23!2!@baseboard_fab2_lib.baseboard_fab2(sch_1):page149_i147@mstr_discrete.cap(chips)!CAP_0402LF-0.1UF,16V,10%,X7R,AA!!!F3417!B!!!!
S!P3V3_STBY!C1T11!1!@baseboard_fab2_lib.baseboard_fab2(sch_1):page158_i97@mstr_discrete.cap(chips)!CAP_0402LF-0.1UF,16V,10%,X7R,AA!!!F3420!A!!!!
S!GND!C1T11!2!@baseboard_fab2_lib.baseboard_fab2(sch_1):page158_i97@mstr_discrete.cap(chips)!CAP_0402LF-0.1UF,16V,10%,X7R,AA!!!F3420!B!!!!
S!P5V!C1M38!1!@baseboard_fab2_lib.baseboard_fab2(sch_1):page176_i108@mstr_discrete.cap(chips)!CAP_0402LF-0.1UF,16V,10%,X7R,AA!!!F3252!A!!!!
S!GND!C1M38!2!@baseboard_fab2_lib.baseboard_fab2(sch_1):page176_i108@mstr_discrete.cap(chips)!CAP_0402LF-0.1UF,16V,10%,X7R,AA!!!F3252!B!!!!
S!GND_LAN_TRCT1234_C!C9G6!1!@baseboard_fab2_lib.baseboard_fab2(sch_1):page141_i47@mstr_discrete.cap(chips)!CAP_0402LF-0.1UF,16V,10%,X7R,AA!!!F3242!A!!!!
S!GND!C9G6!2!@baseboard_fab2_lib.baseboard_fab2(sch_1):page141_i47@mstr_discrete.cap(chips)!CAP_0402LF-0.1UF,16V,10%,X7R,AA!!!F3242!B!!!!
S!GND_LAN_TRCT1234_C!C9G4!1!@baseboard_fab2_lib.baseboard_fab2(sch_1):page141_i46@mstr_discrete.cap(chips)!CAP_0402LF-0.1UF,16V,10%,X7R,AA!!!F3243!A!!!!
S!GND!C9G4!2!@baseboard_fab2_lib.baseboard_fab2(sch_1):page141_i46@mstr_discrete.cap(chips)!CAP_0402LF-0.1UF,16V,10%,X7R,AA!!!F3243!B!!!!
S!P3V3_STBY!C9G7!1!@baseboard_fab2_lib.baseboard_fab2(sch_1):page141_i33@mstr_discrete.cap(chips)!CAP_0402LF-0.1UF,16V,10%,X7R,AA!!!F3241!A!!!!
S!GND!C9G7!2!@baseboard_fab2_lib.baseboard_fab2(sch_1):page141_i33@mstr_discrete.cap(chips)!CAP_0402LF-0.1UF,16V,10%,X7R,AA!!!F3241!B!!!!
S!P3V3_STBY!C9B7!1!@baseboard_fab2_lib.baseboard_fab2(sch_1):page167_i39@mstr_discrete.cap(chips)!CAP_0402LF-0.1UF,16V,10%,X7R,AA!!!F3251!A!!!!
S!GND!C9B7!2!@baseboard_fab2_lib.baseboard_fab2(sch_1):page167_i39@mstr_discrete.cap(chips)!CAP_0402LF-0.1UF,16V,10%,X7R,AA!!!F3251!B!!!!
S!P3V3_STBY!C9R14!1!@baseboard_fab2_lib.baseboard_fab2(sch_1):page167_i41@mstr_discrete.cap(chips)!CAP_0402LF-0.1UF,16V,10%,X7R,AA!!!F3230!A!!!!
S!GND!C9R14!2!@baseboard_fab2_lib.baseboard_fab2(sch_1):page167_i41@mstr_discrete.cap(chips)!CAP_0402LF-0.1UF,16V,10%,X7R,AA!!!F3230!B!!!!
S!P3V3_STBY!C9R13!1!@baseboard_fab2_lib.baseboard_fab2(sch_1):page167_i42@mstr_discrete.cap(chips)!CAP_0402LF-0.1UF,16V,10%,X7R,AA!!!F3231!A!!!!
S!GND!C9R13!2!@baseboard_fab2_lib.baseboard_fab2(sch_1):page167_i42@mstr_discrete.cap(chips)!CAP_0402LF-0.1UF,16V,10%,X7R,AA!!!F3231!B!!!!
S!VR_PVDDQ_DEF_VDD!C7A38!1!@baseboard_fab2_lib.baseboard_fab2(sch_1):page218_i31@mstr_discrete.cap(chips)!CAP_0402LF-0.1UF,16V,10%,X7R,AA!!!F3291!A!!!!
S!GND!C7A38!2!@baseboard_fab2_lib.baseboard_fab2(sch_1):page218_i31@mstr_discrete.cap(chips)!CAP_0402LF-0.1UF,16V,10%,X7R,AA!!!F3291!B!!!!
S!VR_PVDDQ_DEF_VD12!C7B2!1!@baseboard_fab2_lib.baseboard_fab2(sch_1):page218_i23@mstr_discrete.cap(chips)!CAP_0402LF-0.1UF,16V,10%,X7R,AA!!!F3290!A!!!!
S!GND!C7B2!2!@baseboard_fab2_lib.baseboard_fab2(sch_1):page218_i23@mstr_discrete.cap(chips)!CAP_0402LF-0.1UF,16V,10%,X7R,AA!!!F3290!B!!!!
S!VR_PVDDQ_GHJ_VDD!C1G25!1!@baseboard_fab2_lib.baseboard_fab2(sch_1):page223_i27@mstr_discrete.cap(chips)!CAP_0402LF-0.1UF,16V,10%,X7R,AA!!!F3449!A!!!!
S!GND!C1G25!2!@baseboard_fab2_lib.baseboard_fab2(sch_1):page223_i27@mstr_discrete.cap(chips)!CAP_0402LF-0.1UF,16V,10%,X7R,AA!!!F3449!B!!!!
S!VR_PVDDQ_GHJ_VD12!C1G22!1!@baseboard_fab2_lib.baseboard_fab2(sch_1):page223_i44@mstr_discrete.cap(chips)!CAP_0402LF-0.1UF,16V,10%,X7R,AA!!!F3450!A!!!!
S!GND!C1G22!2!@baseboard_fab2_lib.baseboard_fab2(sch_1):page223_i44@mstr_discrete.cap(chips)!CAP_0402LF-0.1UF,16V,10%,X7R,AA!!!F3450!B!!!!
S!VR_PVDDQ_KLM_VDD!C1B5!1!@baseboard_fab2_lib.baseboard_fab2(sch_1):page226_i27@mstr_discrete.cap(chips)!CAP_0402LF-0.1UF,16V,10%,X7R,AA!!!F3472!A!!!!
S!GND!C1B5!2!@baseboard_fab2_lib.baseboard_fab2(sch_1):page226_i27@mstr_discrete.cap(chips)!CAP_0402LF-0.1UF,16V,10%,X7R,AA!!!F3472!B!!!!
S!VR_PVDDQ_KLM_VD12!C1B2!1!@baseboard_fab2_lib.baseboard_fab2(sch_1):page226_i44@mstr_discrete.cap(chips)!CAP_0402LF-0.1UF,16V,10%,X7R,AA!!!F3473!A!!!!
S!GND!C1B2!2!@baseboard_fab2_lib.baseboard_fab2(sch_1):page226_i44@mstr_discrete.cap(chips)!CAP_0402LF-0.1UF,16V,10%,X7R,AA!!!F3473!B!!!!
S!PE_PCH_SPRV_TX_DN!C2M24!1!@baseboard_fab2_lib.baseboard_fab2(sch_1):page139_i90@mstr_discrete.cap(chips)!CAP_0402LF-0.1UF,16V,10%,X7R,AA!!!F3387!A!!!!
S!PE_PCH_SPRV_TX_C_DN!C2M24!2!@baseboard_fab2_lib.baseboard_fab2(sch_1):page139_i90@mstr_discrete.cap(chips)!CAP_0402LF-0.1UF,16V,10%,X7R,AA!!!F3387!B!!!!
S!PE_PCH_SPRV_TX_DP!C2M23!1!@baseboard_fab2_lib.baseboard_fab2(sch_1):page139_i89@mstr_discrete.cap(chips)!CAP_0402LF-0.1UF,16V,10%,X7R,AA!!!F3388!A!!!!
S!PE_PCH_SPRV_TX_C_DP!C2M23!2!@baseboard_fab2_lib.baseboard_fab2(sch_1):page139_i89@mstr_discrete.cap(chips)!CAP_0402LF-0.1UF,16V,10%,X7R,AA!!!F3388!B!!!!
S!PE_PCH_SPRV_RX_DP!C9E4!1!@baseboard_fab2_lib.baseboard_fab2(sch_1):page139_i88@mstr_discrete.cap(chips)!CAP_0402LF-0.1UF,16V,10%,X7R,AA!!!F3250!A!!!!
S!PE_PCH_SPRV_RX_C_DP!C9E4!2!@baseboard_fab2_lib.baseboard_fab2(sch_1):page139_i88@mstr_discrete.cap(chips)!CAP_0402LF-0.1UF,16V,10%,X7R,AA!!!F3250!B!!!!
S!PE_PCH_SPRV_RX_DN!C9E5!1!@baseboard_fab2_lib.baseboard_fab2(sch_1):page139_i87@mstr_discrete.cap(chips)!CAP_0402LF-0.1UF,16V,10%,X7R,AA!!!F3249!A!!!!
S!PE_PCH_SPRV_RX_C_DN!C9E5!2!@baseboard_fab2_lib.baseboard_fab2(sch_1):page139_i87@mstr_discrete.cap(chips)!CAP_0402LF-0.1UF,16V,10%,X7R,AA!!!F3249!B!!!!
S!VR_FET_SW_P12V_STBY_PVCCIN_CPU1!C1C25!1!@baseboard_fab2_lib.baseboard_fab2(sch_1):page209_i17@mstr_discrete.cap(chips)!CAP_0402LF-0.1UF,16V,10%,X7R,AA!!!F3466!A!!!!
S!GND!C1C25!2!@baseboard_fab2_lib.baseboard_fab2(sch_1):page209_i17@mstr_discrete.cap(chips)!CAP_0402LF-0.1UF,16V,10%,X7R,AA!!!F3466!B!!!!
S!P0V7_GTL2104_5_VREF!C2T32!1!@baseboard_fab2_lib.baseboard_fab2(sch_1):page93_i95@mstr_discrete.cap(chips)!CAP_0402LF-0.1UF,16V,10%,X7R,AA!!!F3357!A!!!!
S!GND!C2T32!2!@baseboard_fab2_lib.baseboard_fab2(sch_1):page93_i95@mstr_discrete.cap(chips)!CAP_0402LF-0.1UF,16V,10%,X7R,AA!!!F3357!B!!!!
S!P3V3_STBY_MNG!C2T17!1!@baseboard_fab2_lib.baseboard_fab2(sch_1):page101_i112@mstr_discrete.cap(chips)!CAP_0402LF-0.1UF,16V,10%,X7R,AA!!!F3364!A!!!!
S!GND!C2T17!2!@baseboard_fab2_lib.baseboard_fab2(sch_1):page101_i112@mstr_discrete.cap(chips)!CAP_0402LF-0.1UF,16V,10%,X7R,AA!!!F3364!B!!!!
S!P3V3_STBY_MNG!C2T25!1!@baseboard_fab2_lib.baseboard_fab2(sch_1):page101_i111@mstr_discrete.cap(chips)!CAP_0402LF-0.1UF,16V,10%,X7R,AA!!!F3361!A!!!!
S!GND!C2T25!2!@baseboard_fab2_lib.baseboard_fab2(sch_1):page101_i111@mstr_discrete.cap(chips)!CAP_0402LF-0.1UF,16V,10%,X7R,AA!!!F3361!B!!!!
S!P3V3_STBY_MNG!C2T30!1!@baseboard_fab2_lib.baseboard_fab2(sch_1):page101_i110@mstr_discrete.cap(chips)!CAP_0402LF-0.1UF,16V,10%,X7R,AA!!!F3358!A!!!!
S!GND!C2T30!2!@baseboard_fab2_lib.baseboard_fab2(sch_1):page101_i110@mstr_discrete.cap(chips)!CAP_0402LF-0.1UF,16V,10%,X7R,AA!!!F3358!B!!!!
S!P3V3_STBY!C1R25!1!@baseboard_fab2_lib.baseboard_fab2(sch_1):page140_i3@mstr_discrete.cap(chips)!CAP_0402LF-0.1UF,16V,10%,X7R,AA!!!F3430!A!!!!
S!GND!C1R25!2!@baseboard_fab2_lib.baseboard_fab2(sch_1):page140_i3@mstr_discrete.cap(chips)!CAP_0402LF-0.1UF,16V,10%,X7R,AA!!!F3430!B!!!!
S!P3V3_STBY!C1R20!1!@baseboard_fab2_lib.baseboard_fab2(sch_1):page139_i143@mstr_discrete.cap(chips)!CAP_0402LF-0.1UF,16V,10%,X7R,AA!!!F3433!A!!!!
S!GND!C1R20!2!@baseboard_fab2_lib.baseboard_fab2(sch_1):page139_i143@mstr_discrete.cap(chips)!CAP_0402LF-0.1UF,16V,10%,X7R,AA!!!F3433!B!!!!
S!P3V3_STBY!C1T3!1!@baseboard_fab2_lib.baseboard_fab2(sch_1):page139_i144@mstr_discrete.cap(chips)!CAP_0402LF-0.1UF,16V,10%,X7R,AA!!!F3424!A!!!!
S!GND!C1T3!2!@baseboard_fab2_lib.baseboard_fab2(sch_1):page139_i144@mstr_discrete.cap(chips)!CAP_0402LF-0.1UF,16V,10%,X7R,AA!!!F3424!B!!!!
S!P3V3_STBY!C1R14!1!@baseboard_fab2_lib.baseboard_fab2(sch_1):page139_i145@mstr_discrete.cap(chips)!CAP_0402LF-0.1UF,16V,10%,X7R,AA!!!F3437!A!!!!
S!GND!C1R14!2!@baseboard_fab2_lib.baseboard_fab2(sch_1):page139_i145@mstr_discrete.cap(chips)!CAP_0402LF-0.1UF,16V,10%,X7R,AA!!!F3437!B!!!!
S!P3V3_STBY!C1R21!1!@baseboard_fab2_lib.baseboard_fab2(sch_1):page139_i146@mstr_discrete.cap(chips)!CAP_0402LF-0.1UF,16V,10%,X7R,AA!!!F3432!A!!!!
S!GND!C1R21!2!@baseboard_fab2_lib.baseboard_fab2(sch_1):page139_i146@mstr_discrete.cap(chips)!CAP_0402LF-0.1UF,16V,10%,X7R,AA!!!F3432!B!!!!
S!P1V5_LAN!C1R31!1!@baseboard_fab2_lib.baseboard_fab2(sch_1):page139_i152@mstr_discrete.cap(chips)!CAP_0402LF-0.1UF,16V,10%,X7R,AA!!!F3425!A!!!!
S!GND!C1R31!2!@baseboard_fab2_lib.baseboard_fab2(sch_1):page139_i152@mstr_discrete.cap(chips)!CAP_0402LF-0.1UF,16V,10%,X7R,AA!!!F3425!B!!!!
S!P1V5_LAN!C1R19!1!@baseboard_fab2_lib.baseboard_fab2(sch_1):page139_i151@mstr_discrete.cap(chips)!CAP_0402LF-0.1UF,16V,10%,X7R,AA!!!F3434!A!!!!
S!GND!C1R19!2!@baseboard_fab2_lib.baseboard_fab2(sch_1):page139_i151@mstr_discrete.cap(chips)!CAP_0402LF-0.1UF,16V,10%,X7R,AA!!!F3434!B!!!!
S!P1V5_LAN!C1R29!1!@baseboard_fab2_lib.baseboard_fab2(sch_1):page139_i150@mstr_discrete.cap(chips)!CAP_0402LF-0.1UF,16V,10%,X7R,AA!!!F3426!A!!!!
S!GND!C1R29!2!@baseboard_fab2_lib.baseboard_fab2(sch_1):page139_i150@mstr_discrete.cap(chips)!CAP_0402LF-0.1UF,16V,10%,X7R,AA!!!F3426!B!!!!
S!P1V5_LAN!C1R26!1!@baseboard_fab2_lib.baseboard_fab2(sch_1):page139_i149@mstr_discrete.cap(chips)!CAP_0402LF-0.1UF,16V,10%,X7R,AA!!!F3429!A!!!!
S!GND!C1R26!2!@baseboard_fab2_lib.baseboard_fab2(sch_1):page139_i149@mstr_discrete.cap(chips)!CAP_0402LF-0.1UF,16V,10%,X7R,AA!!!F3429!B!!!!
S!P0V9_LAN!C1R15!1!@baseboard_fab2_lib.baseboard_fab2(sch_1):page139_i160@mstr_discrete.cap(chips)!CAP_0402LF-0.1UF,16V,10%,X7R,AA!!!F3436!A!!!!
S!GND!C1R15!2!@baseboard_fab2_lib.baseboard_fab2(sch_1):page139_i160@mstr_discrete.cap(chips)!CAP_0402LF-0.1UF,16V,10%,X7R,AA!!!F3436!B!!!!
S!P0V9_LAN!C1R24!1!@baseboard_fab2_lib.baseboard_fab2(sch_1):page139_i159@mstr_discrete.cap(chips)!CAP_0402LF-0.1UF,16V,10%,X7R,AA!!!F3431!A!!!!
S!GND!C1R24!2!@baseboard_fab2_lib.baseboard_fab2(sch_1):page139_i159@mstr_discrete.cap(chips)!CAP_0402LF-0.1UF,16V,10%,X7R,AA!!!F3431!B!!!!
S!P0V9_LAN!C1T5!1!@baseboard_fab2_lib.baseboard_fab2(sch_1):page139_i158@mstr_discrete.cap(chips)!CAP_0402LF-0.1UF,16V,10%,X7R,AA!!!F3423!A!!!!
S!GND!C1T5!2!@baseboard_fab2_lib.baseboard_fab2(sch_1):page139_i158@mstr_discrete.cap(chips)!CAP_0402LF-0.1UF,16V,10%,X7R,AA!!!F3423!B!!!!
S!P0V9_LAN!C1R18!1!@baseboard_fab2_lib.baseboard_fab2(sch_1):page139_i157@mstr_discrete.cap(chips)!CAP_0402LF-0.1UF,16V,10%,X7R,AA!!!F3435!A!!!!
S!GND!C1R18!2!@baseboard_fab2_lib.baseboard_fab2(sch_1):page139_i157@mstr_discrete.cap(chips)!CAP_0402LF-0.1UF,16V,10%,X7R,AA!!!F3435!B!!!!
S!USB3_P01_TXN!C1M2!1!@baseboard_fab2_lib.baseboard_fab2(sch_1):page176_i63@mstr_discrete.cap(chips)!CAP_0402LF-0.1UF,16V,10%,X7R,AA!!!F3442!A!!!!
S!USB3_P01_C_TXN!C1M2!2!@baseboard_fab2_lib.baseboard_fab2(sch_1):page176_i63@mstr_discrete.cap(chips)!CAP_0402LF-0.1UF,16V,10%,X7R,AA!!!F3442!B!!!!
S!USB3_P01_TXP!C1M1!1!@baseboard_fab2_lib.baseboard_fab2(sch_1):page176_i64@mstr_discrete.cap(chips)!CAP_0402LF-0.1UF,16V,10%,X7R,AA!!!F3443!A!!!!
S!USB3_P01_C_TXP!C1M1!2!@baseboard_fab2_lib.baseboard_fab2(sch_1):page176_i64@mstr_discrete.cap(chips)!CAP_0402LF-0.1UF,16V,10%,X7R,AA!!!F3443!B!!!!
S!P3V3_STBY!C1M20!1!@baseboard_fab2_lib.baseboard_fab2(sch_1):page186_i270@mstr_discrete.cap(chips)!CAP_0402LF-0.1UF,16V,10%,X7R,AA!!!F3441!A!!!!
S!GND!C1M20!2!@baseboard_fab2_lib.baseboard_fab2(sch_1):page186_i270@mstr_discrete.cap(chips)!CAP_0402LF-0.1UF,16V,10%,X7R,AA!!!F3441!B!!!!
S!P1V26_BMC_STBY_V1PLLAV12!C9F14!1!@baseboard_fab2_lib.baseboard_fab2(sch_1):page149_i105@mstr_discrete.cap(chips)!CAP_0402LF-0.1UF,16V,10%,X7R,AA!!!F3245!A!!!!
S!GND!C9F14!2!@baseboard_fab2_lib.baseboard_fab2(sch_1):page149_i105@mstr_discrete.cap(chips)!CAP_0402LF-0.1UF,16V,10%,X7R,AA!!!F3245!B!!!!
S!PVPP_GHJ!C4G25!1!@baseboard_fab2_lib.baseboard_fab2(sch_1):page99_i41@mstr_discrete.cap(chips)!CAP_0402LF-0.1UF,16V,10%,X7R,AA!!!F3308!A!!!!
S!GND!C4G25!2!@baseboard_fab2_lib.baseboard_fab2(sch_1):page99_i41@mstr_discrete.cap(chips)!CAP_0402LF-0.1UF,16V,10%,X7R,AA!!!F3308!B!!!!
S!PVCCIO_CPU1!C3B4!1!@baseboard_fab2_lib.baseboard_fab2(sch_1):page99_i47@mstr_discrete.cap(chips)!CAP_0402LF-0.1UF,16V,10%,X7R,AA!!!F3344!A!!!!
S!GND!C3B4!2!@baseboard_fab2_lib.baseboard_fab2(sch_1):page99_i47@mstr_discrete.cap(chips)!CAP_0402LF-0.1UF,16V,10%,X7R,AA!!!F3344!B!!!!
S!PVPP_KLM!C3B5!1!@baseboard_fab2_lib.baseboard_fab2(sch_1):page99_i53@mstr_discrete.cap(chips)!CAP_0402LF-0.1UF,16V,10%,X7R,AA!!!F3343!A!!!!
S!GND!C3B5!2!@baseboard_fab2_lib.baseboard_fab2(sch_1):page99_i53@mstr_discrete.cap(chips)!CAP_0402LF-0.1UF,16V,10%,X7R,AA!!!F3343!B!!!!
S!XDP_CPU_PWR_DEBUG_N!C9A4!1!@baseboard_fab2_lib.baseboard_fab2(sch_1):page111_i59@mstr_discrete.cap(chips)!CAP_0402LF-0.1UF,16V,10%,X7R,AA!!!F3254!A!!!!
S!GND!C9A4!2!@baseboard_fab2_lib.baseboard_fab2(sch_1):page111_i59@mstr_discrete.cap(chips)!CAP_0402LF-0.1UF,16V,10%,X7R,AA!!!F3254!B!!!!
S!XDP_SYSPWROK!C9A2!1!@baseboard_fab2_lib.baseboard_fab2(sch_1):page111_i10@mstr_discrete.cap(chips)!CAP_0402LF-0.1UF,16V,10%,X7R,AA!!!F3256!A!!!!
S!GND!C9A2!2!@baseboard_fab2_lib.baseboard_fab2(sch_1):page111_i10@mstr_discrete.cap(chips)!CAP_0402LF-0.1UF,16V,10%,X7R,AA!!!F3256!B!!!!
S!XDP_RST_CO_N!C9A5!1!@baseboard_fab2_lib.baseboard_fab2(sch_1):page111_i12@mstr_discrete.cap(chips)!CAP_0402LF-0.1UF,16V,10%,X7R,AA!!!F3253!A!!!!
S!GND!C9A5!2!@baseboard_fab2_lib.baseboard_fab2(sch_1):page111_i12@mstr_discrete.cap(chips)!CAP_0402LF-0.1UF,16V,10%,X7R,AA!!!F3253!B!!!!
S!XDP_PWRGD_RST_N!C1L8!1!@baseboard_fab2_lib.baseboard_fab2(sch_1):page111_i14@mstr_discrete.cap(chips)!CAP_0402LF-0.1UF,16V,10%,X7R,AA!!!F3447!A!!!!
S!GND!C1L8!2!@baseboard_fab2_lib.baseboard_fab2(sch_1):page111_i14@mstr_discrete.cap(chips)!CAP_0402LF-0.1UF,16V,10%,X7R,AA!!!F3447!B!!!!
S!P3V3!C2U21!1!@baseboard_fab2_lib.baseboard_fab2(sch_1):page108_i5@mstr_discrete.cap(chips)!CAP_0402LF-0.1UF,16V,10%,X7R,AA!!!F3351!A!!!!
S!GND!C2U21!2!@baseboard_fab2_lib.baseboard_fab2(sch_1):page108_i5@mstr_discrete.cap(chips)!CAP_0402LF-0.1UF,16V,10%,X7R,AA!!!F3351!B!!!!
S!P12V!C2U20!1!@baseboard_fab2_lib.baseboard_fab2(sch_1):page108_i1@mstr_discrete.cap(chips)!CAP_0402LF-0.1UF,16V,10%,X7R,AA!!!F3352!A!!!!
S!GND!C2U20!2!@baseboard_fab2_lib.baseboard_fab2(sch_1):page108_i1@mstr_discrete.cap(chips)!CAP_0402LF-0.1UF,16V,10%,X7R,AA!!!F3352!B!!!!
S!P3V3!C2U25!1!@baseboard_fab2_lib.baseboard_fab2(sch_1):page108_i7@mstr_discrete.cap(chips)!CAP_0402LF-0.1UF,16V,10%,X7R,AA!!!F3347!A!!!!
S!GND!C2U25!2!@baseboard_fab2_lib.baseboard_fab2(sch_1):page108_i7@mstr_discrete.cap(chips)!CAP_0402LF-0.1UF,16V,10%,X7R,AA!!!F3347!B!!!!
S!P12V!C2U24!1!@baseboard_fab2_lib.baseboard_fab2(sch_1):page108_i2@mstr_discrete.cap(chips)!CAP_0402LF-0.1UF,16V,10%,X7R,AA!!!F3348!A!!!!
S!GND!C2U24!2!@baseboard_fab2_lib.baseboard_fab2(sch_1):page108_i2@mstr_discrete.cap(chips)!CAP_0402LF-0.1UF,16V,10%,X7R,AA!!!F3348!B!!!!
S!P3V3_STBY!C1T52!1!@baseboard_fab2_lib.baseboard_fab2(sch_1):page149_i1@mstr_discrete.cap(chips)!CAP_0402LF-0.1UF,16V,10%,X7R,AA!!!F3403!A!!!!
S!GND!C1T52!2!@baseboard_fab2_lib.baseboard_fab2(sch_1):page149_i1@mstr_discrete.cap(chips)!CAP_0402LF-0.1UF,16V,10%,X7R,AA!!!F3403!B!!!!
S!P3V3_STBY!C1U3!1!@baseboard_fab2_lib.baseboard_fab2(sch_1):page149_i4@mstr_discrete.cap(chips)!CAP_0402LF-0.1UF,16V,10%,X7R,AA!!!F3400!A!!!!
S!GND!C1U3!2!@baseboard_fab2_lib.baseboard_fab2(sch_1):page149_i4@mstr_discrete.cap(chips)!CAP_0402LF-0.1UF,16V,10%,X7R,AA!!!F3400!B!!!!
S!P3V3_STBY!C1T29!1!@baseboard_fab2_lib.baseboard_fab2(sch_1):page149_i5@mstr_discrete.cap(chips)!CAP_0402LF-0.1UF,16V,10%,X7R,AA!!!F3414!A!!!!
S!GND!C1T29!2!@baseboard_fab2_lib.baseboard_fab2(sch_1):page149_i5@mstr_discrete.cap(chips)!CAP_0402LF-0.1UF,16V,10%,X7R,AA!!!F3414!B!!!!
S!P3V3_STBY!C1T30!1!@baseboard_fab2_lib.baseboard_fab2(sch_1):page149_i6@mstr_discrete.cap(chips)!CAP_0402LF-0.1UF,16V,10%,X7R,AA!!!F3413!A!!!!
S!GND!C1T30!2!@baseboard_fab2_lib.baseboard_fab2(sch_1):page149_i6@mstr_discrete.cap(chips)!CAP_0402LF-0.1UF,16V,10%,X7R,AA!!!F3413!B!!!!
S!P3V3_STBY!C1T43!1!@baseboard_fab2_lib.baseboard_fab2(sch_1):page149_i20@mstr_discrete.cap(chips)!CAP_0402LF-0.1UF,16V,10%,X7R,AA!!!F3408!A!!!!
S!GND!C1T43!2!@baseboard_fab2_lib.baseboard_fab2(sch_1):page149_i20@mstr_discrete.cap(chips)!CAP_0402LF-0.1UF,16V,10%,X7R,AA!!!F3408!B!!!!
S!P3V3_STBY!C1T45!1!@baseboard_fab2_lib.baseboard_fab2(sch_1):page149_i21@mstr_discrete.cap(chips)!CAP_0402LF-0.1UF,16V,10%,X7R,AA!!!F3407!A!!!!
S!GND!C1T45!2!@baseboard_fab2_lib.baseboard_fab2(sch_1):page149_i21@mstr_discrete.cap(chips)!CAP_0402LF-0.1UF,16V,10%,X7R,AA!!!F3407!B!!!!
S!P3V3_STBY!C1U4!1!@baseboard_fab2_lib.baseboard_fab2(sch_1):page149_i18@mstr_discrete.cap(chips)!CAP_0402LF-0.1UF,16V,10%,X7R,AA!!!F3399!A!!!!
S!GND!C1U4!2!@baseboard_fab2_lib.baseboard_fab2(sch_1):page149_i18@mstr_discrete.cap(chips)!CAP_0402LF-0.1UF,16V,10%,X7R,AA!!!F3399!B!!!!
S!P3V3_STBY!C1T47!1!@baseboard_fab2_lib.baseboard_fab2(sch_1):page149_i24@mstr_discrete.cap(chips)!CAP_0402LF-0.1UF,16V,10%,X7R,AA!!!F3406!A!!!!
S!GND!C1T47!2!@baseboard_fab2_lib.baseboard_fab2(sch_1):page149_i24@mstr_discrete.cap(chips)!CAP_0402LF-0.1UF,16V,10%,X7R,AA!!!F3406!B!!!!
S!P3V3_STBY!C1U11!1!@baseboard_fab2_lib.baseboard_fab2(sch_1):page149_i25@mstr_discrete.cap(chips)!CAP_0402LF-0.1UF,16V,10%,X7R,AA!!!F3395!A!!!!
S!GND!C1U11!2!@baseboard_fab2_lib.baseboard_fab2(sch_1):page149_i25@mstr_discrete.cap(chips)!CAP_0402LF-0.1UF,16V,10%,X7R,AA!!!F3395!B!!!!
S!P3V3_STBY!C1U9!1!@baseboard_fab2_lib.baseboard_fab2(sch_1):page149_i23@mstr_discrete.cap(chips)!CAP_0402LF-0.1UF,16V,10%,X7R,AA!!!F3397!A!!!!
S!GND!C1U9!2!@baseboard_fab2_lib.baseboard_fab2(sch_1):page149_i23@mstr_discrete.cap(chips)!CAP_0402LF-0.1UF,16V,10%,X7R,AA!!!F3397!B!!!!
S!P3V3_STBY!C1T22!1!@baseboard_fab2_lib.baseboard_fab2(sch_1):page149_i43@mstr_discrete.cap(chips)!CAP_0402LF-0.1UF,16V,10%,X7R,AA!!!F3418!A!!!!
S!GND!C1T22!2!@baseboard_fab2_lib.baseboard_fab2(sch_1):page149_i43@mstr_discrete.cap(chips)!CAP_0402LF-0.1UF,16V,10%,X7R,AA!!!F3418!B!!!!
S!P3V3_STBY!C1T50!1!@baseboard_fab2_lib.baseboard_fab2(sch_1):page149_i41@mstr_discrete.cap(chips)!CAP_0402LF-0.1UF,16V,10%,X7R,AA!!!F3404!A!!!!
S!GND!C1T50!2!@baseboard_fab2_lib.baseboard_fab2(sch_1):page149_i41@mstr_discrete.cap(chips)!CAP_0402LF-0.1UF,16V,10%,X7R,AA!!!F3404!B!!!!
S!P3V3_STBY!C1T8!1!@baseboard_fab2_lib.baseboard_fab2(sch_1):page149_i44@mstr_discrete.cap(chips)!CAP_0402LF-0.1UF,16V,10%,X7R,AA!!!F3422!A!!!!
S!GND!C1T8!2!@baseboard_fab2_lib.baseboard_fab2(sch_1):page149_i44@mstr_discrete.cap(chips)!CAP_0402LF-0.1UF,16V,10%,X7R,AA!!!F3422!B!!!!
S!P3V3_STBY!C1T25!1!@baseboard_fab2_lib.baseboard_fab2(sch_1):page149_i42@mstr_discrete.cap(chips)!CAP_0402LF-0.1UF,16V,10%,X7R,AA!!!F3416!A!!!!
S!GND!C1T25!2!@baseboard_fab2_lib.baseboard_fab2(sch_1):page149_i42@mstr_discrete.cap(chips)!CAP_0402LF-0.1UF,16V,10%,X7R,AA!!!F3416!B!!!!
S!P3V3_STBY!C1T14!1!@baseboard_fab2_lib.baseboard_fab2(sch_1):page149_i49@mstr_discrete.cap(chips)!CAP_0402LF-0.1UF,16V,10%,X7R,AA!!!F3419!A!!!!
S!GND!C1T14!2!@baseboard_fab2_lib.baseboard_fab2(sch_1):page149_i49@mstr_discrete.cap(chips)!CAP_0402LF-0.1UF,16V,10%,X7R,AA!!!F3419!B!!!!
S!P3V3_STBY!C1T26!1!@baseboard_fab2_lib.baseboard_fab2(sch_1):page149_i46@mstr_discrete.cap(chips)!CAP_0402LF-0.1UF,16V,10%,X7R,AA!!!F3415!A!!!!
S!GND!C1T26!2!@baseboard_fab2_lib.baseboard_fab2(sch_1):page149_i46@mstr_discrete.cap(chips)!CAP_0402LF-0.1UF,16V,10%,X7R,AA!!!F3415!B!!!!
S!VR_FET_SW_P12V_STBY_PVCCIN_CPU0!C4D49!1!@baseboard_fab2_lib.baseboard_fab2(sch_1):page202_i46@mstr_discrete.cap(chips)!CAP_0402LF-0.1UF,16V,10%,X7R,AA!!!F3313!A!!!!
S!GND!C4D49!2!@baseboard_fab2_lib.baseboard_fab2(sch_1):page202_i46@mstr_discrete.cap(chips)!CAP_0402LF-0.1UF,16V,10%,X7R,AA!!!F3313!B!!!!
S!VR_FET_SW_P12V_STBY_PVCCIN_CPU0!C4E20!1!@baseboard_fab2_lib.baseboard_fab2(sch_1):page202_i35@mstr_discrete.cap(chips)!CAP_0402LF-0.1UF,16V,10%,X7R,AA!!!F3311!A!!!!
S!GND!C4E20!2!@baseboard_fab2_lib.baseboard_fab2(sch_1):page202_i35@mstr_discrete.cap(chips)!CAP_0402LF-0.1UF,16V,10%,X7R,AA!!!F3311!B!!!!
S!VR_FET_SW_P12V_STBY_PVDDQ_ABC!C7G29!1!@baseboard_fab2_lib.baseboard_fab2(sch_1):page216_i51@mstr_discrete.cap(chips)!CAP_0402LF-0.1UF,16V,10%,X7R,AA!!!F3275!A!!!!
S!GND!C7G29!2!@baseboard_fab2_lib.baseboard_fab2(sch_1):page216_i51@mstr_discrete.cap(chips)!CAP_0402LF-0.1UF,16V,10%,X7R,AA!!!F3275!B!!!!
S!VR_FET_SW_P12V_STBY_PVDDQ_ABC!C7G36!1!@baseboard_fab2_lib.baseboard_fab2(sch_1):page216_i78@mstr_discrete.cap(chips)!CAP_0402LF-0.1UF,16V,10%,X7R,AA!!!F3274!A!!!!
S!GND!C7G36!2!@baseboard_fab2_lib.baseboard_fab2(sch_1):page216_i78@mstr_discrete.cap(chips)!CAP_0402LF-0.1UF,16V,10%,X7R,AA!!!F3274!B!!!!
S!VR_FET_SW_P12V_STBY_PVCCIN_CPU0!C4C10!1!@baseboard_fab2_lib.baseboard_fab2(sch_1):page205_i31@mstr_discrete.cap(chips)!CAP_0402LF-0.1UF,16V,10%,X7R,AA!!!F3323!A!!!!
S!GND!C4C10!2!@baseboard_fab2_lib.baseboard_fab2(sch_1):page205_i31@mstr_discrete.cap(chips)!CAP_0402LF-0.1UF,16V,10%,X7R,AA!!!F3323!B!!!!
S!VR_PVDDQ_ABC_VDD!C7F17!1!@baseboard_fab2_lib.baseboard_fab2(sch_1):page215_i311@mstr_discrete.cap(chips)!CAP_0402LF-0.1UF,16V,10%,X7R,AA!!!F3276!A!!!!
S!GND!C7F17!2!@baseboard_fab2_lib.baseboard_fab2(sch_1):page215_i311@mstr_discrete.cap(chips)!CAP_0402LF-0.1UF,16V,10%,X7R,AA!!!F3276!B!!!!
S!VR_PVDDQ_ABC_VD12!C7F15!1!@baseboard_fab2_lib.baseboard_fab2(sch_1):page215_i327@mstr_discrete.cap(chips)!CAP_0402LF-0.1UF,16V,10%,X7R,AA!!!F3277!A!!!!
S!GND!C7F15!2!@baseboard_fab2_lib.baseboard_fab2(sch_1):page215_i327@mstr_discrete.cap(chips)!CAP_0402LF-0.1UF,16V,10%,X7R,AA!!!F3277!B!!!!
S!VR_FET_SW_P12V_STBY_PVDDQ_DEF!C7A5!1!@baseboard_fab2_lib.baseboard_fab2(sch_1):page219_i51@mstr_discrete.cap(chips)!CAP_0402LF-0.1UF,16V,10%,X7R,AA!!!F3293!A!!!!
S!GND!C7A5!2!@baseboard_fab2_lib.baseboard_fab2(sch_1):page219_i51@mstr_discrete.cap(chips)!CAP_0402LF-0.1UF,16V,10%,X7R,AA!!!F3293!B!!!!
S!VR_FET_SW_P12V_STBY_PVDDQ_DEF!C7A20!1!@baseboard_fab2_lib.baseboard_fab2(sch_1):page219_i78@mstr_discrete.cap(chips)!CAP_0402LF-0.1UF,16V,10%,X7R,AA!!!F3292!A!!!!
S!GND!C7A20!2!@baseboard_fab2_lib.baseboard_fab2(sch_1):page219_i78@mstr_discrete.cap(chips)!CAP_0402LF-0.1UF,16V,10%,X7R,AA!!!F3292!B!!!!
S!VR_FET_SW_P12V_STBY_PVDDQ_KLM!C1A10!1!@baseboard_fab2_lib.baseboard_fab2(sch_1):page227_i51@mstr_discrete.cap(chips)!CAP_0402LF-0.1UF,16V,10%,X7R,AA!!!F3475!A!!!!
S!GND!C1A10!2!@baseboard_fab2_lib.baseboard_fab2(sch_1):page227_i51@mstr_discrete.cap(chips)!CAP_0402LF-0.1UF,16V,10%,X7R,AA!!!F3475!B!!!!
S!VR_FET_SW_P12V_STBY_PVDDQ_KLM!C1A20!1!@baseboard_fab2_lib.baseboard_fab2(sch_1):page227_i78@mstr_discrete.cap(chips)!CAP_0402LF-0.1UF,16V,10%,X7R,AA!!!F3474!A!!!!
S!GND!C1A20!2!@baseboard_fab2_lib.baseboard_fab2(sch_1):page227_i78@mstr_discrete.cap(chips)!CAP_0402LF-0.1UF,16V,10%,X7R,AA!!!F3474!B!!!!
S!VR_FET_SW_P12V_STBY_PVDDQ_GHJ!C1G14!1!@baseboard_fab2_lib.baseboard_fab2(sch_1):page224_i51@mstr_discrete.cap(chips)!CAP_0402LF-0.1UF,16V,10%,X7R,AA!!!F3451!A!!!!
S!GND!C1G14!2!@baseboard_fab2_lib.baseboard_fab2(sch_1):page224_i51@mstr_discrete.cap(chips)!CAP_0402LF-0.1UF,16V,10%,X7R,AA!!!F3451!B!!!!
S!VR_FET_SW_P12V_STBY_PVDDQ_GHJ!C1F28!1!@baseboard_fab2_lib.baseboard_fab2(sch_1):page224_i78@mstr_discrete.cap(chips)!CAP_0402LF-0.1UF,16V,10%,X7R,AA!!!F3452!A!!!!
S!GND!C1F28!2!@baseboard_fab2_lib.baseboard_fab2(sch_1):page224_i78@mstr_discrete.cap(chips)!CAP_0402LF-0.1UF,16V,10%,X7R,AA!!!F3452!B!!!!
S!VR_PVCCIN_CPU0_VDD!C4D19!1!@baseboard_fab2_lib.baseboard_fab2(sch_1):page201_i39@mstr_discrete.cap(chips)!CAP_0402LF-0.1UF,16V,10%,X7R,AA!!!F3320!A!!!!
S!GND!C4D19!2!@baseboard_fab2_lib.baseboard_fab2(sch_1):page201_i39@mstr_discrete.cap(chips)!CAP_0402LF-0.1UF,16V,10%,X7R,AA!!!F3320!B!!!!
S!VR_PVCCIN_CPU0_VD12!C4D26!1!@baseboard_fab2_lib.baseboard_fab2(sch_1):page201_i32@mstr_discrete.cap(chips)!CAP_0402LF-0.1UF,16V,10%,X7R,AA!!!F3317!A!!!!
S!GND!C4D26!2!@baseboard_fab2_lib.baseboard_fab2(sch_1):page201_i32@mstr_discrete.cap(chips)!CAP_0402LF-0.1UF,16V,10%,X7R,AA!!!F3317!B!!!!
S!VR_PVCCIN_CPU1_VDD!C1C9!1!@baseboard_fab2_lib.baseboard_fab2(sch_1):page206_i42@mstr_discrete.cap(chips)!CAP_0402LF-0.1UF,16V,10%,X7R,AA!!!F3469!A!!!!
S!GND!C1C9!2!@baseboard_fab2_lib.baseboard_fab2(sch_1):page206_i42@mstr_discrete.cap(chips)!CAP_0402LF-0.1UF,16V,10%,X7R,AA!!!F3469!B!!!!
S!VR_PVCCIN_CPU1_VD12!C1C14!1!@baseboard_fab2_lib.baseboard_fab2(sch_1):page206_i31@mstr_discrete.cap(chips)!CAP_0402LF-0.1UF,16V,10%,X7R,AA!!!F3468!A!!!!
S!GND!C1C14!2!@baseboard_fab2_lib.baseboard_fab2(sch_1):page206_i31@mstr_discrete.cap(chips)!CAP_0402LF-0.1UF,16V,10%,X7R,AA!!!F3468!B!!!!
S!P3V3!C1M24!1!@baseboard_fab2_lib.baseboard_fab2(sch_1):page186_i10@mstr_discrete.cap(chips)!CAP_0402LF-0.1UF,16V,10%,X7R,AA!!!F3438!A!!!!
S!GND!C1M24!2!@baseboard_fab2_lib.baseboard_fab2(sch_1):page186_i10@mstr_discrete.cap(chips)!CAP_0402LF-0.1UF,16V,10%,X7R,AA!!!F3438!B!!!!
S!P12V_STBY!C1M23!1!@baseboard_fab2_lib.baseboard_fab2(sch_1):page186_i7@mstr_discrete.cap(chips)!CAP_0402LF-0.1UF,16V,10%,X7R,AA!!!F3439!A!!!!
S!GND!C1M23!2!@baseboard_fab2_lib.baseboard_fab2(sch_1):page186_i7@mstr_discrete.cap(chips)!CAP_0402LF-0.1UF,16V,10%,X7R,AA!!!F3439!B!!!!
S!P12V_STBY!C1M22!1!@baseboard_fab2_lib.baseboard_fab2(sch_1):page186_i8@mstr_discrete.cap(chips)!CAP_0402LF-0.1UF,16V,10%,X7R,AA!!!F3440!A!!!!
S!GND!C1M22!2!@baseboard_fab2_lib.baseboard_fab2(sch_1):page186_i8@mstr_discrete.cap(chips)!CAP_0402LF-0.1UF,16V,10%,X7R,AA!!!F3440!B!!!!
S!A_HSC_OV!C1D27!1!@baseboard_fab2_lib.baseboard_fab2(sch_1):page199_i7@mstr_discrete.cap(chips)!CAP_0402LF-0.1UF,16V,10%,X7R,AA!!!F3460!A!!!!
S!AGND_HSC!C1D27!2!@baseboard_fab2_lib.baseboard_fab2(sch_1):page199_i7@mstr_discrete.cap(chips)!CAP_0402LF-0.1UF,16V,10%,X7R,AA!!!F3460!B!!!!
S!VR_FET_SW_P12V_STBY_PVCCIN_CPU1!C1E14!1!@baseboard_fab2_lib.baseboard_fab2(sch_1):page207_i33@mstr_discrete.cap(chips)!CAP_0402LF-0.1UF,16V,10%,X7R,AA!!!F3457!A!!!!
S!GND!C1E14!2!@baseboard_fab2_lib.baseboard_fab2(sch_1):page207_i33@mstr_discrete.cap(chips)!CAP_0402LF-0.1UF,16V,10%,X7R,AA!!!F3457!B!!!!
S!VR_FET_SW_P12V_STBY_PVCCIN_CPU1!C1D34!1!@baseboard_fab2_lib.baseboard_fab2(sch_1):page207_i41@mstr_discrete.cap(chips)!CAP_0402LF-0.1UF,16V,10%,X7R,AA!!!F3458!A!!!!
S!GND!C1D34!2!@baseboard_fab2_lib.baseboard_fab2(sch_1):page207_i41@mstr_discrete.cap(chips)!CAP_0402LF-0.1UF,16V,10%,X7R,AA!!!F3458!B!!!!
S!VR_FET_SW_P12V_STBY_PVCCIN_CPU1!C1D28!1!@baseboard_fab2_lib.baseboard_fab2(sch_1):page208_i44@mstr_discrete.cap(chips)!CAP_0402LF-0.1UF,16V,10%,X7R,AA!!!F3459!A!!!!
S!GND!C1D28!2!@baseboard_fab2_lib.baseboard_fab2(sch_1):page208_i44@mstr_discrete.cap(chips)!CAP_0402LF-0.1UF,16V,10%,X7R,AA!!!F3459!B!!!!
S!VR_FET_SW_P12V_STBY_PVCCIN_CPU1!C1D13!1!@baseboard_fab2_lib.baseboard_fab2(sch_1):page208_i51@mstr_discrete.cap(chips)!CAP_0402LF-0.1UF,16V,10%,X7R,AA!!!F3463!A!!!!
S!GND!C1D13!2!@baseboard_fab2_lib.baseboard_fab2(sch_1):page208_i51@mstr_discrete.cap(chips)!CAP_0402LF-0.1UF,16V,10%,X7R,AA!!!F3463!B!!!!
S!VR_FET_SW_P12V_STBY_PVCCIN_CPU1!C1C17!1!@baseboard_fab2_lib.baseboard_fab2(sch_1):page210_i27@mstr_discrete.cap(chips)!CAP_0402LF-0.1UF,16V,10%,X7R,AA!!!F3467!A!!!!
S!GND!C1C17!2!@baseboard_fab2_lib.baseboard_fab2(sch_1):page210_i27@mstr_discrete.cap(chips)!CAP_0402LF-0.1UF,16V,10%,X7R,AA!!!F3467!B!!!!
S!PVPP_ABC!C6F3!1!@baseboard_fab2_lib.baseboard_fab2(sch_1):page99_i7@mstr_discrete.cap(chips)!CAP_0402LF-0.1UF,16V,10%,X7R,AA!!!F3303!A!!!!
S!GND!C6F3!2!@baseboard_fab2_lib.baseboard_fab2(sch_1):page99_i7@mstr_discrete.cap(chips)!CAP_0402LF-0.1UF,16V,10%,X7R,AA!!!F3303!B!!!!
S!PVPP_DEF!C7E2!1!@baseboard_fab2_lib.baseboard_fab2(sch_1):page99_i32@mstr_discrete.cap(chips)!CAP_0402LF-0.1UF,16V,10%,X7R,AA!!!F3284!A!!!!
S!GND!C7E2!2!@baseboard_fab2_lib.baseboard_fab2(sch_1):page99_i32@mstr_discrete.cap(chips)!CAP_0402LF-0.1UF,16V,10%,X7R,AA!!!F3284!B!!!!
S!PVCCIO_CPU0!C6F2!1!@baseboard_fab2_lib.baseboard_fab2(sch_1):page99_i2@mstr_discrete.cap(chips)!CAP_0402LF-0.1UF,16V,10%,X7R,AA!!!F3304!A!!!!
S!GND!C6F2!2!@baseboard_fab2_lib.baseboard_fab2(sch_1):page99_i2@mstr_discrete.cap(chips)!CAP_0402LF-0.1UF,16V,10%,X7R,AA!!!F3304!B!!!!
S!PVCCIO_CPU0!C7E1!1!@baseboard_fab2_lib.baseboard_fab2(sch_1):page99_i23@mstr_discrete.cap(chips)!CAP_0402LF-0.1UF,16V,10%,X7R,AA!!!F3285!A!!!!
S!GND!C7E1!2!@baseboard_fab2_lib.baseboard_fab2(sch_1):page99_i23@mstr_discrete.cap(chips)!CAP_0402LF-0.1UF,16V,10%,X7R,AA!!!F3285!B!!!!
S!PVCCIO_CPU1!C4G22!1!@baseboard_fab2_lib.baseboard_fab2(sch_1):page99_i27@mstr_discrete.cap(chips)!CAP_0402LF-0.1UF,16V,10%,X7R,AA!!!F3309!A!!!!
S!GND!C4G22!2!@baseboard_fab2_lib.baseboard_fab2(sch_1):page99_i27@mstr_discrete.cap(chips)!CAP_0402LF-0.1UF,16V,10%,X7R,AA!!!F3309!B!!!!
S!FM_P12V_HOTSWAP0_EN!C1D11!1!@baseboard_fab2_lib.baseboard_fab2(sch_1):page199_i53@mstr_discrete.cap(chips)!CAP_0402LF-0.1UF,16V,10%,X7R,AA!!!F3464!A!!!!
S!AGND_HSC!C1D11!2!@baseboard_fab2_lib.baseboard_fab2(sch_1):page199_i53@mstr_discrete.cap(chips)!CAP_0402LF-0.1UF,16V,10%,X7R,AA!!!F3464!B!!!!
S!VR_FET_SW_P12V_STBY_PVCCIN_CPU0!C4C19!1!@baseboard_fab2_lib.baseboard_fab2(sch_1):page204_i35@mstr_discrete.cap(chips)!CAP_0402LF-0.1UF,16V,10%,X7R,AA!!!F3322!A!!!!
S!GND!C4C19!2!@baseboard_fab2_lib.baseboard_fab2(sch_1):page204_i35@mstr_discrete.cap(chips)!CAP_0402LF-0.1UF,16V,10%,X7R,AA!!!F3322!B!!!!
S!P12V_PSU!C9R12!1!@baseboard_fab2_lib.baseboard_fab2(sch_1):page195_i36@mstr_discrete.cap(chips)!CAP_0402LF-0.1UF,16V,10%,X7R,AA!!!F3232!A!!!!
S!GND!C9R12!2!@baseboard_fab2_lib.baseboard_fab2(sch_1):page195_i36@mstr_discrete.cap(chips)!CAP_0402LF-0.1UF,16V,10%,X7R,AA!!!F3232!B!!!!
S!P12V_PSU!C9R6!1!@baseboard_fab2_lib.baseboard_fab2(sch_1):page195_i37@mstr_discrete.cap(chips)!CAP_0402LF-0.1UF,16V,10%,X7R,AA!!!F3233!A!!!!
S!GND!C9R6!2!@baseboard_fab2_lib.baseboard_fab2(sch_1):page195_i37@mstr_discrete.cap(chips)!CAP_0402LF-0.1UF,16V,10%,X7R,AA!!!F3233!B!!!!
S!P12V_PSU!C1E17!1!@baseboard_fab2_lib.baseboard_fab2(sch_1):page195_i38@mstr_discrete.cap(chips)!CAP_0402LF-0.1UF,16V,10%,X7R,AA!!!F3455!A!!!!
S!GND!C1E17!2!@baseboard_fab2_lib.baseboard_fab2(sch_1):page195_i38@mstr_discrete.cap(chips)!CAP_0402LF-0.1UF,16V,10%,X7R,AA!!!F3455!B!!!!
S!P12V_PSU!C1E16!1!@baseboard_fab2_lib.baseboard_fab2(sch_1):page195_i39@mstr_discrete.cap(chips)!CAP_0402LF-0.1UF,16V,10%,X7R,AA!!!F3456!A!!!!
S!GND!C1E16!2!@baseboard_fab2_lib.baseboard_fab2(sch_1):page195_i39@mstr_discrete.cap(chips)!CAP_0402LF-0.1UF,16V,10%,X7R,AA!!!F3456!B!!!!
S!P3V3_STBY!C1U5!1!@baseboard_fab2_lib.baseboard_fab2(sch_1):page149_i17@mstr_discrete.cap(chips)!CAP_0402LF-0.1UF,16V,10%,X7R,AA!!!F3398!A!!!!
S!GND!C1U5!2!@baseboard_fab2_lib.baseboard_fab2(sch_1):page149_i17@mstr_discrete.cap(chips)!CAP_0402LF-0.1UF,16V,10%,X7R,AA!!!F3398!B!!!!
S!P3V3_STBY!C1T38!1!@baseboard_fab2_lib.baseboard_fab2(sch_1):page149_i22@mstr_discrete.cap(chips)!CAP_0402LF-0.1UF,16V,10%,X7R,AA!!!F3410!A!!!!
S!GND!C1T38!2!@baseboard_fab2_lib.baseboard_fab2(sch_1):page149_i22@mstr_discrete.cap(chips)!CAP_0402LF-0.1UF,16V,10%,X7R,AA!!!F3410!B!!!!
S!P0V7_GTL2104_VREF_1!C3P49!1!@baseboard_fab2_lib.baseboard_fab2(sch_1):page92_i37@mstr_discrete.cap(chips)!CAP_0402LF-0.1UF,16V,10%,X7R,AA!!!F3332!A!!!!
S!GND!C3P49!2!@baseboard_fab2_lib.baseboard_fab2(sch_1):page92_i37@mstr_discrete.cap(chips)!CAP_0402LF-0.1UF,16V,10%,X7R,AA!!!F3332!B!!!!
S!P0V7_GTL2104_VREF_0!C7D5!1!@baseboard_fab2_lib.baseboard_fab2(sch_1):page92_i52@mstr_discrete.cap(chips)!CAP_0402LF-0.1UF,16V,10%,X7R,AA!!!F3286!A!!!!
S!GND!C7D5!2!@baseboard_fab2_lib.baseboard_fab2(sch_1):page92_i52@mstr_discrete.cap(chips)!CAP_0402LF-0.1UF,16V,10%,X7R,AA!!!F3286!B!!!!
S!M_BMC_DDR3_MVREF!C1T37!1!@baseboard_fab2_lib.baseboard_fab2(sch_1):page143_i336@mstr_discrete.cap(chips)!CAP_0402LF-0.1UF,16V,10%,X7R,AA!!!F3411!A!!!!
S!GND!C1T37!2!@baseboard_fab2_lib.baseboard_fab2(sch_1):page143_i336@mstr_discrete.cap(chips)!CAP_0402LF-0.1UF,16V,10%,X7R,AA!!!F3411!B!!!!
S!A_P3V_BAT_SCALED!C9G22!1!@baseboard_fab2_lib.baseboard_fab2(sch_1):page169_i108@mstr_discrete.cap(chips)!CAP_0402LF-10.0PF,50V,5%,COG,AA!!!F3212!A!!!!
S!GND!C9G22!2!@baseboard_fab2_lib.baseboard_fab2(sch_1):page169_i108@mstr_discrete.cap(chips)!CAP_0402LF-10.0PF,50V,5%,COG,AA!!!F3212!B!!!!
S!VR_FB_PVPP_KLM!C4B4!1!@baseboard_fab2_lib.baseboard_fab2(sch_1):page234_i212@mstr_discrete.cap(chips)!CAP_0402LF-100.0PF,50V,5%,COG,A!!!F3208!A!!!!
S!VR_COMP_PVPP_KLM_3!C4B4!2!@baseboard_fab2_lib.baseboard_fab2(sch_1):page234_i212@mstr_discrete.cap(chips)!CAP_0402LF-100.0PF,50V,5%,COG,A!!!F3208!B!!!!
S!VR_FB_PVPP_GHJ!C4G6!1!@baseboard_fab2_lib.baseboard_fab2(sch_1):page233_i273@mstr_discrete.cap(chips)!CAP_0402LF-100.0PF,50V,5%,COG,A!!!F3207!A!!!!
S!VR_COMP_PVPP_GHJ_3!C4G6!2!@baseboard_fab2_lib.baseboard_fab2(sch_1):page233_i273@mstr_discrete.cap(chips)!CAP_0402LF-100.0PF,50V,5%,COG,A!!!F3207!B!!!!
S!VR_FB_PVPP_DEF!C7B10!1!@baseboard_fab2_lib.baseboard_fab2(sch_1):page232_i301@mstr_discrete.cap(chips)!CAP_0402LF-100.0PF,50V,5%,COG,A!!!F3206!A!!!!
S!VR_COMP_PVPP_DEF_3!C7B10!2!@baseboard_fab2_lib.baseboard_fab2(sch_1):page232_i301@mstr_discrete.cap(chips)!CAP_0402LF-100.0PF,50V,5%,COG,A!!!F3206!B!!!!
S!VR_FB_PVPP_ABC!C7F9!1!@baseboard_fab2_lib.baseboard_fab2(sch_1):page231_i199@mstr_discrete.cap(chips)!CAP_0402LF-100.0PF,50V,5%,COG,A!!!F3205!A!!!!
S!VR_COMP_PVPP_ABC_3!C7F9!2!@baseboard_fab2_lib.baseboard_fab2(sch_1):page231_i199@mstr_discrete.cap(chips)!CAP_0402LF-100.0PF,50V,5%,COG,A!!!F3205!B!!!!
S!P3V3_STBY_BMC_ADCAV33!C1U17!1!@baseboard_fab2_lib.baseboard_fab2(sch_1):page149_i142@mstr_discrete.cap(chips)!CAP_0402LF-100.0PF,50V,5%,COG,A!!!F3209!A!!!!
S!GND!C1U17!2!@baseboard_fab2_lib.baseboard_fab2(sch_1):page149_i142@mstr_discrete.cap(chips)!CAP_0402LF-100.0PF,50V,5%,COG,A!!!F3209!B!!!!
S!P3V3_STBY!C1U2!1!@baseboard_fab2_lib.baseboard_fab2(sch_1):page148_i26@mstr_discrete.cap(chips)!CAP_0402LF-100.0PF,50V,5%,COG,A!!!F3210!A!!!!
S!GND!C1U2!2!@baseboard_fab2_lib.baseboard_fab2(sch_1):page148_i26@mstr_discrete.cap(chips)!CAP_0402LF-100.0PF,50V,5%,COG,A!!!F3210!B!!!!
S!P3V3_STBY_BMC_HPLLAV33!C1T20!1!@baseboard_fab2_lib.baseboard_fab2(sch_1):page149_i119@mstr_discrete.cap(chips)!CAP_0402LF-100.0PF,50V,5%,COG,A!!!F3211!A!!!!
S!GND!C1T20!2!@baseboard_fab2_lib.baseboard_fab2(sch_1):page149_i119@mstr_discrete.cap(chips)!CAP_0402LF-100.0PF,50V,5%,COG,A!!!F3211!B!!!!
S!P1V26_BMC_STBY_V1PLLAV12!C9F18!1!@baseboard_fab2_lib.baseboard_fab2(sch_1):page149_i104@mstr_discrete.cap(chips)!CAP_0402LF-100.0PF,50V,5%,COG,A!!!F3204!A!!!!
S!GND!C9F18!2!@baseboard_fab2_lib.baseboard_fab2(sch_1):page149_i104@mstr_discrete.cap(chips)!CAP_0402LF-100.0PF,50V,5%,COG,A!!!F3204!B!!!!
S!FM_PVPP_CPU0_EN!C7B9!1!@baseboard_fab2_lib.baseboard_fab2(sch_1):page232_i185@mstr_discrete.cap(chips)!CAP_0402LF-1000PF,50V,10%,EMPTA!!!F3197!A!!!!
S!AGND_PVPP_DEF!C7B9!2!@baseboard_fab2_lib.baseboard_fab2(sch_1):page232_i185@mstr_discrete.cap(chips)!CAP_0402LF-1000PF,50V,10%,EMPTA!!!F3197!B!!!!
S!FM_PVPP_CPU1_EN!C4G7!1!@baseboard_fab2_lib.baseboard_fab2(sch_1):page233_i183@mstr_discrete.cap(chips)!CAP_0402LF-1000PF,50V,10%,EMPTA!!!F3200!A!!!!
S!AGND_PVPP_GHJ!C4G7!2!@baseboard_fab2_lib.baseboard_fab2(sch_1):page233_i183@mstr_discrete.cap(chips)!CAP_0402LF-1000PF,50V,10%,EMPTA!!!F3200!B!!!!
S!FM_PVPP_CPU1_EN!C4B5!1!@baseboard_fab2_lib.baseboard_fab2(sch_1):page234_i129@mstr_discrete.cap(chips)!CAP_0402LF-1000PF,50V,10%,EMPTA!!!F3201!A!!!!
S!AGND_PVPP_KLM!C4B5!2!@baseboard_fab2_lib.baseboard_fab2(sch_1):page234_i129@mstr_discrete.cap(chips)!CAP_0402LF-1000PF,50V,10%,EMPTA!!!F3201!B!!!!
S!FM_PVPP_CPU0_EN!C7F8!1!@baseboard_fab2_lib.baseboard_fab2(sch_1):page231_i140@mstr_discrete.cap(chips)!CAP_0402LF-1000PF,50V,10%,EMPTA!!!F3196!A!!!!
S!AGND_PVPP_ABC!C7F8!2!@baseboard_fab2_lib.baseboard_fab2(sch_1):page231_i140@mstr_discrete.cap(chips)!CAP_0402LF-1000PF,50V,10%,EMPTA!!!F3196!B!!!!
S!PWRGD_P5V_STBY!C8E17!1!@baseboard_fab2_lib.baseboard_fab2(sch_1):page240_i113@mstr_discrete.cap(chips)!CAP_0402LF-1000PF,50V,10%,EMPTA!!!F3193!A!!!!
S!AGND_P3V3_STBY!C8E17!2!@baseboard_fab2_lib.baseboard_fab2(sch_1):page240_i113@mstr_discrete.cap(chips)!CAP_0402LF-1000PF,50V,10%,EMPTA!!!F3193!B!!!!
S!PWRGD_P3V3_STBY!C8A10!1!@baseboard_fab2_lib.baseboard_fab2(sch_1):page237_i55@mstr_discrete.cap(chips)!CAP_0402LF-1000PF,50V,10%,EMPTA!!!F3195!A!!!!
S!GND!C8A10!2!@baseboard_fab2_lib.baseboard_fab2(sch_1):page237_i55@mstr_discrete.cap(chips)!CAP_0402LF-1000PF,50V,10%,EMPTA!!!F3195!B!!!!
S!FM_PVTT_ABC_EN_R!C4G23!1!@baseboard_fab2_lib.baseboard_fab2(sch_1):page221_i39@mstr_discrete.cap(chips)!CAP_0402LF-1000PF,50V,10%,EMPTA!!!F3198!A!!!!
S!GND!C4G23!2!@baseboard_fab2_lib.baseboard_fab2(sch_1):page221_i39@mstr_discrete.cap(chips)!CAP_0402LF-1000PF,50V,10%,EMPTA!!!F3198!B!!!!
S!FM_PVTT_DEF_EN_R!C4A2!1!@baseboard_fab2_lib.baseboard_fab2(sch_1):page222_i40@mstr_discrete.cap(chips)!CAP_0402LF-1000PF,50V,10%,EMPTA!!!F3203!A!!!!
S!GND!C4A2!2!@baseboard_fab2_lib.baseboard_fab2(sch_1):page222_i40@mstr_discrete.cap(chips)!CAP_0402LF-1000PF,50V,10%,EMPTA!!!F3203!B!!!!
S!FM_PVTT_GHJ_EN_R!C4G12!1!@baseboard_fab2_lib.baseboard_fab2(sch_1):page229_i36@mstr_discrete.cap(chips)!CAP_0402LF-1000PF,50V,10%,EMPTA!!!F3199!A!!!!
S!GND!C4G12!2!@baseboard_fab2_lib.baseboard_fab2(sch_1):page229_i36@mstr_discrete.cap(chips)!CAP_0402LF-1000PF,50V,10%,EMPTA!!!F3199!B!!!!
S!FM_PVTT_KLM_EN_R!C4A6!1!@baseboard_fab2_lib.baseboard_fab2(sch_1):page230_i39@mstr_discrete.cap(chips)!CAP_0402LF-1000PF,50V,10%,EMPTA!!!F3202!A!!!!
S!GND!C4A6!2!@baseboard_fab2_lib.baseboard_fab2(sch_1):page230_i39@mstr_discrete.cap(chips)!CAP_0402LF-1000PF,50V,10%,EMPTA!!!F3202!B!!!!
S!PWRGD_P12V_HSC_DLY!C8E13!1!@baseboard_fab2_lib.baseboard_fab2(sch_1):page241_i41@mstr_discrete.cap(chips)!CAP_0402LF-1000PF,50V,10%,EMPTA!!!F3194!A!!!!
S!AGND_P5V_STBY!C8E13!2!@baseboard_fab2_lib.baseboard_fab2(sch_1):page241_i41@mstr_discrete.cap(chips)!CAP_0402LF-1000PF,50V,10%,EMPTA!!!F3194!B!!!!
S!PWRGD_P1V538_BMC_STBY!C9F9!1!@baseboard_fab2_lib.baseboard_fab2(sch_1):page238_i5@mstr_discrete.cap(chips)!CAP_0402LF-1000PF,50V,10%,EMPTA!!!F3191!A!!!!
S!GND!C9F9!2!@baseboard_fab2_lib.baseboard_fab2(sch_1):page238_i5@mstr_discrete.cap(chips)!CAP_0402LF-1000PF,50V,10%,EMPTA!!!F3191!B!!!!
S!PWRGD_P3V3_STBY!C9F6!1!@baseboard_fab2_lib.baseboard_fab2(sch_1):page239_i30@mstr_discrete.cap(chips)!CAP_0402LF-1000PF,50V,10%,EMPTA!!!F3192!A!!!!
S!GND!C9F6!2!@baseboard_fab2_lib.baseboard_fab2(sch_1):page239_i30@mstr_discrete.cap(chips)!CAP_0402LF-1000PF,50V,10%,EMPTA!!!F3192!B!!!!
S!VR_VRRDY_PVCCIN_CPU0!C4D42!1!@baseboard_fab2_lib.baseboard_fab2(sch_1):page201_i125@mstr_discrete.cap(chips)!CAP_0402LF-1000PF,50V,10%,X7R,A!!!F3176!A!!!!
S!GND!C4D42!2!@baseboard_fab2_lib.baseboard_fab2(sch_1):page201_i125@mstr_discrete.cap(chips)!CAP_0402LF-1000PF,50V,10%,X7R,A!!!F3176!B!!!!
S!VR_VRRDY_PVCCIN_CPU1!C1C23!1!@baseboard_fab2_lib.baseboard_fab2(sch_1):page206_i114@mstr_discrete.cap(chips)!CAP_0402LF-1000PF,50V,10%,X7R,A!!!F3187!A!!!!
S!GND!C1C23!2!@baseboard_fab2_lib.baseboard_fab2(sch_1):page206_i114@mstr_discrete.cap(chips)!CAP_0402LF-1000PF,50V,10%,X7R,A!!!F3187!B!!!!
S!PWRGD_PVCCIO_CPU0_R!C3P6!1!@baseboard_fab2_lib.baseboard_fab2(sch_1):page211_i71@mstr_discrete.cap(chips)!CAP_0402LF-1000PF,50V,10%,X7R,A!!!F3183!A!!!!
S!GND!C3P6!2!@baseboard_fab2_lib.baseboard_fab2(sch_1):page211_i71@mstr_discrete.cap(chips)!CAP_0402LF-1000PF,50V,10%,X7R,A!!!F3183!B!!!!
S!PWRGD_PVCCIO_CPU1_R!C4D33!1!@baseboard_fab2_lib.baseboard_fab2(sch_1):page213_i73@mstr_discrete.cap(chips)!CAP_0402LF-1000PF,50V,10%,X7R,A!!!F3178!A!!!!
S!GND!C4D33!2!@baseboard_fab2_lib.baseboard_fab2(sch_1):page213_i73@mstr_discrete.cap(chips)!CAP_0402LF-1000PF,50V,10%,X7R,A!!!F3178!B!!!!
S!PWRGD_PVNN_PCH_R!C8A9!1!@baseboard_fab2_lib.baseboard_fab2(sch_1):page235_i218@mstr_discrete.cap(chips)!CAP_0402LF-1000PF,50V,10%,X7R,A!!!F3164!A!!!!
S!GND!C8A9!2!@baseboard_fab2_lib.baseboard_fab2(sch_1):page235_i218@mstr_discrete.cap(chips)!CAP_0402LF-1000PF,50V,10%,X7R,A!!!F3164!B!!!!
S!PWRGD_PVDDQ_ABC_R!C7F14!1!@baseboard_fab2_lib.baseboard_fab2(sch_1):page215_i305@mstr_discrete.cap(chips)!CAP_0402LF-1000PF,50V,10%,X7R,A!!!F3167!A!!!!
S!GND!C7F14!2!@baseboard_fab2_lib.baseboard_fab2(sch_1):page215_i305@mstr_discrete.cap(chips)!CAP_0402LF-1000PF,50V,10%,X7R,A!!!F3167!B!!!!
S!PWRGD_PVDDQ_DEF_R!C7B3!1!@baseboard_fab2_lib.baseboard_fab2(sch_1):page218_i26@mstr_discrete.cap(chips)!CAP_0402LF-1000PF,50V,10%,X7R,A!!!F3171!A!!!!
S!GND!C7B3!2!@baseboard_fab2_lib.baseboard_fab2(sch_1):page218_i26@mstr_discrete.cap(chips)!CAP_0402LF-1000PF,50V,10%,X7R,A!!!F3171!B!!!!
S!PWRGD_PVDDQ_GHJ_R!C1G21!1!@baseboard_fab2_lib.baseboard_fab2(sch_1):page223_i80@mstr_discrete.cap(chips)!CAP_0402LF-1000PF,50V,10%,X7R,A!!!F3186!A!!!!
S!GND!C1G21!2!@baseboard_fab2_lib.baseboard_fab2(sch_1):page223_i80@mstr_discrete.cap(chips)!CAP_0402LF-1000PF,50V,10%,X7R,A!!!F3186!B!!!!
S!PWRGD_PVDDQ_KLM_R!C1B4!1!@baseboard_fab2_lib.baseboard_fab2(sch_1):page226_i80@mstr_discrete.cap(chips)!CAP_0402LF-1000PF,50V,10%,X7R,A!!!F3190!A!!!!
S!GND!C1B4!2!@baseboard_fab2_lib.baseboard_fab2(sch_1):page226_i80@mstr_discrete.cap(chips)!CAP_0402LF-1000PF,50V,10%,X7R,A!!!F3190!B!!!!
S!PWRGD_PVPP_DEF_R!C7B12!1!@baseboard_fab2_lib.baseboard_fab2(sch_1):page232_i209@mstr_discrete.cap(chips)!CAP_0402LF-1000PF,50V,10%,X7R,A!!!F3170!A!!!!
S!GND!C7B12!2!@baseboard_fab2_lib.baseboard_fab2(sch_1):page232_i209@mstr_discrete.cap(chips)!CAP_0402LF-1000PF,50V,10%,X7R,A!!!F3170!B!!!!
S!PWRGD_PVPP_GHJ_R!C4G9!1!@baseboard_fab2_lib.baseboard_fab2(sch_1):page233_i201@mstr_discrete.cap(chips)!CAP_0402LF-1000PF,50V,10%,X7R,A!!!F3175!A!!!!
S!GND!C4G9!2!@baseboard_fab2_lib.baseboard_fab2(sch_1):page233_i201@mstr_discrete.cap(chips)!CAP_0402LF-1000PF,50V,10%,X7R,A!!!F3175!B!!!!
S!PWRGD_PVPP_KLM_R!C4B8!1!@baseboard_fab2_lib.baseboard_fab2(sch_1):page234_i139@mstr_discrete.cap(chips)!CAP_0402LF-1000PF,50V,10%,X7R,A!!!F3180!A!!!!
S!GND!C4B8!2!@baseboard_fab2_lib.baseboard_fab2(sch_1):page234_i139@mstr_discrete.cap(chips)!CAP_0402LF-1000PF,50V,10%,X7R,A!!!F3180!B!!!!
S!PWRGD_PVPP_ABC_R!C7F11!1!@baseboard_fab2_lib.baseboard_fab2(sch_1):page231_i142@mstr_discrete.cap(chips)!CAP_0402LF-1000PF,50V,10%,X7R,A!!!F3168!A!!!!
S!GND!C7F11!2!@baseboard_fab2_lib.baseboard_fab2(sch_1):page231_i142@mstr_discrete.cap(chips)!CAP_0402LF-1000PF,50V,10%,X7R,A!!!F3168!B!!!!
S!PWRGD_P3V3_STBY_R!C8F2!1!@baseboard_fab2_lib.baseboard_fab2(sch_1):page240_i116@mstr_discrete.cap(chips)!CAP_0402LF-1000PF,50V,10%,X7R,A!!!F3162!A!!!!
S!GND!C8F2!2!@baseboard_fab2_lib.baseboard_fab2(sch_1):page240_i116@mstr_discrete.cap(chips)!CAP_0402LF-1000PF,50V,10%,X7R,A!!!F3162!B!!!!
S!PWRGD_PVTT_ABC_CPU0_R!C4G14!1!@baseboard_fab2_lib.baseboard_fab2(sch_1):page221_i15@mstr_discrete.cap(chips)!CAP_0402LF-1000PF,50V,10%,X7R,A!!!F3173!A!!!!
S!GND!C4G14!2!@baseboard_fab2_lib.baseboard_fab2(sch_1):page221_i15@mstr_discrete.cap(chips)!CAP_0402LF-1000PF,50V,10%,X7R,A!!!F3173!B!!!!
S!PWRGD_PVTT_DEF_CPU0_R!C4A12!1!@baseboard_fab2_lib.baseboard_fab2(sch_1):page222_i12@mstr_discrete.cap(chips)!CAP_0402LF-1000PF,50V,10%,X7R,A!!!F3181!A!!!!
S!GND!C4A12!2!@baseboard_fab2_lib.baseboard_fab2(sch_1):page222_i12@mstr_discrete.cap(chips)!CAP_0402LF-1000PF,50V,10%,X7R,A!!!F3181!B!!!!
S!PWRGD_PVTT_GHJ_CPU1_R!C4G13!1!@baseboard_fab2_lib.baseboard_fab2(sch_1):page229_i15@mstr_discrete.cap(chips)!CAP_0402LF-1000PF,50V,10%,X7R,A!!!F3174!A!!!!
S!GND!C4G13!2!@baseboard_fab2_lib.baseboard_fab2(sch_1):page229_i15@mstr_discrete.cap(chips)!CAP_0402LF-1000PF,50V,10%,X7R,A!!!F3174!B!!!!
S!PWRGD_PVTT_KLM_CPU1_R!C4A3!1!@baseboard_fab2_lib.baseboard_fab2(sch_1):page230_i16@mstr_discrete.cap(chips)!CAP_0402LF-1000PF,50V,10%,X7R,A!!!F3182!A!!!!
S!GND!C4A3!2!@baseboard_fab2_lib.baseboard_fab2(sch_1):page230_i16@mstr_discrete.cap(chips)!CAP_0402LF-1000PF,50V,10%,X7R,A!!!F3182!B!!!!
S!PWRGD_P1V8_PCH_STBY_R!C8A11!1!@baseboard_fab2_lib.baseboard_fab2(sch_1):page237_i5@mstr_discrete.cap(chips)!CAP_0402LF-1000PF,50V,10%,X7R,A!!!F3163!A!!!!
S!GND!C8A11!2!@baseboard_fab2_lib.baseboard_fab2(sch_1):page237_i5@mstr_discrete.cap(chips)!CAP_0402LF-1000PF,50V,10%,X7R,A!!!F3163!B!!!!
S!VR_PVNN_PCH_VINSEN!C8A3!1!@baseboard_fab2_lib.baseboard_fab2(sch_1):page235_i167@mstr_discrete.cap(chips)!CAP_0402LF-1000PF,50V,10%,X7R,A!!!F3165!A!!!!
S!GND!C8A3!2!@baseboard_fab2_lib.baseboard_fab2(sch_1):page235_i167@mstr_discrete.cap(chips)!CAP_0402LF-1000PF,50V,10%,X7R,A!!!F3165!B!!!!
S!VR_PVCCIO_CPU0_VINSEN!C3P2!1!@baseboard_fab2_lib.baseboard_fab2(sch_1):page211_i33@mstr_discrete.cap(chips)!CAP_0402LF-1000PF,50V,10%,X7R,A!!!F3184!A!!!!
S!GND!C3P2!2!@baseboard_fab2_lib.baseboard_fab2(sch_1):page211_i33@mstr_discrete.cap(chips)!CAP_0402LF-1000PF,50V,10%,X7R,A!!!F3184!B!!!!
S!VR_PVCCIO_CPU1_VINSEN!C4D40!1!@baseboard_fab2_lib.baseboard_fab2(sch_1):page213_i33@mstr_discrete.cap(chips)!CAP_0402LF-1000PF,50V,10%,X7R,A!!!F3177!A!!!!
S!GND!C4D40!2!@baseboard_fab2_lib.baseboard_fab2(sch_1):page213_i33@mstr_discrete.cap(chips)!CAP_0402LF-1000PF,50V,10%,X7R,A!!!F3177!B!!!!
S!VR_PVDDQ_DEF_VINSEN!C7A35!1!@baseboard_fab2_lib.baseboard_fab2(sch_1):page218_i55@mstr_discrete.cap(chips)!CAP_0402LF-1000PF,50V,10%,X7R,A!!!F3172!A!!!!
S!GND!C7A35!2!@baseboard_fab2_lib.baseboard_fab2(sch_1):page218_i55@mstr_discrete.cap(chips)!CAP_0402LF-1000PF,50V,10%,X7R,A!!!F3172!B!!!!
S!VR_PVDDQ_GHJ_VINSEN!C1G26!1!@baseboard_fab2_lib.baseboard_fab2(sch_1):page223_i59@mstr_discrete.cap(chips)!CAP_0402LF-1000PF,50V,10%,X7R,A!!!F3185!A!!!!
S!GND!C1G26!2!@baseboard_fab2_lib.baseboard_fab2(sch_1):page223_i59@mstr_discrete.cap(chips)!CAP_0402LF-1000PF,50V,10%,X7R,A!!!F3185!B!!!!
S!VR_PVDDQ_KLM_VINSEN!C1B8!1!@baseboard_fab2_lib.baseboard_fab2(sch_1):page226_i59@mstr_discrete.cap(chips)!CAP_0402LF-1000PF,50V,10%,X7R,A!!!F3189!A!!!!
S!GND!C1B8!2!@baseboard_fab2_lib.baseboard_fab2(sch_1):page226_i59@mstr_discrete.cap(chips)!CAP_0402LF-1000PF,50V,10%,X7R,A!!!F3189!B!!!!
S!PWRGD_P5V_STBY_R!C7E10!1!@baseboard_fab2_lib.baseboard_fab2(sch_1):page241_i14@mstr_discrete.cap(chips)!CAP_0402LF-1000PF,50V,10%,X7R,A!!!F3169!A!!!!
S!GND!C7E10!2!@baseboard_fab2_lib.baseboard_fab2(sch_1):page241_i14@mstr_discrete.cap(chips)!CAP_0402LF-1000PF,50V,10%,X7R,A!!!F3169!B!!!!
S!PWRGD_P1V26_BMC_STBY_R!C9F8!1!@baseboard_fab2_lib.baseboard_fab2(sch_1):page238_i19@mstr_discrete.cap(chips)!CAP_0402LF-1000PF,50V,10%,X7R,A!!!F3161!A!!!!
S!GND!C9F8!2!@baseboard_fab2_lib.baseboard_fab2(sch_1):page238_i19@mstr_discrete.cap(chips)!CAP_0402LF-1000PF,50V,10%,X7R,A!!!F3161!B!!!!
S!PWRGD_P1V538_BMC_STBY_R!C9F10!1!@baseboard_fab2_lib.baseboard_fab2(sch_1):page239_i4@mstr_discrete.cap(chips)!CAP_0402LF-1000PF,50V,10%,X7R,A!!!F3160!A!!!!
S!GND!C9F10!2!@baseboard_fab2_lib.baseboard_fab2(sch_1):page239_i4@mstr_discrete.cap(chips)!CAP_0402LF-1000PF,50V,10%,X7R,A!!!F3160!B!!!!
S!VR_PVDDQ_ABC_VINSEN!C7G1!1!@baseboard_fab2_lib.baseboard_fab2(sch_1):page215_i339@mstr_discrete.cap(chips)!CAP_0402LF-1000PF,50V,10%,X7R,A!!!F3166!A!!!!
S!GND!C7G1!2!@baseboard_fab2_lib.baseboard_fab2(sch_1):page215_i339@mstr_discrete.cap(chips)!CAP_0402LF-1000PF,50V,10%,X7R,A!!!F3166!B!!!!
S!VR_PVCCIN_CPU0_AVINSEN!C4D20!1!@baseboard_fab2_lib.baseboard_fab2(sch_1):page201_i60@mstr_discrete.cap(chips)!CAP_0402LF-1000PF,50V,10%,X7R,A!!!F3179!A!!!!
S!GND!C4D20!2!@baseboard_fab2_lib.baseboard_fab2(sch_1):page201_i60@mstr_discrete.cap(chips)!CAP_0402LF-1000PF,50V,10%,X7R,A!!!F3179!B!!!!
S!VR_PVCCIN_CPU1_AVINSEN!C1C8!1!@baseboard_fab2_lib.baseboard_fab2(sch_1):page206_i73@mstr_discrete.cap(chips)!CAP_0402LF-1000PF,50V,10%,X7R,A!!!F3188!A!!!!
S!GND!C1C8!2!@baseboard_fab2_lib.baseboard_fab2(sch_1):page206_i73@mstr_discrete.cap(chips)!CAP_0402LF-1000PF,50V,10%,X7R,A!!!F3188!B!!!!
S!XTAL_33K_RTC1!C7C13!1!@baseboard_fab2_lib.baseboard_fab2(sch_1):page114_i56@mstr_discrete.cap(chips)!CAP_0402LF-18PF,50V,5%,C0G,A36A!!!F3155!A!!!!
S!GND!C7C13!2!@baseboard_fab2_lib.baseboard_fab2(sch_1):page114_i56@mstr_discrete.cap(chips)!CAP_0402LF-18PF,50V,5%,C0G,A36A!!!F3155!B!!!!
S!XTAL_33K_RTC2!C7C15!1!@baseboard_fab2_lib.baseboard_fab2(sch_1):page114_i46@mstr_discrete.cap(chips)!CAP_0402LF-18PF,50V,5%,C0G,A36A!!!F3154!A!!!!
S!GND!C7C15!2!@baseboard_fab2_lib.baseboard_fab2(sch_1):page114_i46@mstr_discrete.cap(chips)!CAP_0402LF-18PF,50V,5%,C0G,A36A!!!F3154!B!!!!
S!XTAL_25MHZ_IN!C9E9!1!@baseboard_fab2_lib.baseboard_fab2(sch_1):page139_i112@mstr_discrete.cap(chips)!CAP_0402LF-22.0PF,50V,5%,COG,AA!!!F3152!A!!!!
S!GND!C9E9!2!@baseboard_fab2_lib.baseboard_fab2(sch_1):page139_i112@mstr_discrete.cap(chips)!CAP_0402LF-22.0PF,50V,5%,COG,AA!!!F3152!B!!!!
S!XTAL_25MHZ_OUT_R!C9E8!1!@baseboard_fab2_lib.baseboard_fab2(sch_1):page139_i111@mstr_discrete.cap(chips)!CAP_0402LF-22.0PF,50V,5%,COG,AA!!!F3153!A!!!!
S!GND!C9E8!2!@baseboard_fab2_lib.baseboard_fab2(sch_1):page139_i111@mstr_discrete.cap(chips)!CAP_0402LF-22.0PF,50V,5%,COG,AA!!!F3153!B!!!!
S!VR_COMP_RC_PVPP_DEF!C7B14!1!@baseboard_fab2_lib.baseboard_fab2(sch_1):page232_i306@mstr_discrete.cap(chips)!CAP_0402LF-2200PF,50V,10%,X7R,A!!!F3146!A!!!!
S!VR_COMP_PVPP_DEF_3!C7B14!2!@baseboard_fab2_lib.baseboard_fab2(sch_1):page232_i306@mstr_discrete.cap(chips)!CAP_0402LF-2200PF,50V,10%,X7R,A!!!F3146!B!!!!
S!VR_COMP_PVPP_KLM!C4B7!1!@baseboard_fab2_lib.baseboard_fab2(sch_1):page234_i218@mstr_discrete.cap(chips)!CAP_0402LF-2200PF,50V,10%,X7R,A!!!F3151!A!!!!
S!VR_FB_PVPP_KLM!C4B7!2!@baseboard_fab2_lib.baseboard_fab2(sch_1):page234_i218@mstr_discrete.cap(chips)!CAP_0402LF-2200PF,50V,10%,X7R,A!!!F3151!B!!!!
S!VR_COMP_RC_PVPP_KLM!C4B9!1!@baseboard_fab2_lib.baseboard_fab2(sch_1):page234_i211@mstr_discrete.cap(chips)!CAP_0402LF-2200PF,50V,10%,X7R,A!!!F3150!A!!!!
S!VR_COMP_PVPP_KLM_3!C4B9!2!@baseboard_fab2_lib.baseboard_fab2(sch_1):page234_i211@mstr_discrete.cap(chips)!CAP_0402LF-2200PF,50V,10%,X7R,A!!!F3150!B!!!!
S!VR_COMP_RC_PVPP_GHJ!C4G10!1!@baseboard_fab2_lib.baseboard_fab2(sch_1):page233_i274@mstr_discrete.cap(chips)!CAP_0402LF-2200PF,50V,10%,X7R,A!!!F3149!A!!!!
S!VR_COMP_PVPP_GHJ_3!C4G10!2!@baseboard_fab2_lib.baseboard_fab2(sch_1):page233_i274@mstr_discrete.cap(chips)!CAP_0402LF-2200PF,50V,10%,X7R,A!!!F3149!B!!!!
S!VR_COMP_PVPP_GHJ!C4G11!1!@baseboard_fab2_lib.baseboard_fab2(sch_1):page233_i267@mstr_discrete.cap(chips)!CAP_0402LF-2200PF,50V,10%,X7R,A!!!F3148!A!!!!
S!VR_FB_PVPP_GHJ!C4G11!2!@baseboard_fab2_lib.baseboard_fab2(sch_1):page233_i267@mstr_discrete.cap(chips)!CAP_0402LF-2200PF,50V,10%,X7R,A!!!F3148!B!!!!
S!VR_COMP_PVPP_DEF!C7B13!1!@baseboard_fab2_lib.baseboard_fab2(sch_1):page232_i302@mstr_discrete.cap(chips)!CAP_0402LF-2200PF,50V,10%,X7R,A!!!F3147!A!!!!
S!VR_FB_PVPP_DEF!C7B13!2!@baseboard_fab2_lib.baseboard_fab2(sch_1):page232_i302@mstr_discrete.cap(chips)!CAP_0402LF-2200PF,50V,10%,X7R,A!!!F3147!B!!!!
S!VR_COMP_RC_PVPP_ABC!C7F12!1!@baseboard_fab2_lib.baseboard_fab2(sch_1):page231_i200@mstr_discrete.cap(chips)!CAP_0402LF-2200PF,50V,10%,X7R,A!!!F3145!A!!!!
S!VR_COMP_PVPP_ABC_3!C7F12!2!@baseboard_fab2_lib.baseboard_fab2(sch_1):page231_i200@mstr_discrete.cap(chips)!CAP_0402LF-2200PF,50V,10%,X7R,A!!!F3145!B!!!!
S!VR_COMP_PVPP_ABC!C7F13!1!@baseboard_fab2_lib.baseboard_fab2(sch_1):page231_i219@mstr_discrete.cap(chips)!CAP_0402LF-2200PF,50V,10%,X7R,A!!!F3144!A!!!!
S!VR_FB_PVPP_ABC!C7F13!2!@baseboard_fab2_lib.baseboard_fab2(sch_1):page231_i219@mstr_discrete.cap(chips)!CAP_0402LF-2200PF,50V,10%,X7R,A!!!F3144!B!!!!
S!VR_P5V_STBY_RC_COMP!C8F1!1!@baseboard_fab2_lib.baseboard_fab2(sch_1):page241_i57@mstr_discrete.cap(chips)!CAP_0402LF-2200PF,50V,10%,X7R,A!!!F3143!A!!!!
S!AGND_P5V_STBY!C8F1!2!@baseboard_fab2_lib.baseboard_fab2(sch_1):page241_i57@mstr_discrete.cap(chips)!CAP_0402LF-2200PF,50V,10%,X7R,A!!!F3143!B!!!!
S!VR_P1V05_PCH_STBY_AVSP!C2L2!1!@baseboard_fab2_lib.baseboard_fab2(sch_1):page235_i153@mstr_discrete.cap(chips)!CAP_0402LF-220PF,50V,10%,X7R,AA!!!F3134!A!!!!
S!VSENSE_P1V05_PCH_STBY_AVSN!C2L2!2!@baseboard_fab2_lib.baseboard_fab2(sch_1):page235_i153@mstr_discrete.cap(chips)!CAP_0402LF-220PF,50V,10%,X7R,AA!!!F3134!B!!!!
S!VR_PVNN_PCH_AVSP!C8A2!1!@baseboard_fab2_lib.baseboard_fab2(sch_1):page235_i209@mstr_discrete.cap(chips)!CAP_0402LF-220PF,50V,10%,X7R,AA!!!F3123!A!!!!
S!VSENSE_PVNN_PCH_STBY_AVSN!C8A2!2!@baseboard_fab2_lib.baseboard_fab2(sch_1):page235_i209@mstr_discrete.cap(chips)!CAP_0402LF-220PF,50V,10%,X7R,AA!!!F3123!B!!!!
S!VR_PVCCIO_CPU0_AVSP!C3N39!1!@baseboard_fab2_lib.baseboard_fab2(sch_1):page211_i83@mstr_discrete.cap(chips)!CAP_0402LF-220PF,50V,10%,X7R,AA!!!F3133!A!!!!
S!VSENSE_PVCCIO_CPU0_AVSN!C3N39!2!@baseboard_fab2_lib.baseboard_fab2(sch_1):page211_i83@mstr_discrete.cap(chips)!CAP_0402LF-220PF,50V,10%,X7R,AA!!!F3133!B!!!!
S!VR_PVCCIO_CPU1_AVSP!C4D44!1!@baseboard_fab2_lib.baseboard_fab2(sch_1):page213_i83@mstr_discrete.cap(chips)!CAP_0402LF-220PF,50V,10%,X7R,AA!!!F3129!A!!!!
S!VSENSE_PVCCIO_CPU1_AVSN!C4D44!2!@baseboard_fab2_lib.baseboard_fab2(sch_1):page213_i83@mstr_discrete.cap(chips)!CAP_0402LF-220PF,50V,10%,X7R,AA!!!F3129!B!!!!
S!A_TSENSE_PVDDQ_DEF!C7A29!1!@baseboard_fab2_lib.baseboard_fab2(sch_1):page218_i39@mstr_discrete.cap(chips)!CAP_0402LF-220PF,50V,10%,X7R,AA!!!F3126!A!!!!
S!GND!C7A29!2!@baseboard_fab2_lib.baseboard_fab2(sch_1):page218_i39@mstr_discrete.cap(chips)!CAP_0402LF-220PF,50V,10%,X7R,AA!!!F3126!B!!!!
S!VR_PVDDQ_DEF_AVSP!C7A28!1!@baseboard_fab2_lib.baseboard_fab2(sch_1):page218_i61@mstr_discrete.cap(chips)!CAP_0402LF-220PF,50V,10%,X7R,AA!!!F3127!A!!!!
S!VSENSE_PVDDQ_DEF_N!C7A28!2!@baseboard_fab2_lib.baseboard_fab2(sch_1):page218_i61@mstr_discrete.cap(chips)!CAP_0402LF-220PF,50V,10%,X7R,AA!!!F3127!B!!!!
S!A_TSENSE_PVDDQ_GHJ!C1G24!1!@baseboard_fab2_lib.baseboard_fab2(sch_1):page223_i36@mstr_discrete.cap(chips)!CAP_0402LF-220PF,50V,10%,X7R,AA!!!F3135!A!!!!
S!GND!C1G24!2!@baseboard_fab2_lib.baseboard_fab2(sch_1):page223_i36@mstr_discrete.cap(chips)!CAP_0402LF-220PF,50V,10%,X7R,AA!!!F3135!B!!!!
S!VR_PVDDQ_GHJ_AVSP!C1G16!1!@baseboard_fab2_lib.baseboard_fab2(sch_1):page223_i39@mstr_discrete.cap(chips)!CAP_0402LF-220PF,50V,10%,X7R,AA!!!F3136!A!!!!
S!VSENSE_PVDDQ_GHJ_N!C1G16!2!@baseboard_fab2_lib.baseboard_fab2(sch_1):page223_i39@mstr_discrete.cap(chips)!CAP_0402LF-220PF,50V,10%,X7R,AA!!!F3136!B!!!!
S!A_TSENSE_PVDDQ_KLM!C1B11!1!@baseboard_fab2_lib.baseboard_fab2(sch_1):page226_i36@mstr_discrete.cap(chips)!CAP_0402LF-220PF,50V,10%,X7R,AA!!!F3142!A!!!!
S!GND!C1B11!2!@baseboard_fab2_lib.baseboard_fab2(sch_1):page226_i36@mstr_discrete.cap(chips)!CAP_0402LF-220PF,50V,10%,X7R,AA!!!F3142!B!!!!
S!VR_PVDDQ_KLM_AVSP!C1B12!1!@baseboard_fab2_lib.baseboard_fab2(sch_1):page226_i39@mstr_discrete.cap(chips)!CAP_0402LF-220PF,50V,10%,X7R,AA!!!F3141!A!!!!
S!VSENSE_PVDDQ_KLM_N!C1B12!2!@baseboard_fab2_lib.baseboard_fab2(sch_1):page226_i39@mstr_discrete.cap(chips)!CAP_0402LF-220PF,50V,10%,X7R,AA!!!F3141!B!!!!
S!VR_PVDDQ_ABC_AVSP!C7G4!1!@baseboard_fab2_lib.baseboard_fab2(sch_1):page215_i342@mstr_discrete.cap(chips)!CAP_0402LF-220PF,50V,10%,X7R,AA!!!F3124!A!!!!
S!VSENSE_PVDDQ_ABC_N!C7G4!2!@baseboard_fab2_lib.baseboard_fab2(sch_1):page215_i342@mstr_discrete.cap(chips)!CAP_0402LF-220PF,50V,10%,X7R,AA!!!F3124!B!!!!
S!A_TSENSE_PVDDQ_ABC!C7G3!1!@baseboard_fab2_lib.baseboard_fab2(sch_1):page215_i320@mstr_discrete.cap(chips)!CAP_0402LF-220PF,50V,10%,X7R,AA!!!F3125!A!!!!
S!GND!C7G3!2!@baseboard_fab2_lib.baseboard_fab2(sch_1):page215_i320@mstr_discrete.cap(chips)!CAP_0402LF-220PF,50V,10%,X7R,AA!!!F3125!B!!!!
S!VSENSE_PVCCIN_CPU0_AVSP!C4D45!1!@baseboard_fab2_lib.baseboard_fab2(sch_1):page201_i70@mstr_discrete.cap(chips)!CAP_0402LF-220PF,50V,10%,X7R,AA!!!F3128!A!!!!
S!VSENSE_PVCCIN_CPU0_N!C4D45!2!@baseboard_fab2_lib.baseboard_fab2(sch_1):page201_i70@mstr_discrete.cap(chips)!CAP_0402LF-220PF,50V,10%,X7R,AA!!!F3128!B!!!!
S!A_TSENSE_PVSA_CPU0!C4D18!1!@baseboard_fab2_lib.baseboard_fab2(sch_1):page201_i68@mstr_discrete.cap(chips)!CAP_0402LF-220PF,50V,10%,X7R,AA!!!F3131!A!!!!
S!GND!C4D18!2!@baseboard_fab2_lib.baseboard_fab2(sch_1):page201_i68@mstr_discrete.cap(chips)!CAP_0402LF-220PF,50V,10%,X7R,AA!!!F3131!B!!!!
S!A_TSENSE_PVCCIN_CPU0!C4D17!1!@baseboard_fab2_lib.baseboard_fab2(sch_1):page201_i66@mstr_discrete.cap(chips)!CAP_0402LF-220PF,50V,10%,X7R,AA!!!F3132!A!!!!
S!GND!C4D17!2!@baseboard_fab2_lib.baseboard_fab2(sch_1):page201_i66@mstr_discrete.cap(chips)!CAP_0402LF-220PF,50V,10%,X7R,AA!!!F3132!B!!!!
S!VSENSE_PVSA_CPU0_BVSP!C4D29!1!@baseboard_fab2_lib.baseboard_fab2(sch_1):page201_i64@mstr_discrete.cap(chips)!CAP_0402LF-220PF,50V,10%,X7R,AA!!!F3130!A!!!!
S!VSENSE_PVSA_CPU0_N!C4D29!2!@baseboard_fab2_lib.baseboard_fab2(sch_1):page201_i64@mstr_discrete.cap(chips)!CAP_0402LF-220PF,50V,10%,X7R,AA!!!F3130!B!!!!
S!VSENSE_PVCCIN_CPU1_AVSP!C1D1!1!@baseboard_fab2_lib.baseboard_fab2(sch_1):page206_i78@mstr_discrete.cap(chips)!CAP_0402LF-220PF,50V,10%,X7R,AA!!!F3137!A!!!!
S!VSENSE_PVCCIN_CPU1_N!C1D1!2!@baseboard_fab2_lib.baseboard_fab2(sch_1):page206_i78@mstr_discrete.cap(chips)!CAP_0402LF-220PF,50V,10%,X7R,AA!!!F3137!B!!!!
S!A_TSENSE_PVSA_CPU1!C1C11!1!@baseboard_fab2_lib.baseboard_fab2(sch_1):page206_i71@mstr_discrete.cap(chips)!CAP_0402LF-220PF,50V,10%,X7R,AA!!!F3139!A!!!!
S!GND!C1C11!2!@baseboard_fab2_lib.baseboard_fab2(sch_1):page206_i71@mstr_discrete.cap(chips)!CAP_0402LF-220PF,50V,10%,X7R,AA!!!F3139!B!!!!
S!A_TSENSE_PVCCIN_CPU1!C1C10!1!@baseboard_fab2_lib.baseboard_fab2(sch_1):page206_i69@mstr_discrete.cap(chips)!CAP_0402LF-220PF,50V,10%,X7R,AA!!!F3140!A!!!!
S!GND!C1C10!2!@baseboard_fab2_lib.baseboard_fab2(sch_1):page206_i69@mstr_discrete.cap(chips)!CAP_0402LF-220PF,50V,10%,X7R,AA!!!F3140!B!!!!
S!VSENSE_PVSA_CPU1_BVSP!C1C16!1!@baseboard_fab2_lib.baseboard_fab2(sch_1):page206_i68@mstr_discrete.cap(chips)!CAP_0402LF-220PF,50V,10%,X7R,AA!!!F3138!A!!!!
S!VSENSE_PVSA_CPU1_N!C1C16!2!@baseboard_fab2_lib.baseboard_fab2(sch_1):page206_i68@mstr_discrete.cap(chips)!CAP_0402LF-220PF,50V,10%,X7R,AA!!!F3138!B!!!!
S!XTAL_CK_MNG_OUT!C8F19!1!@baseboard_fab2_lib.baseboard_fab2(sch_1):page101_i53@mstr_discrete.cap(chips)!CAP_0402LF-27.0PF,50V,5%,COG,AA!!!F3121!A!!!!
S!GND!C8F19!2!@baseboard_fab2_lib.baseboard_fab2(sch_1):page101_i53@mstr_discrete.cap(chips)!CAP_0402LF-27.0PF,50V,5%,COG,AA!!!F3121!B!!!!
S!XTAL_CK_MNG_IN!C8F18!1!@baseboard_fab2_lib.baseboard_fab2(sch_1):page101_i49@mstr_discrete.cap(chips)!CAP_0402LF-27.0PF,50V,5%,COG,AA!!!F3122!A!!!!
S!GND!C8F18!2!@baseboard_fab2_lib.baseboard_fab2(sch_1):page101_i49@mstr_discrete.cap(chips)!CAP_0402LF-27.0PF,50V,5%,COG,AA!!!F3122!B!!!!
S!VR_P5V_STBY_COMP!C8E16!1!@baseboard_fab2_lib.baseboard_fab2(sch_1):page241_i53@mstr_discrete.cap(chips)!CAP_0402LF-270PF,50V,10%,X7R,AA!!!F3120!A!!!!
S!AGND_P5V_STBY!C8E16!2!@baseboard_fab2_lib.baseboard_fab2(sch_1):page241_i53@mstr_discrete.cap(chips)!CAP_0402LF-270PF,50V,10%,X7R,AA!!!F3120!B!!!!
S!VR_PVPP_DEF_PHASE!C7A34!1!@baseboard_fab2_lib.baseboard_fab2(sch_1):page232_i220@mstr_discrete.cap(chips)!CAP_0402LF-3300PF,50V,10%,EMPTA!!!F3115!A!!!!
S!VR_PVPP_DEF_SNUB!C7A34!2!@baseboard_fab2_lib.baseboard_fab2(sch_1):page232_i220@mstr_discrete.cap(chips)!CAP_0402LF-3300PF,50V,10%,EMPTA!!!F3115!B!!!!
S!VR_PVPP_GHJ_PHASE!C4F12!1!@baseboard_fab2_lib.baseboard_fab2(sch_1):page233_i209@mstr_discrete.cap(chips)!CAP_0402LF-3300PF,50V,10%,EMPTA!!!F3116!A!!!!
S!VR_PVPP_GHJ_SNUB!C4F12!2!@baseboard_fab2_lib.baseboard_fab2(sch_1):page233_i209@mstr_discrete.cap(chips)!CAP_0402LF-3300PF,50V,10%,EMPTA!!!F3116!B!!!!
S!VR_PVPP_KLM_PHASE!C4A16!1!@baseboard_fab2_lib.baseboard_fab2(sch_1):page234_i163@mstr_discrete.cap(chips)!CAP_0402LF-3300PF,50V,10%,EMPTA!!!F3117!A!!!!
S!VR_PVPP_KLM_SNUB!C4A16!2!@baseboard_fab2_lib.baseboard_fab2(sch_1):page234_i163@mstr_discrete.cap(chips)!CAP_0402LF-3300PF,50V,10%,EMPTA!!!F3117!B!!!!
S!VR_PVPP_ABC_PHASE!C7F3!1!@baseboard_fab2_lib.baseboard_fab2(sch_1):page231_i175@mstr_discrete.cap(chips)!CAP_0402LF-3300PF,50V,10%,EMPTA!!!F3114!A!!!!
S!VR_PVPP_ABC_SNUB!C7F3!2!@baseboard_fab2_lib.baseboard_fab2(sch_1):page231_i175@mstr_discrete.cap(chips)!CAP_0402LF-3300PF,50V,10%,EMPTA!!!F3114!B!!!!
S!VR_P3V3_STBY_PHASE!C8F3!1!@baseboard_fab2_lib.baseboard_fab2(sch_1):page240_i163@mstr_discrete.cap(chips)!CAP_0402LF-3300PF,50V,10%,EMPTA!!!F3113!A!!!!
S!VR_P3V3_STBY_SNUB!C8F3!2!@baseboard_fab2_lib.baseboard_fab2(sch_1):page240_i163@mstr_discrete.cap(chips)!CAP_0402LF-3300PF,50V,10%,EMPTA!!!F3113!B!!!!
S!A_PVNN_STBY_PCH_SENSOR!C9G18!1!@baseboard_fab2_lib.baseboard_fab2(sch_1):page169_i153@mstr_discrete.cap(chips)!CAP_0402LF-47.0PF,50V,5%,COG,AA!!!F3108!A!!!!
S!GND!C9G18!2!@baseboard_fab2_lib.baseboard_fab2(sch_1):page169_i153@mstr_discrete.cap(chips)!CAP_0402LF-47.0PF,50V,5%,COG,AA!!!F3108!B!!!!
S!A_P5V_SCALED!C9G15!1!@baseboard_fab2_lib.baseboard_fab2(sch_1):page169_i139@mstr_discrete.cap(chips)!CAP_0402LF-47.0PF,50V,5%,COG,AA!!!F3110!A!!!!
S!GND!C9G15!2!@baseboard_fab2_lib.baseboard_fab2(sch_1):page169_i139@mstr_discrete.cap(chips)!CAP_0402LF-47.0PF,50V,5%,COG,AA!!!F3110!B!!!!
S!A_P3V3_SCALED!C9G14!1!@baseboard_fab2_lib.baseboard_fab2(sch_1):page169_i146@mstr_discrete.cap(chips)!CAP_0402LF-47.0PF,50V,5%,COG,AA!!!F3111!A!!!!
S!GND!C9G14!2!@baseboard_fab2_lib.baseboard_fab2(sch_1):page169_i146@mstr_discrete.cap(chips)!CAP_0402LF-47.0PF,50V,5%,COG,AA!!!F3111!B!!!!
S!A_P1V05_STBY_PCH_SENSOR!C1U21!1!@baseboard_fab2_lib.baseboard_fab2(sch_1):page169_i56@mstr_discrete.cap(chips)!CAP_0402LF-47.0PF,50V,5%,COG,AA!!!F3112!A!!!!
S!GND!C1U21!2!@baseboard_fab2_lib.baseboard_fab2(sch_1):page169_i56@mstr_discrete.cap(chips)!CAP_0402LF-47.0PF,50V,5%,COG,AA!!!F3112!B!!!!
S!A_P5V_STBY_SCALED!C9G21!1!@baseboard_fab2_lib.baseboard_fab2(sch_1):page169_i68@mstr_discrete.cap(chips)!CAP_0402LF-47.0PF,50V,5%,COG,AA!!!F3106!A!!!!
S!GND!C9G21!2!@baseboard_fab2_lib.baseboard_fab2(sch_1):page169_i68@mstr_discrete.cap(chips)!CAP_0402LF-47.0PF,50V,5%,COG,AA!!!F3106!B!!!!
S!A_P12V_STBY_SCALED!C9G17!1!@baseboard_fab2_lib.baseboard_fab2(sch_1):page169_i80@mstr_discrete.cap(chips)!CAP_0402LF-47.0PF,50V,5%,COG,AA!!!F3109!A!!!!
S!GND!C9G17!2!@baseboard_fab2_lib.baseboard_fab2(sch_1):page169_i80@mstr_discrete.cap(chips)!CAP_0402LF-47.0PF,50V,5%,COG,AA!!!F3109!B!!!!
S!A_P3V3_STBY_SCALED!C9G20!1!@baseboard_fab2_lib.baseboard_fab2(sch_1):page169_i86@mstr_discrete.cap(chips)!CAP_0402LF-47.0PF,50V,5%,COG,AA!!!F3107!A!!!!
S!GND!C9G20!2!@baseboard_fab2_lib.baseboard_fab2(sch_1):page169_i86@mstr_discrete.cap(chips)!CAP_0402LF-47.0PF,50V,5%,COG,AA!!!F3107!B!!!!
S!LED_LAN_1_N!C9F22!1!@baseboard_fab2_lib.baseboard_fab2(sch_1):page141_i60@mstr_discrete.cap(chips)!CAP_0402LF-470PF,50V,10%,X7R,AA!!!F3097!A!!!!
S!GND!C9F22!2!@baseboard_fab2_lib.baseboard_fab2(sch_1):page141_i60@mstr_discrete.cap(chips)!CAP_0402LF-470PF,50V,10%,X7R,AA!!!F3097!B!!!!
S!LED_LAN_2_N!C9G1!1!@baseboard_fab2_lib.baseboard_fab2(sch_1):page141_i58@mstr_discrete.cap(chips)!CAP_0402LF-470PF,50V,10%,X7R,AA!!!F3096!A!!!!
S!GND!C9G1!2!@baseboard_fab2_lib.baseboard_fab2(sch_1):page141_i58@mstr_discrete.cap(chips)!CAP_0402LF-470PF,50V,10%,X7R,AA!!!F3096!B!!!!
S!LED_LAN_0_N!C9G3!1!@baseboard_fab2_lib.baseboard_fab2(sch_1):page141_i59@mstr_discrete.cap(chips)!CAP_0402LF-470PF,50V,10%,X7R,AA!!!F3094!A!!!!
S!GND!C9G3!2!@baseboard_fab2_lib.baseboard_fab2(sch_1):page141_i59@mstr_discrete.cap(chips)!CAP_0402LF-470PF,50V,10%,X7R,AA!!!F3094!B!!!!
S!P3V3_STBY!C9G2!1!@baseboard_fab2_lib.baseboard_fab2(sch_1):page141_i36@mstr_discrete.cap(chips)!CAP_0402LF-470PF,50V,10%,X7R,AA!!!F3095!A!!!!
S!GND!C9G2!2!@baseboard_fab2_lib.baseboard_fab2(sch_1):page141_i36@mstr_discrete.cap(chips)!CAP_0402LF-470PF,50V,10%,X7R,AA!!!F3095!B!!!!
S!P1V26_BMC_STBY!C1T42!1!@baseboard_fab2_lib.baseboard_fab2(sch_1):page149_i85@mstr_discrete.cap(chips)!CAP_0603-0.47UF,16V,10%,X7R,20A!!!F3093!A!!!!
S!GND!C1T42!2!@baseboard_fab2_lib.baseboard_fab2(sch_1):page149_i85@mstr_discrete.cap(chips)!CAP_0603-0.47UF,16V,10%,X7R,20A!!!F3093!B!!!!
S!P3V3_STBY!C8A6!1!@baseboard_fab2_lib.baseboard_fab2(sch_1):page237_i29@mstr_discrete.cap(chips)!CAP_0603-10UF,6.3V,20%,X6S,E15A!!!F3075!A!!!!
S!GND!C8A6!2!@baseboard_fab2_lib.baseboard_fab2(sch_1):page237_i29@mstr_discrete.cap(chips)!CAP_0603-10UF,6.3V,20%,X6S,E15A!!!F3075!B!!!!
S!P3V3_STBY!C2N14!1!@baseboard_fab2_lib.baseboard_fab2(sch_1):page130_i25@mstr_discrete.cap(chips)!CAP_0603-10UF,6.3V,20%,X6S,E15A!!!F3082!A!!!!
S!GND!C2N14!2!@baseboard_fab2_lib.baseboard_fab2(sch_1):page130_i25@mstr_discrete.cap(chips)!CAP_0603-10UF,6.3V,20%,X6S,E15A!!!F3082!B!!!!
S!P3V3_STBY!C8C6!1!@baseboard_fab2_lib.baseboard_fab2(sch_1):page130_i22@mstr_discrete.cap(chips)!CAP_0603-10UF,6.3V,20%,X6S,E15A!!!F3071!A!!!!
S!GND!C8C6!2!@baseboard_fab2_lib.baseboard_fab2(sch_1):page130_i22@mstr_discrete.cap(chips)!CAP_0603-10UF,6.3V,20%,X6S,E15A!!!F3071!B!!!!
S!P3V3_STBY!C2N23!1!@baseboard_fab2_lib.baseboard_fab2(sch_1):page130_i24@mstr_discrete.cap(chips)!CAP_0603-10UF,6.3V,20%,X6S,E15A!!!F3078!A!!!!
S!GND!C2N23!2!@baseboard_fab2_lib.baseboard_fab2(sch_1):page130_i24@mstr_discrete.cap(chips)!CAP_0603-10UF,6.3V,20%,X6S,E15A!!!F3078!B!!!!
S!P3V3_STBY!C8C5!1!@baseboard_fab2_lib.baseboard_fab2(sch_1):page130_i21@mstr_discrete.cap(chips)!CAP_0603-10UF,6.3V,20%,X6S,E15A!!!F3072!A!!!!
S!GND!C8C5!2!@baseboard_fab2_lib.baseboard_fab2(sch_1):page130_i21@mstr_discrete.cap(chips)!CAP_0603-10UF,6.3V,20%,X6S,E15A!!!F3072!B!!!!
S!P3V3_STBY!C8C4!1!@baseboard_fab2_lib.baseboard_fab2(sch_1):page130_i20@mstr_discrete.cap(chips)!CAP_0603-10UF,6.3V,20%,X6S,E15A!!!F3073!A!!!!
S!GND!C8C4!2!@baseboard_fab2_lib.baseboard_fab2(sch_1):page130_i20@mstr_discrete.cap(chips)!CAP_0603-10UF,6.3V,20%,X6S,E15A!!!F3073!B!!!!
S!P3V3_STBY!C8C3!1!@baseboard_fab2_lib.baseboard_fab2(sch_1):page130_i19@mstr_discrete.cap(chips)!CAP_0603-10UF,6.3V,20%,X6S,E15A!!!F3074!A!!!!
S!GND!C8C3!2!@baseboard_fab2_lib.baseboard_fab2(sch_1):page130_i19@mstr_discrete.cap(chips)!CAP_0603-10UF,6.3V,20%,X6S,E15A!!!F3074!B!!!!
S!P3V3_STBY!C7D2!1!@baseboard_fab2_lib.baseboard_fab2(sch_1):page130_i2@mstr_discrete.cap(chips)!CAP_0603-10UF,6.3V,20%,X6S,E15A!!!F3076!A!!!!
S!GND!C7D2!2!@baseboard_fab2_lib.baseboard_fab2(sch_1):page130_i2@mstr_discrete.cap(chips)!CAP_0603-10UF,6.3V,20%,X6S,E15A!!!F3076!B!!!!
S!P3V3_STBY!C2N21!1!@baseboard_fab2_lib.baseboard_fab2(sch_1):page130_i15@mstr_discrete.cap(chips)!CAP_0603-10UF,6.3V,20%,X6S,E15A!!!F3080!A!!!!
S!GND!C2N21!2!@baseboard_fab2_lib.baseboard_fab2(sch_1):page130_i15@mstr_discrete.cap(chips)!CAP_0603-10UF,6.3V,20%,X6S,E15A!!!F3080!B!!!!
S!P3V3_STBY!C2N22!1!@baseboard_fab2_lib.baseboard_fab2(sch_1):page130_i9@mstr_discrete.cap(chips)!CAP_0603-10UF,6.3V,20%,X6S,E15A!!!F3079!A!!!!
S!GND!C2N22!2!@baseboard_fab2_lib.baseboard_fab2(sch_1):page130_i9@mstr_discrete.cap(chips)!CAP_0603-10UF,6.3V,20%,X6S,E15A!!!F3079!B!!!!
S!P3V3_STBY!C2N24!1!@baseboard_fab2_lib.baseboard_fab2(sch_1):page130_i8@mstr_discrete.cap(chips)!CAP_0603-10UF,6.3V,20%,X6S,E15A!!!F3077!A!!!!
S!GND!C2N24!2!@baseboard_fab2_lib.baseboard_fab2(sch_1):page130_i8@mstr_discrete.cap(chips)!CAP_0603-10UF,6.3V,20%,X6S,E15A!!!F3077!B!!!!
S!P3V3_STBY!C2N17!1!@baseboard_fab2_lib.baseboard_fab2(sch_1):page130_i28@mstr_discrete.cap(chips)!CAP_0603-10UF,6.3V,20%,X6S,E15A!!!F3081!A!!!!
S!GND!C2N17!2!@baseboard_fab2_lib.baseboard_fab2(sch_1):page130_i28@mstr_discrete.cap(chips)!CAP_0603-10UF,6.3V,20%,X6S,E15A!!!F3081!B!!!!
S!P1V538_BMC_STBY!C9F3!1!@baseboard_fab2_lib.baseboard_fab2(sch_1):page238_i7@mstr_discrete.cap(chips)!CAP_0603-10UF,6.3V,20%,X6S,E15A!!!F3069!A!!!!
S!GND!C9F3!2!@baseboard_fab2_lib.baseboard_fab2(sch_1):page238_i7@mstr_discrete.cap(chips)!CAP_0603-10UF,6.3V,20%,X6S,E15A!!!F3069!B!!!!
S!P1V26_BMC_STBY!C9E10!1!@baseboard_fab2_lib.baseboard_fab2(sch_1):page238_i23@mstr_discrete.cap(chips)!CAP_0603-10UF,6.3V,20%,X6S,E15A!!!F3070!A!!!!
S!GND!C9E10!2!@baseboard_fab2_lib.baseboard_fab2(sch_1):page238_i23@mstr_discrete.cap(chips)!CAP_0603-10UF,6.3V,20%,X6S,E15A!!!F3070!B!!!!
S!P3V3_STBY!C1T7!1!@baseboard_fab2_lib.baseboard_fab2(sch_1):page239_i22@mstr_discrete.cap(chips)!CAP_0603-10UF,6.3V,20%,X6S,E15A!!!F3084!A!!!!
S!GND!C1T7!2!@baseboard_fab2_lib.baseboard_fab2(sch_1):page239_i22@mstr_discrete.cap(chips)!CAP_0603-10UF,6.3V,20%,X6S,E15A!!!F3084!B!!!!
S!P1V538_BMC_STBY!C1T15!1!@baseboard_fab2_lib.baseboard_fab2(sch_1):page239_i12@mstr_discrete.cap(chips)!CAP_0603-10UF,6.3V,20%,X6S,E15A!!!F3083!A!!!!
S!GND!C1T15!2!@baseboard_fab2_lib.baseboard_fab2(sch_1):page239_i12@mstr_discrete.cap(chips)!CAP_0603-10UF,6.3V,20%,X6S,E15A!!!F3083!B!!!!
S!P3V3_STBY!C1R22!1!@baseboard_fab2_lib.baseboard_fab2(sch_1):page139_i136@mstr_discrete.cap(chips)!CAP_0603-10UF,6.3V,20%,X6S,E15A!!!F3087!A!!!!
S!GND!C1R22!2!@baseboard_fab2_lib.baseboard_fab2(sch_1):page139_i136@mstr_discrete.cap(chips)!CAP_0603-10UF,6.3V,20%,X6S,E15A!!!F3087!B!!!!
S!P1V5_LAN!C1R30!1!@baseboard_fab2_lib.baseboard_fab2(sch_1):page139_i135@mstr_discrete.cap(chips)!CAP_0603-10UF,6.3V,20%,X6S,E15A!!!F3086!A!!!!
S!GND!C1R30!2!@baseboard_fab2_lib.baseboard_fab2(sch_1):page139_i135@mstr_discrete.cap(chips)!CAP_0603-10UF,6.3V,20%,X6S,E15A!!!F3086!B!!!!
S!P0V9_LAN!C1T4!1!@baseboard_fab2_lib.baseboard_fab2(sch_1):page139_i134@mstr_discrete.cap(chips)!CAP_0603-10UF,6.3V,20%,X6S,E15A!!!F3085!A!!!!
S!GND!C1T4!2!@baseboard_fab2_lib.baseboard_fab2(sch_1):page139_i134@mstr_discrete.cap(chips)!CAP_0603-10UF,6.3V,20%,X6S,E15A!!!F3085!B!!!!
S!P3V3_STBY!C1R13!1!@baseboard_fab2_lib.baseboard_fab2(sch_1):page139_i142@mstr_discrete.cap(chips)!CAP_0603-10UF,6.3V,20%,X6S,E15A!!!F3090!A!!!!
S!GND!C1R13!2!@baseboard_fab2_lib.baseboard_fab2(sch_1):page139_i142@mstr_discrete.cap(chips)!CAP_0603-10UF,6.3V,20%,X6S,E15A!!!F3090!B!!!!
S!P1V5_LAN!C1R17!1!@baseboard_fab2_lib.baseboard_fab2(sch_1):page139_i153@mstr_discrete.cap(chips)!CAP_0603-10UF,6.3V,20%,X6S,E15A!!!F3088!A!!!!
S!GND!C1R17!2!@baseboard_fab2_lib.baseboard_fab2(sch_1):page139_i153@mstr_discrete.cap(chips)!CAP_0603-10UF,6.3V,20%,X6S,E15A!!!F3088!B!!!!
S!P0V9_LAN!C1R16!1!@baseboard_fab2_lib.baseboard_fab2(sch_1):page139_i161@mstr_discrete.cap(chips)!CAP_0603-10UF,6.3V,20%,X6S,E15A!!!F3089!A!!!!
S!GND!C1R16!2!@baseboard_fab2_lib.baseboard_fab2(sch_1):page139_i161@mstr_discrete.cap(chips)!CAP_0603-10UF,6.3V,20%,X6S,E15A!!!F3089!B!!!!
S!P5V_STBY!C2R11!1!@baseboard_fab2_lib.baseboard_fab2(sch_1):page240_i109@mstr_discrete.cap(chips)!CAP_0603-4.7UF,6.3V,10%,X6S,E1A!!!F2746!A!!!!
S!AGND_P3V3_STBY!C2R11!2!@baseboard_fab2_lib.baseboard_fab2(sch_1):page240_i109@mstr_discrete.cap(chips)!CAP_0603-4.7UF,6.3V,10%,X6S,E1A!!!F2746!B!!!!
S!VR_VB_PVPP_ABC!C3T11!1!@baseboard_fab2_lib.baseboard_fab2(sch_1):page231_i202@mstr_discrete.cap(chips)!CAP_0603-4.7UF,6.3V,10%,X6S,E1A!!!F2744!A!!!!
S!AGND_PVPP_ABC!C3T11!2!@baseboard_fab2_lib.baseboard_fab2(sch_1):page231_i202@mstr_discrete.cap(chips)!CAP_0603-4.7UF,6.3V,10%,X6S,E1A!!!F2744!B!!!!
S!VR_VB_PVPP_DEF!C3M10!1!@baseboard_fab2_lib.baseboard_fab2(sch_1):page232_i253@mstr_discrete.cap(chips)!CAP_0603-4.7UF,6.3V,10%,X6S,E1A!!!F2745!A!!!!
S!AGND_PVPP_DEF!C3M10!2!@baseboard_fab2_lib.baseboard_fab2(sch_1):page232_i253@mstr_discrete.cap(chips)!CAP_0603-4.7UF,6.3V,10%,X6S,E1A!!!F2745!B!!!!
S!VR_VB_PVPP_GHJ!C6U6!1!@baseboard_fab2_lib.baseboard_fab2(sch_1):page233_i187@mstr_discrete.cap(chips)!CAP_0603-4.7UF,6.3V,10%,X6S,E1A!!!F2740!A!!!!
S!AGND_PVPP_GHJ!C6U6!2!@baseboard_fab2_lib.baseboard_fab2(sch_1):page233_i187@mstr_discrete.cap(chips)!CAP_0603-4.7UF,6.3V,10%,X6S,E1A!!!F2740!B!!!!
S!VR_VB_PVPP_KLM!C6L12!1!@baseboard_fab2_lib.baseboard_fab2(sch_1):page234_i144@mstr_discrete.cap(chips)!CAP_0603-4.7UF,6.3V,10%,X6S,E1A!!!F2741!A!!!!
S!AGND_PVPP_KLM!C6L12!2!@baseboard_fab2_lib.baseboard_fab2(sch_1):page234_i144@mstr_discrete.cap(chips)!CAP_0603-4.7UF,6.3V,10%,X6S,E1A!!!F2741!B!!!!
S!VSENSE_PVDDQ_ABC_VTT!C6U12!1!@baseboard_fab2_lib.baseboard_fab2(sch_1):page221_i49@mstr_discrete.cap(chips)!CAP_0603-4.7UF,6.3V,10%,X6S,E1A!!!F2738!A!!!!
S!GND!C6U12!2!@baseboard_fab2_lib.baseboard_fab2(sch_1):page221_i49@mstr_discrete.cap(chips)!CAP_0603-4.7UF,6.3V,10%,X6S,E1A!!!F2738!B!!!!
S!VSENSE_PVDDQ_DEF_VTT!C4A11!1!@baseboard_fab2_lib.baseboard_fab2(sch_1):page222_i46@mstr_discrete.cap(chips)!CAP_0603-4.7UF,6.3V,10%,X6S,E1A!!!F2742!A!!!!
S!GND!C4A11!2!@baseboard_fab2_lib.baseboard_fab2(sch_1):page222_i46@mstr_discrete.cap(chips)!CAP_0603-4.7UF,6.3V,10%,X6S,E1A!!!F2742!B!!!!
S!VSENSE_PVDDQ_GHJ_VTT!C6U11!1!@baseboard_fab2_lib.baseboard_fab2(sch_1):page229_i46@mstr_discrete.cap(chips)!CAP_0603-4.7UF,6.3V,10%,X6S,E1A!!!F2739!A!!!!
S!GND!C6U11!2!@baseboard_fab2_lib.baseboard_fab2(sch_1):page229_i46@mstr_discrete.cap(chips)!CAP_0603-4.7UF,6.3V,10%,X6S,E1A!!!F2739!B!!!!
S!VSENSE_PVDDQ_KLM_VTT!C4A7!1!@baseboard_fab2_lib.baseboard_fab2(sch_1):page230_i46@mstr_discrete.cap(chips)!CAP_0603-4.7UF,6.3V,10%,X6S,E1A!!!F2743!A!!!!
S!GND!C4A7!2!@baseboard_fab2_lib.baseboard_fab2(sch_1):page230_i46@mstr_discrete.cap(chips)!CAP_0603-4.7UF,6.3V,10%,X6S,E1A!!!F2743!B!!!!
S!P3V3_STBY!C1T44!1!@baseboard_fab2_lib.baseboard_fab2(sch_1):page148_i25@mstr_discrete.cap(chips)!CAP_0603-4.7UF,6.3V,10%,X6S,E1A!!!F2747!A!!!!
S!GND!C1T44!2!@baseboard_fab2_lib.baseboard_fab2(sch_1):page148_i25@mstr_discrete.cap(chips)!CAP_0603-4.7UF,6.3V,10%,X6S,E1A!!!F2747!B!!!!
S!A_HSC_TIMER!C9P14!1!@baseboard_fab2_lib.baseboard_fab2(sch_1):page199_i24@mstr_discrete.cap(chips)!CAP_0603LF-0.033UF,50V,10%,X7RA!!!F2685!A!!!!
S!AGND_HSC!C9P14!2!@baseboard_fab2_lib.baseboard_fab2(sch_1):page199_i24@mstr_discrete.cap(chips)!CAP_0603LF-0.033UF,50V,10%,X7RA!!!F2685!B!!!!
S!VR_PVPP_DEF_PHASE!C7B30!1!@baseboard_fab2_lib.baseboard_fab2(sch_1):page232_i241@mstr_discrete.cap(chips)!CAP_0603LF-0.1UF,25V,10%,X7R,6A!!!F2684!A!!!!
S!VR_PVPP_DEF_BOOT_R!C7B30!2!@baseboard_fab2_lib.baseboard_fab2(sch_1):page232_i241@mstr_discrete.cap(chips)!CAP_0603LF-0.1UF,25V,10%,X7R,6A!!!F2684!B!!!!
S!VR_PVPP_GHJ_PHASE!C4G26!1!@baseboard_fab2_lib.baseboard_fab2(sch_1):page233_i224@mstr_discrete.cap(chips)!CAP_0603LF-0.1UF,25V,10%,X7R,6A!!!F2682!A!!!!
S!VR_PVPP_GHJ_BOOT_R!C4G26!2!@baseboard_fab2_lib.baseboard_fab2(sch_1):page233_i224@mstr_discrete.cap(chips)!CAP_0603LF-0.1UF,25V,10%,X7R,6A!!!F2682!B!!!!
S!VR_PVPP_KLM_PHASE!C4B15!1!@baseboard_fab2_lib.baseboard_fab2(sch_1):page234_i182@mstr_discrete.cap(chips)!CAP_0603LF-0.1UF,25V,10%,X7R,6A!!!F2683!A!!!!
S!VR_PVPP_KLM_BOOT_R!C4B15!2!@baseboard_fab2_lib.baseboard_fab2(sch_1):page234_i182@mstr_discrete.cap(chips)!CAP_0603LF-0.1UF,25V,10%,X7R,6A!!!F2683!B!!!!
S!VR_PVPP_ABC_PHASE!C7F4!1!@baseboard_fab2_lib.baseboard_fab2(sch_1):page231_i159@mstr_discrete.cap(chips)!CAP_0603LF-0.1UF,25V,10%,X7R,6A!!!F2681!A!!!!
S!VR_PVPP_ABC_BOOT_R!C7F4!2!@baseboard_fab2_lib.baseboard_fab2(sch_1):page231_i159@mstr_discrete.cap(chips)!CAP_0603LF-0.1UF,25V,10%,X7R,6A!!!F2681!B!!!!
S!VR_P3V3_STBY_PHASE!C8E12!1!@baseboard_fab2_lib.baseboard_fab2(sch_1):page240_i129@mstr_discrete.cap(chips)!CAP_0603LF-0.1UF,25V,10%,X7R,6A!!!F2678!A!!!!
S!VR_P3V3_STBY_BOOT_R!C8E12!2!@baseboard_fab2_lib.baseboard_fab2(sch_1):page240_i129@mstr_discrete.cap(chips)!CAP_0603LF-0.1UF,25V,10%,X7R,6A!!!F2678!B!!!!
S!P3V3_STBY!C8A4!1!@baseboard_fab2_lib.baseboard_fab2(sch_1):page237_i31@mstr_discrete.cap(chips)!CAP_0603LF-0.1UF,25V,10%,X7R,6A!!!F2680!A!!!!
S!GND!C8A4!2!@baseboard_fab2_lib.baseboard_fab2(sch_1):page237_i31@mstr_discrete.cap(chips)!CAP_0603LF-0.1UF,25V,10%,X7R,6A!!!F2680!B!!!!
S!VR_P5V_STBY_BOOT!C8E6!1!@baseboard_fab2_lib.baseboard_fab2(sch_1):page241_i12@mstr_discrete.cap(chips)!CAP_0603LF-0.1UF,25V,10%,X7R,6A!!!F2679!A!!!!
S!VR_P5V_STBY_PHASE!C8E6!2!@baseboard_fab2_lib.baseboard_fab2(sch_1):page241_i12@mstr_discrete.cap(chips)!CAP_0603LF-0.1UF,25V,10%,X7R,6A!!!F2679!B!!!!
S!PVPP_ABC!C6F5!1!@baseboard_fab2_lib.baseboard_fab2(sch_1):page231_i149@mstr_discrete.cap(chips)!CAP_0603LF-10UF,4V,20%,X6S,E15A!!!F2613!A!!!!
S!GND!C6F5!2!@baseboard_fab2_lib.baseboard_fab2(sch_1):page231_i149@mstr_discrete.cap(chips)!CAP_0603LF-10UF,4V,20%,X6S,E15A!!!F2613!B!!!!
S!PVPP_DEF!C4L1!1!@baseboard_fab2_lib.baseboard_fab2(sch_1):page232_i129@mstr_discrete.cap(chips)!CAP_0603LF-10UF,4V,20%,X6S,E15A!!!F2644!A!!!!
S!GND!C4L1!2!@baseboard_fab2_lib.baseboard_fab2(sch_1):page232_i129@mstr_discrete.cap(chips)!CAP_0603LF-10UF,4V,20%,X6S,E15A!!!F2644!B!!!!
S!PVPP_GHJ!C7U3!1!@baseboard_fab2_lib.baseboard_fab2(sch_1):page233_i136@mstr_discrete.cap(chips)!CAP_0603LF-10UF,4V,20%,X6S,E15A!!!F2592!A!!!!
S!GND!C7U3!2!@baseboard_fab2_lib.baseboard_fab2(sch_1):page233_i136@mstr_discrete.cap(chips)!CAP_0603LF-10UF,4V,20%,X6S,E15A!!!F2592!B!!!!
S!PVPP_ABC!C6F6!1!@baseboard_fab2_lib.baseboard_fab2(sch_1):page231_i122@mstr_discrete.cap(chips)!CAP_0603LF-10UF,4V,20%,X6S,E15A!!!F2612!A!!!!
S!GND!C6F6!2!@baseboard_fab2_lib.baseboard_fab2(sch_1):page231_i122@mstr_discrete.cap(chips)!CAP_0603LF-10UF,4V,20%,X6S,E15A!!!F2612!B!!!!
S!PVPP_ABC!C4T6!1!@baseboard_fab2_lib.baseboard_fab2(sch_1):page231_i124@mstr_discrete.cap(chips)!CAP_0603LF-10UF,4V,20%,X6S,E15A!!!F2637!A!!!!
S!GND!C4T6!2!@baseboard_fab2_lib.baseboard_fab2(sch_1):page231_i124@mstr_discrete.cap(chips)!CAP_0603LF-10UF,4V,20%,X6S,E15A!!!F2637!B!!!!
S!PVPP_ABC!C4T5!1!@baseboard_fab2_lib.baseboard_fab2(sch_1):page231_i125@mstr_discrete.cap(chips)!CAP_0603LF-10UF,4V,20%,X6S,E15A!!!F2638!A!!!!
S!GND!C4T5!2!@baseboard_fab2_lib.baseboard_fab2(sch_1):page231_i125@mstr_discrete.cap(chips)!CAP_0603LF-10UF,4V,20%,X6S,E15A!!!F2638!B!!!!
S!PVPP_ABC!C6G1!1!@baseboard_fab2_lib.baseboard_fab2(sch_1):page231_i126@mstr_discrete.cap(chips)!CAP_0603LF-10UF,4V,20%,X6S,E15A!!!F2611!A!!!!
S!GND!C6G1!2!@baseboard_fab2_lib.baseboard_fab2(sch_1):page231_i126@mstr_discrete.cap(chips)!CAP_0603LF-10UF,4V,20%,X6S,E15A!!!F2611!B!!!!
S!PVPP_ABC!C6G2!1!@baseboard_fab2_lib.baseboard_fab2(sch_1):page231_i128@mstr_discrete.cap(chips)!CAP_0603LF-10UF,4V,20%,X6S,E15A!!!F2610!A!!!!
S!GND!C6G2!2!@baseboard_fab2_lib.baseboard_fab2(sch_1):page231_i128@mstr_discrete.cap(chips)!CAP_0603LF-10UF,4V,20%,X6S,E15A!!!F2610!B!!!!
S!PVPP_ABC!C4U2!1!@baseboard_fab2_lib.baseboard_fab2(sch_1):page231_i129@mstr_discrete.cap(chips)!CAP_0603LF-10UF,4V,20%,X6S,E15A!!!F2635!A!!!!
S!GND!C4U2!2!@baseboard_fab2_lib.baseboard_fab2(sch_1):page231_i129@mstr_discrete.cap(chips)!CAP_0603LF-10UF,4V,20%,X6S,E15A!!!F2635!B!!!!
S!PVPP_ABC!C4U1!1!@baseboard_fab2_lib.baseboard_fab2(sch_1):page231_i130@mstr_discrete.cap(chips)!CAP_0603LF-10UF,4V,20%,X6S,E15A!!!F2636!A!!!!
S!GND!C4U1!2!@baseboard_fab2_lib.baseboard_fab2(sch_1):page231_i130@mstr_discrete.cap(chips)!CAP_0603LF-10UF,4V,20%,X6S,E15A!!!F2636!B!!!!
S!PVPP_ABC!C6G4!1!@baseboard_fab2_lib.baseboard_fab2(sch_1):page231_i131@mstr_discrete.cap(chips)!CAP_0603LF-10UF,4V,20%,X6S,E15A!!!F2609!A!!!!
S!GND!C6G4!2!@baseboard_fab2_lib.baseboard_fab2(sch_1):page231_i131@mstr_discrete.cap(chips)!CAP_0603LF-10UF,4V,20%,X6S,E15A!!!F2609!B!!!!
S!PVPP_ABC!C6G5!1!@baseboard_fab2_lib.baseboard_fab2(sch_1):page231_i145@mstr_discrete.cap(chips)!CAP_0603LF-10UF,4V,20%,X6S,E15A!!!F2608!A!!!!
S!GND!C6G5!2!@baseboard_fab2_lib.baseboard_fab2(sch_1):page231_i145@mstr_discrete.cap(chips)!CAP_0603LF-10UF,4V,20%,X6S,E15A!!!F2608!B!!!!
S!PVPP_ABC!C4U4!1!@baseboard_fab2_lib.baseboard_fab2(sch_1):page231_i146@mstr_discrete.cap(chips)!CAP_0603LF-10UF,4V,20%,X6S,E15A!!!F2633!A!!!!
S!GND!C4U4!2!@baseboard_fab2_lib.baseboard_fab2(sch_1):page231_i146@mstr_discrete.cap(chips)!CAP_0603LF-10UF,4V,20%,X6S,E15A!!!F2633!B!!!!
S!PVPP_ABC!C4U3!1!@baseboard_fab2_lib.baseboard_fab2(sch_1):page231_i148@mstr_discrete.cap(chips)!CAP_0603LF-10UF,4V,20%,X6S,E15A!!!F2634!A!!!!
S!GND!C4U3!2!@baseboard_fab2_lib.baseboard_fab2(sch_1):page231_i148@mstr_discrete.cap(chips)!CAP_0603LF-10UF,4V,20%,X6S,E15A!!!F2634!B!!!!
S!PVPP_DEF!C4L2!1!@baseboard_fab2_lib.baseboard_fab2(sch_1):page232_i102@mstr_discrete.cap(chips)!CAP_0603LF-10UF,4V,20%,X6S,E15A!!!F2643!A!!!!
S!GND!C4L2!2!@baseboard_fab2_lib.baseboard_fab2(sch_1):page232_i102@mstr_discrete.cap(chips)!CAP_0603LF-10UF,4V,20%,X6S,E15A!!!F2643!B!!!!
S!PVPP_DEF!C6A3!1!@baseboard_fab2_lib.baseboard_fab2(sch_1):page232_i104@mstr_discrete.cap(chips)!CAP_0603LF-10UF,4V,20%,X6S,E15A!!!F2619!A!!!!
S!GND!C6A3!2!@baseboard_fab2_lib.baseboard_fab2(sch_1):page232_i104@mstr_discrete.cap(chips)!CAP_0603LF-10UF,4V,20%,X6S,E15A!!!F2619!B!!!!
S!PVPP_DEF!C6A2!1!@baseboard_fab2_lib.baseboard_fab2(sch_1):page232_i105@mstr_discrete.cap(chips)!CAP_0603LF-10UF,4V,20%,X6S,E15A!!!F2620!A!!!!
S!GND!C6A2!2!@baseboard_fab2_lib.baseboard_fab2(sch_1):page232_i105@mstr_discrete.cap(chips)!CAP_0603LF-10UF,4V,20%,X6S,E15A!!!F2620!B!!!!
S!PVPP_DEF!C4L3!1!@baseboard_fab2_lib.baseboard_fab2(sch_1):page232_i106@mstr_discrete.cap(chips)!CAP_0603LF-10UF,4V,20%,X6S,E15A!!!F2642!A!!!!
S!GND!C4L3!2!@baseboard_fab2_lib.baseboard_fab2(sch_1):page232_i106@mstr_discrete.cap(chips)!CAP_0603LF-10UF,4V,20%,X6S,E15A!!!F2642!B!!!!
S!PVPP_DEF!C4L4!1!@baseboard_fab2_lib.baseboard_fab2(sch_1):page232_i108@mstr_discrete.cap(chips)!CAP_0603LF-10UF,4V,20%,X6S,E15A!!!F2641!A!!!!
S!GND!C4L4!2!@baseboard_fab2_lib.baseboard_fab2(sch_1):page232_i108@mstr_discrete.cap(chips)!CAP_0603LF-10UF,4V,20%,X6S,E15A!!!F2641!B!!!!
S!PVPP_DEF!C6A7!1!@baseboard_fab2_lib.baseboard_fab2(sch_1):page232_i109@mstr_discrete.cap(chips)!CAP_0603LF-10UF,4V,20%,X6S,E15A!!!F2617!A!!!!
S!GND!C6A7!2!@baseboard_fab2_lib.baseboard_fab2(sch_1):page232_i109@mstr_discrete.cap(chips)!CAP_0603LF-10UF,4V,20%,X6S,E15A!!!F2617!B!!!!
S!PVPP_DEF!C6A6!1!@baseboard_fab2_lib.baseboard_fab2(sch_1):page232_i110@mstr_discrete.cap(chips)!CAP_0603LF-10UF,4V,20%,X6S,E15A!!!F2618!A!!!!
S!GND!C6A6!2!@baseboard_fab2_lib.baseboard_fab2(sch_1):page232_i110@mstr_discrete.cap(chips)!CAP_0603LF-10UF,4V,20%,X6S,E15A!!!F2618!B!!!!
S!PVPP_DEF!C4M3!1!@baseboard_fab2_lib.baseboard_fab2(sch_1):page232_i111@mstr_discrete.cap(chips)!CAP_0603LF-10UF,4V,20%,X6S,E15A!!!F2640!A!!!!
S!GND!C4M3!2!@baseboard_fab2_lib.baseboard_fab2(sch_1):page232_i111@mstr_discrete.cap(chips)!CAP_0603LF-10UF,4V,20%,X6S,E15A!!!F2640!B!!!!
S!PVPP_DEF!C4M4!1!@baseboard_fab2_lib.baseboard_fab2(sch_1):page232_i125@mstr_discrete.cap(chips)!CAP_0603LF-10UF,4V,20%,X6S,E15A!!!F2639!A!!!!
S!GND!C4M4!2!@baseboard_fab2_lib.baseboard_fab2(sch_1):page232_i125@mstr_discrete.cap(chips)!CAP_0603LF-10UF,4V,20%,X6S,E15A!!!F2639!B!!!!
S!PVPP_DEF!C6B2!1!@baseboard_fab2_lib.baseboard_fab2(sch_1):page232_i126@mstr_discrete.cap(chips)!CAP_0603LF-10UF,4V,20%,X6S,E15A!!!F2615!A!!!!
S!GND!C6B2!2!@baseboard_fab2_lib.baseboard_fab2(sch_1):page232_i126@mstr_discrete.cap(chips)!CAP_0603LF-10UF,4V,20%,X6S,E15A!!!F2615!B!!!!
S!PVPP_DEF!C6B1!1!@baseboard_fab2_lib.baseboard_fab2(sch_1):page232_i128@mstr_discrete.cap(chips)!CAP_0603LF-10UF,4V,20%,X6S,E15A!!!F2616!A!!!!
S!GND!C6B1!2!@baseboard_fab2_lib.baseboard_fab2(sch_1):page232_i128@mstr_discrete.cap(chips)!CAP_0603LF-10UF,4V,20%,X6S,E15A!!!F2616!B!!!!
S!PVPP_GHJ!C7U4!1!@baseboard_fab2_lib.baseboard_fab2(sch_1):page233_i109@mstr_discrete.cap(chips)!CAP_0603LF-10UF,4V,20%,X6S,E15A!!!F2591!A!!!!
S!GND!C7U4!2!@baseboard_fab2_lib.baseboard_fab2(sch_1):page233_i109@mstr_discrete.cap(chips)!CAP_0603LF-10UF,4V,20%,X6S,E15A!!!F2591!B!!!!
S!PVPP_GHJ!C7U5!1!@baseboard_fab2_lib.baseboard_fab2(sch_1):page233_i111@mstr_discrete.cap(chips)!CAP_0603LF-10UF,4V,20%,X6S,E15A!!!F2590!A!!!!
S!GND!C7U5!2!@baseboard_fab2_lib.baseboard_fab2(sch_1):page233_i111@mstr_discrete.cap(chips)!CAP_0603LF-10UF,4V,20%,X6S,E15A!!!F2590!B!!!!
S!PVPP_GHJ!C7T2!1!@baseboard_fab2_lib.baseboard_fab2(sch_1):page233_i112@mstr_discrete.cap(chips)!CAP_0603LF-10UF,4V,20%,X6S,E15A!!!F2594!A!!!!
S!GND!C7T2!2!@baseboard_fab2_lib.baseboard_fab2(sch_1):page233_i112@mstr_discrete.cap(chips)!CAP_0603LF-10UF,4V,20%,X6S,E15A!!!F2594!B!!!!
S!PVPP_GHJ!C7T3!1!@baseboard_fab2_lib.baseboard_fab2(sch_1):page233_i113@mstr_discrete.cap(chips)!CAP_0603LF-10UF,4V,20%,X6S,E15A!!!F2593!A!!!!
S!GND!C7T3!2!@baseboard_fab2_lib.baseboard_fab2(sch_1):page233_i113@mstr_discrete.cap(chips)!CAP_0603LF-10UF,4V,20%,X6S,E15A!!!F2593!B!!!!
S!PVPP_GHJ!C7U6!1!@baseboard_fab2_lib.baseboard_fab2(sch_1):page233_i115@mstr_discrete.cap(chips)!CAP_0603LF-10UF,4V,20%,X6S,E15A!!!F2589!A!!!!
S!GND!C7U6!2!@baseboard_fab2_lib.baseboard_fab2(sch_1):page233_i115@mstr_discrete.cap(chips)!CAP_0603LF-10UF,4V,20%,X6S,E15A!!!F2589!B!!!!
S!PVPP_GHJ!C3F3!1!@baseboard_fab2_lib.baseboard_fab2(sch_1):page233_i116@mstr_discrete.cap(chips)!CAP_0603LF-10UF,4V,20%,X6S,E15A!!!F2655!A!!!!
S!GND!C3F3!2!@baseboard_fab2_lib.baseboard_fab2(sch_1):page233_i116@mstr_discrete.cap(chips)!CAP_0603LF-10UF,4V,20%,X6S,E15A!!!F2655!B!!!!
S!PVPP_GHJ!C3F4!1!@baseboard_fab2_lib.baseboard_fab2(sch_1):page233_i117@mstr_discrete.cap(chips)!CAP_0603LF-10UF,4V,20%,X6S,E15A!!!F2654!A!!!!
S!GND!C3F4!2!@baseboard_fab2_lib.baseboard_fab2(sch_1):page233_i117@mstr_discrete.cap(chips)!CAP_0603LF-10UF,4V,20%,X6S,E15A!!!F2654!B!!!!
S!PVPP_GHJ!C3G3!1!@baseboard_fab2_lib.baseboard_fab2(sch_1):page233_i118@mstr_discrete.cap(chips)!CAP_0603LF-10UF,4V,20%,X6S,E15A!!!F2653!A!!!!
S!GND!C3G3!2!@baseboard_fab2_lib.baseboard_fab2(sch_1):page233_i118@mstr_discrete.cap(chips)!CAP_0603LF-10UF,4V,20%,X6S,E15A!!!F2653!B!!!!
S!PVPP_GHJ!C3G7!1!@baseboard_fab2_lib.baseboard_fab2(sch_1):page233_i132@mstr_discrete.cap(chips)!CAP_0603LF-10UF,4V,20%,X6S,E15A!!!F2651!A!!!!
S!GND!C3G7!2!@baseboard_fab2_lib.baseboard_fab2(sch_1):page233_i132@mstr_discrete.cap(chips)!CAP_0603LF-10UF,4V,20%,X6S,E15A!!!F2651!B!!!!
S!PVPP_GHJ!C3G4!1!@baseboard_fab2_lib.baseboard_fab2(sch_1):page233_i133@mstr_discrete.cap(chips)!CAP_0603LF-10UF,4V,20%,X6S,E15A!!!F2652!A!!!!
S!GND!C3G4!2!@baseboard_fab2_lib.baseboard_fab2(sch_1):page233_i133@mstr_discrete.cap(chips)!CAP_0603LF-10UF,4V,20%,X6S,E15A!!!F2652!B!!!!
S!PVPP_GHJ!C3G8!1!@baseboard_fab2_lib.baseboard_fab2(sch_1):page233_i135@mstr_discrete.cap(chips)!CAP_0603LF-10UF,4V,20%,X6S,E15A!!!F2650!A!!!!
S!GND!C3G8!2!@baseboard_fab2_lib.baseboard_fab2(sch_1):page233_i135@mstr_discrete.cap(chips)!CAP_0603LF-10UF,4V,20%,X6S,E15A!!!F2650!B!!!!
S!PVPP_KLM!C3A3!1!@baseboard_fab2_lib.baseboard_fab2(sch_1):page234_i97@mstr_discrete.cap(chips)!CAP_0603LF-10UF,4V,20%,X6S,E15A!!!F2662!A!!!!
S!GND!C3A3!2!@baseboard_fab2_lib.baseboard_fab2(sch_1):page234_i97@mstr_discrete.cap(chips)!CAP_0603LF-10UF,4V,20%,X6S,E15A!!!F2662!B!!!!
S!PVPP_KLM!C3A7!1!@baseboard_fab2_lib.baseboard_fab2(sch_1):page234_i95@mstr_discrete.cap(chips)!CAP_0603LF-10UF,4V,20%,X6S,E15A!!!F2660!A!!!!
S!GND!C3A7!2!@baseboard_fab2_lib.baseboard_fab2(sch_1):page234_i95@mstr_discrete.cap(chips)!CAP_0603LF-10UF,4V,20%,X6S,E15A!!!F2660!B!!!!
S!PVPP_KLM!C3B1!1!@baseboard_fab2_lib.baseboard_fab2(sch_1):page234_i94@mstr_discrete.cap(chips)!CAP_0603LF-10UF,4V,20%,X6S,E15A!!!F2658!A!!!!
S!GND!C3B1!2!@baseboard_fab2_lib.baseboard_fab2(sch_1):page234_i94@mstr_discrete.cap(chips)!CAP_0603LF-10UF,4V,20%,X6S,E15A!!!F2658!B!!!!
S!PVPP_KLM!C3A4!1!@baseboard_fab2_lib.baseboard_fab2(sch_1):page234_i93@mstr_discrete.cap(chips)!CAP_0603LF-10UF,4V,20%,X6S,E15A!!!F2661!A!!!!
S!GND!C3A4!2!@baseboard_fab2_lib.baseboard_fab2(sch_1):page234_i93@mstr_discrete.cap(chips)!CAP_0603LF-10UF,4V,20%,X6S,E15A!!!F2661!B!!!!
S!PVPP_KLM!C7M3!1!@baseboard_fab2_lib.baseboard_fab2(sch_1):page234_i92@mstr_discrete.cap(chips)!CAP_0603LF-10UF,4V,20%,X6S,E15A!!!F2596!A!!!!
S!GND!C7M3!2!@baseboard_fab2_lib.baseboard_fab2(sch_1):page234_i92@mstr_discrete.cap(chips)!CAP_0603LF-10UF,4V,20%,X6S,E15A!!!F2596!B!!!!
S!PVPP_KLM!C7M4!1!@baseboard_fab2_lib.baseboard_fab2(sch_1):page234_i91@mstr_discrete.cap(chips)!CAP_0603LF-10UF,4V,20%,X6S,E15A!!!F2595!A!!!!
S!GND!C7M4!2!@baseboard_fab2_lib.baseboard_fab2(sch_1):page234_i91@mstr_discrete.cap(chips)!CAP_0603LF-10UF,4V,20%,X6S,E15A!!!F2595!B!!!!
S!PVPP_KLM!C7L6!1!@baseboard_fab2_lib.baseboard_fab2(sch_1):page234_i90@mstr_discrete.cap(chips)!CAP_0603LF-10UF,4V,20%,X6S,E15A!!!F2598!A!!!!
S!GND!C7L6!2!@baseboard_fab2_lib.baseboard_fab2(sch_1):page234_i90@mstr_discrete.cap(chips)!CAP_0603LF-10UF,4V,20%,X6S,E15A!!!F2598!B!!!!
S!PVPP_KLM!C7L7!1!@baseboard_fab2_lib.baseboard_fab2(sch_1):page234_i89@mstr_discrete.cap(chips)!CAP_0603LF-10UF,4V,20%,X6S,E15A!!!F2597!A!!!!
S!GND!C7L7!2!@baseboard_fab2_lib.baseboard_fab2(sch_1):page234_i89@mstr_discrete.cap(chips)!CAP_0603LF-10UF,4V,20%,X6S,E15A!!!F2597!B!!!!
S!PVPP_KLM!C7L2!1!@baseboard_fab2_lib.baseboard_fab2(sch_1):page234_i88@mstr_discrete.cap(chips)!CAP_0603LF-10UF,4V,20%,X6S,E15A!!!F2600!A!!!!
S!GND!C7L2!2!@baseboard_fab2_lib.baseboard_fab2(sch_1):page234_i88@mstr_discrete.cap(chips)!CAP_0603LF-10UF,4V,20%,X6S,E15A!!!F2600!B!!!!
S!PVPP_KLM!C7L3!1!@baseboard_fab2_lib.baseboard_fab2(sch_1):page234_i87@mstr_discrete.cap(chips)!CAP_0603LF-10UF,4V,20%,X6S,E15A!!!F2599!A!!!!
S!GND!C7L3!2!@baseboard_fab2_lib.baseboard_fab2(sch_1):page234_i87@mstr_discrete.cap(chips)!CAP_0603LF-10UF,4V,20%,X6S,E15A!!!F2599!B!!!!
S!PVPP_KLM!C3A8!1!@baseboard_fab2_lib.baseboard_fab2(sch_1):page234_i86@mstr_discrete.cap(chips)!CAP_0603LF-10UF,4V,20%,X6S,E15A!!!F2659!A!!!!
S!GND!C3A8!2!@baseboard_fab2_lib.baseboard_fab2(sch_1):page234_i86@mstr_discrete.cap(chips)!CAP_0603LF-10UF,4V,20%,X6S,E15A!!!F2659!B!!!!
S!PVPP_KLM!C3B2!1!@baseboard_fab2_lib.baseboard_fab2(sch_1):page234_i84@mstr_discrete.cap(chips)!CAP_0603LF-10UF,4V,20%,X6S,E15A!!!F2657!A!!!!
S!GND!C3B2!2!@baseboard_fab2_lib.baseboard_fab2(sch_1):page234_i84@mstr_discrete.cap(chips)!CAP_0603LF-10UF,4V,20%,X6S,E15A!!!F2657!B!!!!
S!P1V05_PCH_STBY_ISCLK_PLL!C3M24!1!@baseboard_fab2_lib.baseboard_fab2(sch_1):page127_i54@mstr_discrete.cap(chips)!CAP_0603LF-10UF,4V,20%,X6S,E15A!!!F2646!A!!!!
S!GND!C3M24!2!@baseboard_fab2_lib.baseboard_fab2(sch_1):page127_i54@mstr_discrete.cap(chips)!CAP_0603LF-10UF,4V,20%,X6S,E15A!!!F2646!B!!!!
S!P1V05_PCH_STBY_KR_PLL!C2N6!1!@baseboard_fab2_lib.baseboard_fab2(sch_1):page127_i64@mstr_discrete.cap(chips)!CAP_0603LF-10UF,4V,20%,X6S,E15A!!!F2663!A!!!!
S!GND!C2N6!2!@baseboard_fab2_lib.baseboard_fab2(sch_1):page127_i64@mstr_discrete.cap(chips)!CAP_0603LF-10UF,4V,20%,X6S,E15A!!!F2663!B!!!!
S!P1V05_PCH_STBY_WM20_PLL!C2M5!1!@baseboard_fab2_lib.baseboard_fab2(sch_1):page127_i43@mstr_discrete.cap(chips)!CAP_0603LF-10UF,4V,20%,X6S,E15A!!!F2665!A!!!!
S!GND!C2M5!2!@baseboard_fab2_lib.baseboard_fab2(sch_1):page127_i43@mstr_discrete.cap(chips)!CAP_0603LF-10UF,4V,20%,X6S,E15A!!!F2665!B!!!!
S!P1V05_PCH_STBY_WM26_PLL!C2M10!1!@baseboard_fab2_lib.baseboard_fab2(sch_1):page127_i49@mstr_discrete.cap(chips)!CAP_0603LF-10UF,4V,20%,X6S,E15A!!!F2664!A!!!!
S!GND!C2M10!2!@baseboard_fab2_lib.baseboard_fab2(sch_1):page127_i49@mstr_discrete.cap(chips)!CAP_0603LF-10UF,4V,20%,X6S,E15A!!!F2664!B!!!!
S!P1V05_PCH_STBY_VCCA_PLL1!C3M17!1!@baseboard_fab2_lib.baseboard_fab2(sch_1):page127_i3@mstr_discrete.cap(chips)!CAP_0603LF-10UF,4V,20%,X6S,E15A!!!F2649!A!!!!
S!GND!C3M17!2!@baseboard_fab2_lib.baseboard_fab2(sch_1):page127_i3@mstr_discrete.cap(chips)!CAP_0603LF-10UF,4V,20%,X6S,E15A!!!F2649!B!!!!
S!P1V05_PCH_STBY_VCCA_PLL0!C3M18!1!@baseboard_fab2_lib.baseboard_fab2(sch_1):page127_i10@mstr_discrete.cap(chips)!CAP_0603LF-10UF,4V,20%,X6S,E15A!!!F2648!A!!!!
S!GND!C3M18!2!@baseboard_fab2_lib.baseboard_fab2(sch_1):page127_i10@mstr_discrete.cap(chips)!CAP_0603LF-10UF,4V,20%,X6S,E15A!!!F2648!B!!!!
S!P1V05_PCH_STBY_VCCA_XTAL!C3M23!1!@baseboard_fab2_lib.baseboard_fab2(sch_1):page127_i19@mstr_discrete.cap(chips)!CAP_0603LF-10UF,4V,20%,X6S,E15A!!!F2647!A!!!!
S!GND!C3M23!2!@baseboard_fab2_lib.baseboard_fab2(sch_1):page127_i19@mstr_discrete.cap(chips)!CAP_0603LF-10UF,4V,20%,X6S,E15A!!!F2647!B!!!!
S!PVDDQ_ABC!C6U15!1!@baseboard_fab2_lib.baseboard_fab2(sch_1):page221_i26@mstr_discrete.cap(chips)!CAP_0603LF-10UF,4V,20%,X6S,E15A!!!F2602!A!!!!
S!GND!C6U15!2!@baseboard_fab2_lib.baseboard_fab2(sch_1):page221_i26@mstr_discrete.cap(chips)!CAP_0603LF-10UF,4V,20%,X6S,E15A!!!F2602!B!!!!
S!PVDDQ_ABC!C6U16!1!@baseboard_fab2_lib.baseboard_fab2(sch_1):page221_i22@mstr_discrete.cap(chips)!CAP_0603LF-10UF,4V,20%,X6S,E15A!!!F2601!A!!!!
S!GND!C6U16!2!@baseboard_fab2_lib.baseboard_fab2(sch_1):page221_i22@mstr_discrete.cap(chips)!CAP_0603LF-10UF,4V,20%,X6S,E15A!!!F2601!B!!!!
S!PVDDQ_DEF!C6L4!1!@baseboard_fab2_lib.baseboard_fab2(sch_1):page222_i26@mstr_discrete.cap(chips)!CAP_0603LF-10UF,4V,20%,X6S,E15A!!!F2606!A!!!!
S!GND!C6L4!2!@baseboard_fab2_lib.baseboard_fab2(sch_1):page222_i26@mstr_discrete.cap(chips)!CAP_0603LF-10UF,4V,20%,X6S,E15A!!!F2606!B!!!!
S!PVDDQ_GHJ!C6U13!1!@baseboard_fab2_lib.baseboard_fab2(sch_1):page229_i29@mstr_discrete.cap(chips)!CAP_0603LF-10UF,4V,20%,X6S,E15A!!!F2604!A!!!!
S!GND!C6U13!2!@baseboard_fab2_lib.baseboard_fab2(sch_1):page229_i29@mstr_discrete.cap(chips)!CAP_0603LF-10UF,4V,20%,X6S,E15A!!!F2604!B!!!!
S!PVDDQ_KLM!C6L5!1!@baseboard_fab2_lib.baseboard_fab2(sch_1):page230_i26@mstr_discrete.cap(chips)!CAP_0603LF-10UF,4V,20%,X6S,E15A!!!F2605!A!!!!
S!GND!C6L5!2!@baseboard_fab2_lib.baseboard_fab2(sch_1):page230_i26@mstr_discrete.cap(chips)!CAP_0603LF-10UF,4V,20%,X6S,E15A!!!F2605!B!!!!
S!PVDDQ_DEF!C6L3!1!@baseboard_fab2_lib.baseboard_fab2(sch_1):page222_i24@mstr_discrete.cap(chips)!CAP_0603LF-10UF,4V,20%,X6S,E15A!!!F2607!A!!!!
S!GND!C6L3!2!@baseboard_fab2_lib.baseboard_fab2(sch_1):page222_i24@mstr_discrete.cap(chips)!CAP_0603LF-10UF,4V,20%,X6S,E15A!!!F2607!B!!!!
S!PVDDQ_GHJ!C6U14!1!@baseboard_fab2_lib.baseboard_fab2(sch_1):page229_i25@mstr_discrete.cap(chips)!CAP_0603LF-10UF,4V,20%,X6S,E15A!!!F2603!A!!!!
S!GND!C6U14!2!@baseboard_fab2_lib.baseboard_fab2(sch_1):page229_i25@mstr_discrete.cap(chips)!CAP_0603LF-10UF,4V,20%,X6S,E15A!!!F2603!B!!!!
S!PVDDQ_KLM!C4A15!1!@baseboard_fab2_lib.baseboard_fab2(sch_1):page230_i25@mstr_discrete.cap(chips)!CAP_0603LF-10UF,4V,20%,X6S,E15A!!!F2645!A!!!!
S!GND!C4A15!2!@baseboard_fab2_lib.baseboard_fab2(sch_1):page230_i25@mstr_discrete.cap(chips)!CAP_0603LF-10UF,4V,20%,X6S,E15A!!!F2645!B!!!!
S!PVDDQ_ABC!C5D54!1!@baseboard_fab2_lib.baseboard_fab2(sch_1):page217_i190@mstr_discrete.cap(chips)!CAP_0603LF-10UF,4V,20%,X6S,E15A!!!F2624!A!!!!
S!GND!C5D54!2!@baseboard_fab2_lib.baseboard_fab2(sch_1):page217_i190@mstr_discrete.cap(chips)!CAP_0603LF-10UF,4V,20%,X6S,E15A!!!F2624!B!!!!
S!PVDDQ_ABC!C5D55!1!@baseboard_fab2_lib.baseboard_fab2(sch_1):page217_i189@mstr_discrete.cap(chips)!CAP_0603LF-10UF,4V,20%,X6S,E15A!!!F2623!A!!!!
S!GND!C5D55!2!@baseboard_fab2_lib.baseboard_fab2(sch_1):page217_i189@mstr_discrete.cap(chips)!CAP_0603LF-10UF,4V,20%,X6S,E15A!!!F2623!B!!!!
S!PVDDQ_ABC!C5D56!1!@baseboard_fab2_lib.baseboard_fab2(sch_1):page217_i188@mstr_discrete.cap(chips)!CAP_0603LF-10UF,4V,20%,X6S,E15A!!!F2622!A!!!!
S!GND!C5D56!2!@baseboard_fab2_lib.baseboard_fab2(sch_1):page217_i188@mstr_discrete.cap(chips)!CAP_0603LF-10UF,4V,20%,X6S,E15A!!!F2622!B!!!!
S!PVDDQ_ABC!C5D57!1!@baseboard_fab2_lib.baseboard_fab2(sch_1):page217_i186@mstr_discrete.cap(chips)!CAP_0603LF-10UF,4V,20%,X6S,E15A!!!F2621!A!!!!
S!GND!C5D57!2!@baseboard_fab2_lib.baseboard_fab2(sch_1):page217_i186@mstr_discrete.cap(chips)!CAP_0603LF-10UF,4V,20%,X6S,E15A!!!F2621!B!!!!
S!PVDDQ_DEF!C5D9!1!@baseboard_fab2_lib.baseboard_fab2(sch_1):page220_i180@mstr_discrete.cap(chips)!CAP_0603LF-10UF,4V,20%,X6S,E15A!!!F2629!A!!!!
S!GND!C5D9!2!@baseboard_fab2_lib.baseboard_fab2(sch_1):page220_i180@mstr_discrete.cap(chips)!CAP_0603LF-10UF,4V,20%,X6S,E15A!!!F2629!B!!!!
S!PVDDQ_DEF!C5D6!1!@baseboard_fab2_lib.baseboard_fab2(sch_1):page220_i182@mstr_discrete.cap(chips)!CAP_0603LF-10UF,4V,20%,X6S,E15A!!!F2632!A!!!!
S!GND!C5D6!2!@baseboard_fab2_lib.baseboard_fab2(sch_1):page220_i182@mstr_discrete.cap(chips)!CAP_0603LF-10UF,4V,20%,X6S,E15A!!!F2632!B!!!!
S!PVDDQ_DEF!C5D7!1!@baseboard_fab2_lib.baseboard_fab2(sch_1):page220_i183@mstr_discrete.cap(chips)!CAP_0603LF-10UF,4V,20%,X6S,E15A!!!F2631!A!!!!
S!GND!C5D7!2!@baseboard_fab2_lib.baseboard_fab2(sch_1):page220_i183@mstr_discrete.cap(chips)!CAP_0603LF-10UF,4V,20%,X6S,E15A!!!F2631!B!!!!
S!PVDDQ_DEF!C5D8!1!@baseboard_fab2_lib.baseboard_fab2(sch_1):page220_i184@mstr_discrete.cap(chips)!CAP_0603LF-10UF,4V,20%,X6S,E15A!!!F2630!A!!!!
S!GND!C5D8!2!@baseboard_fab2_lib.baseboard_fab2(sch_1):page220_i184@mstr_discrete.cap(chips)!CAP_0603LF-10UF,4V,20%,X6S,E15A!!!F2630!B!!!!
S!PVDDQ_GHJ!C2D43!1!@baseboard_fab2_lib.baseboard_fab2(sch_1):page225_i179@mstr_discrete.cap(chips)!CAP_0603LF-10UF,4V,20%,X6S,E15A!!!F2667!A!!!!
S!GND!C2D43!2!@baseboard_fab2_lib.baseboard_fab2(sch_1):page225_i179@mstr_discrete.cap(chips)!CAP_0603LF-10UF,4V,20%,X6S,E15A!!!F2667!B!!!!
S!PVDDQ_GHJ!C2D41!1!@baseboard_fab2_lib.baseboard_fab2(sch_1):page225_i180@mstr_discrete.cap(chips)!CAP_0603LF-10UF,4V,20%,X6S,E15A!!!F2669!A!!!!
S!GND!C2D41!2!@baseboard_fab2_lib.baseboard_fab2(sch_1):page225_i180@mstr_discrete.cap(chips)!CAP_0603LF-10UF,4V,20%,X6S,E15A!!!F2669!B!!!!
S!PVDDQ_GHJ!C2D44!1!@baseboard_fab2_lib.baseboard_fab2(sch_1):page225_i181@mstr_discrete.cap(chips)!CAP_0603LF-10UF,4V,20%,X6S,E15A!!!F2666!A!!!!
S!GND!C2D44!2!@baseboard_fab2_lib.baseboard_fab2(sch_1):page225_i181@mstr_discrete.cap(chips)!CAP_0603LF-10UF,4V,20%,X6S,E15A!!!F2666!B!!!!
S!PVDDQ_GHJ!C2D42!1!@baseboard_fab2_lib.baseboard_fab2(sch_1):page225_i183@mstr_discrete.cap(chips)!CAP_0603LF-10UF,4V,20%,X6S,E15A!!!F2668!A!!!!
S!GND!C2D42!2!@baseboard_fab2_lib.baseboard_fab2(sch_1):page225_i183@mstr_discrete.cap(chips)!CAP_0603LF-10UF,4V,20%,X6S,E15A!!!F2668!B!!!!
S!PVDDQ_KLM!C2D7!1!@baseboard_fab2_lib.baseboard_fab2(sch_1):page228_i186@mstr_discrete.cap(chips)!CAP_0603LF-10UF,4V,20%,X6S,E15A!!!F2674!A!!!!
S!GND!C2D7!2!@baseboard_fab2_lib.baseboard_fab2(sch_1):page228_i186@mstr_discrete.cap(chips)!CAP_0603LF-10UF,4V,20%,X6S,E15A!!!F2674!B!!!!
S!PVDDQ_KLM!C2D4!1!@baseboard_fab2_lib.baseboard_fab2(sch_1):page228_i187@mstr_discrete.cap(chips)!CAP_0603LF-10UF,4V,20%,X6S,E15A!!!F2677!A!!!!
S!GND!C2D4!2!@baseboard_fab2_lib.baseboard_fab2(sch_1):page228_i187@mstr_discrete.cap(chips)!CAP_0603LF-10UF,4V,20%,X6S,E15A!!!F2677!B!!!!
S!PVDDQ_KLM!C2D5!1!@baseboard_fab2_lib.baseboard_fab2(sch_1):page228_i188@mstr_discrete.cap(chips)!CAP_0603LF-10UF,4V,20%,X6S,E15A!!!F2676!A!!!!
S!GND!C2D5!2!@baseboard_fab2_lib.baseboard_fab2(sch_1):page228_i188@mstr_discrete.cap(chips)!CAP_0603LF-10UF,4V,20%,X6S,E15A!!!F2676!B!!!!
S!PVDDQ_KLM!C2D6!1!@baseboard_fab2_lib.baseboard_fab2(sch_1):page228_i190@mstr_discrete.cap(chips)!CAP_0603LF-10UF,4V,20%,X6S,E15A!!!F2675!A!!!!
S!GND!C2D6!2!@baseboard_fab2_lib.baseboard_fab2(sch_1):page228_i190@mstr_discrete.cap(chips)!CAP_0603LF-10UF,4V,20%,X6S,E15A!!!F2675!B!!!!
S!PVSA_CPU0!C5D10!1!@baseboard_fab2_lib.baseboard_fab2(sch_1):page42_i108@mstr_discrete.cap(chips)!CAP_0603LF-10UF,4V,20%,X6S,E15A!!!F2628!A!!!!
S!GND!C5D10!2!@baseboard_fab2_lib.baseboard_fab2(sch_1):page42_i108@mstr_discrete.cap(chips)!CAP_0603LF-10UF,4V,20%,X6S,E15A!!!F2628!B!!!!
S!PVSA_CPU0!C5D12!1!@baseboard_fab2_lib.baseboard_fab2(sch_1):page42_i94@mstr_discrete.cap(chips)!CAP_0603LF-10UF,4V,20%,X6S,E15A!!!F2626!A!!!!
S!GND!C5D12!2!@baseboard_fab2_lib.baseboard_fab2(sch_1):page42_i94@mstr_discrete.cap(chips)!CAP_0603LF-10UF,4V,20%,X6S,E15A!!!F2626!B!!!!
S!PVSA_CPU0!C5D11!1!@baseboard_fab2_lib.baseboard_fab2(sch_1):page42_i93@mstr_discrete.cap(chips)!CAP_0603LF-10UF,4V,20%,X6S,E15A!!!F2627!A!!!!
S!GND!C5D11!2!@baseboard_fab2_lib.baseboard_fab2(sch_1):page42_i93@mstr_discrete.cap(chips)!CAP_0603LF-10UF,4V,20%,X6S,E15A!!!F2627!B!!!!
S!PVSA_CPU0!C5D13!1!@baseboard_fab2_lib.baseboard_fab2(sch_1):page42_i91@mstr_discrete.cap(chips)!CAP_0603LF-10UF,4V,20%,X6S,E15A!!!F2625!A!!!!
S!GND!C5D13!2!@baseboard_fab2_lib.baseboard_fab2(sch_1):page42_i91@mstr_discrete.cap(chips)!CAP_0603LF-10UF,4V,20%,X6S,E15A!!!F2625!B!!!!
S!PVSA_CPU1!C2D9!1!@baseboard_fab2_lib.baseboard_fab2(sch_1):page76_i43@mstr_discrete.cap(chips)!CAP_0603LF-10UF,4V,20%,X6S,E15A!!!F2672!A!!!!
S!GND!C2D9!2!@baseboard_fab2_lib.baseboard_fab2(sch_1):page76_i43@mstr_discrete.cap(chips)!CAP_0603LF-10UF,4V,20%,X6S,E15A!!!F2672!B!!!!
S!PVSA_CPU1!C2D11!1!@baseboard_fab2_lib.baseboard_fab2(sch_1):page76_i42@mstr_discrete.cap(chips)!CAP_0603LF-10UF,4V,20%,X6S,E15A!!!F2670!A!!!!
S!GND!C2D11!2!@baseboard_fab2_lib.baseboard_fab2(sch_1):page76_i42@mstr_discrete.cap(chips)!CAP_0603LF-10UF,4V,20%,X6S,E15A!!!F2670!B!!!!
S!PVSA_CPU1!C2D10!1!@baseboard_fab2_lib.baseboard_fab2(sch_1):page76_i37@mstr_discrete.cap(chips)!CAP_0603LF-10UF,4V,20%,X6S,E15A!!!F2671!A!!!!
S!GND!C2D10!2!@baseboard_fab2_lib.baseboard_fab2(sch_1):page76_i37@mstr_discrete.cap(chips)!CAP_0603LF-10UF,4V,20%,X6S,E15A!!!F2671!B!!!!
S!PVSA_CPU1!C2D8!1!@baseboard_fab2_lib.baseboard_fab2(sch_1):page76_i33@mstr_discrete.cap(chips)!CAP_0603LF-10UF,4V,20%,X6S,E15A!!!F2673!A!!!!
S!GND!C2D8!2!@baseboard_fab2_lib.baseboard_fab2(sch_1):page76_i33@mstr_discrete.cap(chips)!CAP_0603LF-10UF,4V,20%,X6S,E15A!!!F2673!B!!!!
S!P1V8_MCP_CPU1!C3D3!1!@baseboard_fab2_lib.baseboard_fab2(sch_1):page72_i25@mstr_discrete.cap(chips)!CAP_0603LF-10UF,4V,20%,X6S,E15A!!!F2656!A!!!!
S!GND!C3D3!2!@baseboard_fab2_lib.baseboard_fab2(sch_1):page72_i25@mstr_discrete.cap(chips)!CAP_0603LF-10UF,4V,20%,X6S,E15A!!!F2656!B!!!!
S!P1V8_MCP_CPU0!C6D1!1!@baseboard_fab2_lib.baseboard_fab2(sch_1):page38_i19@mstr_discrete.cap(chips)!CAP_0603LF-10UF,4V,20%,X6S,E15A!!!F2614!A!!!!
S!GND!C6D1!2!@baseboard_fab2_lib.baseboard_fab2(sch_1):page38_i19@mstr_discrete.cap(chips)!CAP_0603LF-10UF,4V,20%,X6S,E15A!!!F2614!B!!!!
S!P5V_HDD_SATA!C9B1!1!@baseboard_fab2_lib.baseboard_fab2(sch_1):page172_i39@mstr_discrete.cap(chips)!CAP_0805-10UF,16V,10%,X6S,C953A!!!F2483!A!!!!
S!GND!C9B1!2!@baseboard_fab2_lib.baseboard_fab2(sch_1):page172_i39@mstr_discrete.cap(chips)!CAP_0805-10UF,16V,10%,X6S,C953A!!!F2483!B!!!!
S!P12V_HDD_SATA!C9B2!1!@baseboard_fab2_lib.baseboard_fab2(sch_1):page172_i36@mstr_discrete.cap(chips)!CAP_0805-10UF,16V,10%,X6S,C953A!!!F2482!A!!!!
S!GND!C9B2!2!@baseboard_fab2_lib.baseboard_fab2(sch_1):page172_i36@mstr_discrete.cap(chips)!CAP_0805-10UF,16V,10%,X6S,C953A!!!F2482!B!!!!
S!P3V3_STBY_MNG!C2T22!1!@baseboard_fab2_lib.baseboard_fab2(sch_1):page101_i113@mstr_discrete.cap(chips)!CAP_0805-10UF,16V,10%,X6S,C953A!!!F2548!A!!!!
S!GND!C2T22!2!@baseboard_fab2_lib.baseboard_fab2(sch_1):page101_i113@mstr_discrete.cap(chips)!CAP_0805-10UF,16V,10%,X6S,C953A!!!F2548!B!!!!
S!VR_FET_SW_P12V_STBY_PVPP_ABC!C7F5!1!@baseboard_fab2_lib.baseboard_fab2(sch_1):page231_i209@mstr_discrete.cap(chips)!CAP_0805-10UF,16V,10%,X6S,C953A!!!F2486!A!!!!
S!GND!C7F5!2!@baseboard_fab2_lib.baseboard_fab2(sch_1):page231_i209@mstr_discrete.cap(chips)!CAP_0805-10UF,16V,10%,X6S,C953A!!!F2486!B!!!!
S!VR_FET_SW_P12V_STBY_PVPP_ABC!C3T8!1!@baseboard_fab2_lib.baseboard_fab2(sch_1):page231_i210@mstr_discrete.cap(chips)!CAP_0805-10UF,16V,10%,X6S,C953A!!!F2527!A!!!!
S!GND!C3T8!2!@baseboard_fab2_lib.baseboard_fab2(sch_1):page231_i210@mstr_discrete.cap(chips)!CAP_0805-10UF,16V,10%,X6S,C953A!!!F2527!B!!!!
S!VR_FET_SW_P12V_STBY_PVPP_ABC!C3T14!1!@baseboard_fab2_lib.baseboard_fab2(sch_1):page231_i211@mstr_discrete.cap(chips)!CAP_0805-10UF,16V,10%,X6S,C953A!!!F2525!A!!!!
S!GND!C3T14!2!@baseboard_fab2_lib.baseboard_fab2(sch_1):page231_i211@mstr_discrete.cap(chips)!CAP_0805-10UF,16V,10%,X6S,C953A!!!F2525!B!!!!
S!VR_FET_SW_P12V_STBY_PVPP_ABC!C3T12!1!@baseboard_fab2_lib.baseboard_fab2(sch_1):page231_i215@mstr_discrete.cap(chips)!CAP_0805-10UF,16V,10%,X6S,C953A!!!F2526!A!!!!
S!GND!C3T12!2!@baseboard_fab2_lib.baseboard_fab2(sch_1):page231_i215@mstr_discrete.cap(chips)!CAP_0805-10UF,16V,10%,X6S,C953A!!!F2526!B!!!!
S!VR_FET_SW_P12V_STBY_PVPP_DEF!C3M8!1!@baseboard_fab2_lib.baseboard_fab2(sch_1):page232_i259@mstr_discrete.cap(chips)!CAP_0805-10UF,16V,10%,X6S,C953A!!!F2533!A!!!!
S!GND!C3M8!2!@baseboard_fab2_lib.baseboard_fab2(sch_1):page232_i259@mstr_discrete.cap(chips)!CAP_0805-10UF,16V,10%,X6S,C953A!!!F2533!B!!!!
S!VR_FET_SW_P12V_STBY_PVPP_DEF!C3M15!1!@baseboard_fab2_lib.baseboard_fab2(sch_1):page232_i260@mstr_discrete.cap(chips)!CAP_0805-10UF,16V,10%,X6S,C953A!!!F2532!A!!!!
S!GND!C3M15!2!@baseboard_fab2_lib.baseboard_fab2(sch_1):page232_i260@mstr_discrete.cap(chips)!CAP_0805-10UF,16V,10%,X6S,C953A!!!F2532!B!!!!
S!VR_FET_SW_P12V_STBY_PVPP_DEF!C3M16!1!@baseboard_fab2_lib.baseboard_fab2(sch_1):page232_i261@mstr_discrete.cap(chips)!CAP_0805-10UF,16V,10%,X6S,C953A!!!F2531!A!!!!
S!GND!C3M16!2!@baseboard_fab2_lib.baseboard_fab2(sch_1):page232_i261@mstr_discrete.cap(chips)!CAP_0805-10UF,16V,10%,X6S,C953A!!!F2531!B!!!!
S!VR_FET_SW_P12V_STBY_PVPP_DEF!C7B5!1!@baseboard_fab2_lib.baseboard_fab2(sch_1):page232_i262@mstr_discrete.cap(chips)!CAP_0805-10UF,16V,10%,X6S,C953A!!!F2489!A!!!!
S!GND!C7B5!2!@baseboard_fab2_lib.baseboard_fab2(sch_1):page232_i262@mstr_discrete.cap(chips)!CAP_0805-10UF,16V,10%,X6S,C953A!!!F2489!B!!!!
S!VR_FET_SW_P12V_STBY_PVPP_GHJ!C6U4!1!@baseboard_fab2_lib.baseboard_fab2(sch_1):page233_i248@mstr_discrete.cap(chips)!CAP_0805-10UF,16V,10%,X6S,C953A!!!F2492!A!!!!
S!GND!C6U4!2!@baseboard_fab2_lib.baseboard_fab2(sch_1):page233_i248@mstr_discrete.cap(chips)!CAP_0805-10UF,16V,10%,X6S,C953A!!!F2492!B!!!!
S!VR_FET_SW_P12V_STBY_PVPP_GHJ!C4G2!1!@baseboard_fab2_lib.baseboard_fab2(sch_1):page233_i253@mstr_discrete.cap(chips)!CAP_0805-10UF,16V,10%,X6S,C953A!!!F2517!A!!!!
S!GND!C4G2!2!@baseboard_fab2_lib.baseboard_fab2(sch_1):page233_i253@mstr_discrete.cap(chips)!CAP_0805-10UF,16V,10%,X6S,C953A!!!F2517!B!!!!
S!VR_FET_SW_P12V_STBY_PVPP_GHJ!C6U7!1!@baseboard_fab2_lib.baseboard_fab2(sch_1):page233_i254@mstr_discrete.cap(chips)!CAP_0805-10UF,16V,10%,X6S,C953A!!!F2491!A!!!!
S!GND!C6U7!2!@baseboard_fab2_lib.baseboard_fab2(sch_1):page233_i254@mstr_discrete.cap(chips)!CAP_0805-10UF,16V,10%,X6S,C953A!!!F2491!B!!!!
S!VR_FET_SW_P12V_STBY_PVPP_GHJ!C6U8!1!@baseboard_fab2_lib.baseboard_fab2(sch_1):page233_i255@mstr_discrete.cap(chips)!CAP_0805-10UF,16V,10%,X6S,C953A!!!F2490!A!!!!
S!GND!C6U8!2!@baseboard_fab2_lib.baseboard_fab2(sch_1):page233_i255@mstr_discrete.cap(chips)!CAP_0805-10UF,16V,10%,X6S,C953A!!!F2490!B!!!!
S!VR_FET_SW_P12V_STBY_PVPP_KLM!C6L10!1!@baseboard_fab2_lib.baseboard_fab2(sch_1):page234_i202@mstr_discrete.cap(chips)!CAP_0805-10UF,16V,10%,X6S,C953A!!!F2516!A!!!!
S!GND!C6L10!2!@baseboard_fab2_lib.baseboard_fab2(sch_1):page234_i202@mstr_discrete.cap(chips)!CAP_0805-10UF,16V,10%,X6S,C953A!!!F2516!B!!!!
S!VR_FET_SW_P12V_STBY_PVPP_KLM!C6M3!1!@baseboard_fab2_lib.baseboard_fab2(sch_1):page234_i203@mstr_discrete.cap(chips)!CAP_0805-10UF,16V,10%,X6S,C953A!!!F2515!A!!!!
S!GND!C6M3!2!@baseboard_fab2_lib.baseboard_fab2(sch_1):page234_i203@mstr_discrete.cap(chips)!CAP_0805-10UF,16V,10%,X6S,C953A!!!F2515!B!!!!
S!VR_FET_SW_P12V_STBY_PVPP_KLM!C6M5!1!@baseboard_fab2_lib.baseboard_fab2(sch_1):page234_i204@mstr_discrete.cap(chips)!CAP_0805-10UF,16V,10%,X6S,C953A!!!F2514!A!!!!
S!GND!C6M5!2!@baseboard_fab2_lib.baseboard_fab2(sch_1):page234_i204@mstr_discrete.cap(chips)!CAP_0805-10UF,16V,10%,X6S,C953A!!!F2514!B!!!!
S!VR_FET_SW_P12V_STBY_PVPP_KLM!C4A19!1!@baseboard_fab2_lib.baseboard_fab2(sch_1):page234_i205@mstr_discrete.cap(chips)!CAP_0805-10UF,16V,10%,X6S,C953A!!!F2518!A!!!!
S!GND!C4A19!2!@baseboard_fab2_lib.baseboard_fab2(sch_1):page234_i205@mstr_discrete.cap(chips)!CAP_0805-10UF,16V,10%,X6S,C953A!!!F2518!B!!!!
S!P12V_FAN!C1B18!1!@baseboard_fab2_lib.baseboard_fab2(sch_1):page198_i61@mstr_discrete.cap(chips)!CAP_0805-10UF,16V,10%,X6S,C953A!!!F2556!A!!!!
S!GND!C1B18!2!@baseboard_fab2_lib.baseboard_fab2(sch_1):page198_i61@mstr_discrete.cap(chips)!CAP_0805-10UF,16V,10%,X6S,C953A!!!F2556!B!!!!
S!P12V_STBY!C9M10!1!@baseboard_fab2_lib.baseboard_fab2(sch_1):page198_i74@mstr_discrete.cap(chips)!CAP_0805-10UF,16V,10%,X6S,C953A!!!F2474!A!!!!
S!GND!C9M10!2!@baseboard_fab2_lib.baseboard_fab2(sch_1):page198_i74@mstr_discrete.cap(chips)!CAP_0805-10UF,16V,10%,X6S,C953A!!!F2474!B!!!!
S!VR_FET_SW_P12V_STBY_PVDDQ_DEF!C3L7!1!@baseboard_fab2_lib.baseboard_fab2(sch_1):page236_i31@mstr_discrete.cap(chips)!CAP_0805-10UF,16V,10%,X6S,C953A!!!F2543!A!!!!
S!GND!C3L7!2!@baseboard_fab2_lib.baseboard_fab2(sch_1):page236_i31@mstr_discrete.cap(chips)!CAP_0805-10UF,16V,10%,X6S,C953A!!!F2543!B!!!!
S!VR_FET_SW_P12V_STBY_PVDDQ_DEF!C3L11!1!@baseboard_fab2_lib.baseboard_fab2(sch_1):page236_i24@mstr_discrete.cap(chips)!CAP_0805-10UF,16V,10%,X6S,C953A!!!F2539!A!!!!
S!GND!C3L11!2!@baseboard_fab2_lib.baseboard_fab2(sch_1):page236_i24@mstr_discrete.cap(chips)!CAP_0805-10UF,16V,10%,X6S,C953A!!!F2539!B!!!!
S!VR_FET_SW_P12V_STBY_PVDDQ_DEF!C3L9!1!@baseboard_fab2_lib.baseboard_fab2(sch_1):page236_i29@mstr_discrete.cap(chips)!CAP_0805-10UF,16V,10%,X6S,C953A!!!F2541!A!!!!
S!GND!C3L9!2!@baseboard_fab2_lib.baseboard_fab2(sch_1):page236_i29@mstr_discrete.cap(chips)!CAP_0805-10UF,16V,10%,X6S,C953A!!!F2541!B!!!!
S!VR_FET_SW_P12V_STBY_PVDDQ_DEF!C3L8!1!@baseboard_fab2_lib.baseboard_fab2(sch_1):page236_i26@mstr_discrete.cap(chips)!CAP_0805-10UF,16V,10%,X6S,C953A!!!F2542!A!!!!
S!GND!C3L8!2!@baseboard_fab2_lib.baseboard_fab2(sch_1):page236_i26@mstr_discrete.cap(chips)!CAP_0805-10UF,16V,10%,X6S,C953A!!!F2542!B!!!!
S!VR_FET_SW_P12V_STBY_PVDDQ_DEF!C3L10!1!@baseboard_fab2_lib.baseboard_fab2(sch_1):page236_i32@mstr_discrete.cap(chips)!CAP_0805-10UF,16V,10%,X6S,C953A!!!F2540!A!!!!
S!GND!C3L10!2!@baseboard_fab2_lib.baseboard_fab2(sch_1):page236_i32@mstr_discrete.cap(chips)!CAP_0805-10UF,16V,10%,X6S,C953A!!!F2540!B!!!!
S!VR_FET_SW_P12V_STBY_PVDDQ_DEF!C3L12!1!@baseboard_fab2_lib.baseboard_fab2(sch_1):page236_i23@mstr_discrete.cap(chips)!CAP_0805-10UF,16V,10%,X6S,C953A!!!F2538!A!!!!
S!GND!C3L12!2!@baseboard_fab2_lib.baseboard_fab2(sch_1):page236_i23@mstr_discrete.cap(chips)!CAP_0805-10UF,16V,10%,X6S,C953A!!!F2538!B!!!!
S!VR_FET_SW_P12V_STBY_PVCCIO_CPU0!C3N34!1!@baseboard_fab2_lib.baseboard_fab2(sch_1):page212_i43@mstr_discrete.cap(chips)!CAP_0805-10UF,16V,10%,X6S,C953A!!!F2529!A!!!!
S!GND!C3N34!2!@baseboard_fab2_lib.baseboard_fab2(sch_1):page212_i43@mstr_discrete.cap(chips)!CAP_0805-10UF,16V,10%,X6S,C953A!!!F2529!B!!!!
S!VR_FET_SW_P12V_STBY_PVCCIO_CPU0!C3N36!1!@baseboard_fab2_lib.baseboard_fab2(sch_1):page212_i40@mstr_discrete.cap(chips)!CAP_0805-10UF,16V,10%,X6S,C953A!!!F2528!A!!!!
S!GND!C3N36!2!@baseboard_fab2_lib.baseboard_fab2(sch_1):page212_i40@mstr_discrete.cap(chips)!CAP_0805-10UF,16V,10%,X6S,C953A!!!F2528!B!!!!
S!VR_FET_SW_P12V_STBY_PVCCIN_CPU0!C6R8!1!@baseboard_fab2_lib.baseboard_fab2(sch_1):page214_i83@mstr_discrete.cap(chips)!CAP_0805-10UF,16V,10%,X6S,C953A!!!F2497!A!!!!
S!GND!C6R8!2!@baseboard_fab2_lib.baseboard_fab2(sch_1):page214_i83@mstr_discrete.cap(chips)!CAP_0805-10UF,16V,10%,X6S,C953A!!!F2497!B!!!!
S!VR_FET_SW_P12V_STBY_PVCCIN_CPU0!C6R10!1!@baseboard_fab2_lib.baseboard_fab2(sch_1):page214_i81@mstr_discrete.cap(chips)!CAP_0805-10UF,16V,10%,X6S,C953A!!!F2496!A!!!!
S!GND!C6R10!2!@baseboard_fab2_lib.baseboard_fab2(sch_1):page214_i81@mstr_discrete.cap(chips)!CAP_0805-10UF,16V,10%,X6S,C953A!!!F2496!B!!!!
S!VR_FET_SW_P12V_STBY_PVCCIN_CPU0!C6R14!1!@baseboard_fab2_lib.baseboard_fab2(sch_1):page214_i80@mstr_discrete.cap(chips)!CAP_0805-10UF,16V,10%,X6S,C953A!!!F2493!A!!!!
S!GND!C6R14!2!@baseboard_fab2_lib.baseboard_fab2(sch_1):page214_i80@mstr_discrete.cap(chips)!CAP_0805-10UF,16V,10%,X6S,C953A!!!F2493!B!!!!
S!VR_FET_SW_P12V_STBY_PVCCIN_CPU0!C6P24!1!@baseboard_fab2_lib.baseboard_fab2(sch_1):page203_i1@mstr_discrete.cap(chips)!CAP_0805-10UF,16V,10%,X6S,C953A!!!F2500!A!!!!
S!GND!C6P24!2!@baseboard_fab2_lib.baseboard_fab2(sch_1):page203_i1@mstr_discrete.cap(chips)!CAP_0805-10UF,16V,10%,X6S,C953A!!!F2500!B!!!!
S!VR_FET_SW_P12V_STBY_PVCCIN_CPU0!C6R6!1!@baseboard_fab2_lib.baseboard_fab2(sch_1):page203_i2@mstr_discrete.cap(chips)!CAP_0805-10UF,16V,10%,X6S,C953A!!!F2498!A!!!!
S!GND!C6R6!2!@baseboard_fab2_lib.baseboard_fab2(sch_1):page203_i2@mstr_discrete.cap(chips)!CAP_0805-10UF,16V,10%,X6S,C953A!!!F2498!B!!!!
S!VR_FET_SW_P12V_STBY_PVCCIN_CPU0!C6P19!1!@baseboard_fab2_lib.baseboard_fab2(sch_1):page203_i54@mstr_discrete.cap(chips)!CAP_0805-10UF,16V,10%,X6S,C953A!!!F2503!A!!!!
S!GND!C6P19!2!@baseboard_fab2_lib.baseboard_fab2(sch_1):page203_i54@mstr_discrete.cap(chips)!CAP_0805-10UF,16V,10%,X6S,C953A!!!F2503!B!!!!
S!VR_FET_SW_P12V_STBY_PVCCIN_CPU0!C6P7!1!@baseboard_fab2_lib.baseboard_fab2(sch_1):page203_i59@mstr_discrete.cap(chips)!CAP_0805-10UF,16V,10%,X6S,C953A!!!F2507!A!!!!
S!GND!C6P7!2!@baseboard_fab2_lib.baseboard_fab2(sch_1):page203_i59@mstr_discrete.cap(chips)!CAP_0805-10UF,16V,10%,X6S,C953A!!!F2507!B!!!!
S!VR_FET_SW_P12V_STBY_PVCCIN_CPU0!C6P15!1!@baseboard_fab2_lib.baseboard_fab2(sch_1):page203_i58@mstr_discrete.cap(chips)!CAP_0805-10UF,16V,10%,X6S,C953A!!!F2505!A!!!!
S!GND!C6P15!2!@baseboard_fab2_lib.baseboard_fab2(sch_1):page203_i58@mstr_discrete.cap(chips)!CAP_0805-10UF,16V,10%,X6S,C953A!!!F2505!B!!!!
S!VR_FET_SW_P12V_STBY_PVCCIN_CPU0!C6P20!1!@baseboard_fab2_lib.baseboard_fab2(sch_1):page203_i57@mstr_discrete.cap(chips)!CAP_0805-10UF,16V,10%,X6S,C953A!!!F2502!A!!!!
S!GND!C6P20!2!@baseboard_fab2_lib.baseboard_fab2(sch_1):page203_i57@mstr_discrete.cap(chips)!CAP_0805-10UF,16V,10%,X6S,C953A!!!F2502!B!!!!
S!P12V_FAN!C1E21!1!@baseboard_fab2_lib.baseboard_fab2(sch_1):page161_i3@mstr_discrete.cap(chips)!CAP_0805-10UF,16V,10%,X6S,C953A!!!F2553!A!!!!
S!GND!C1E21!2!@baseboard_fab2_lib.baseboard_fab2(sch_1):page161_i3@mstr_discrete.cap(chips)!CAP_0805-10UF,16V,10%,X6S,C953A!!!F2553!B!!!!
S!P12V_FAN!C9M4!1!@baseboard_fab2_lib.baseboard_fab2(sch_1):page161_i27@mstr_discrete.cap(chips)!CAP_0805-10UF,16V,10%,X6S,C953A!!!F2475!A!!!!
S!GND!C9M4!2!@baseboard_fab2_lib.baseboard_fab2(sch_1):page161_i27@mstr_discrete.cap(chips)!CAP_0805-10UF,16V,10%,X6S,C953A!!!F2475!B!!!!
S!P12V_STBY!C7E6!1!@baseboard_fab2_lib.baseboard_fab2(sch_1):page198_i53@mstr_discrete.cap(chips)!CAP_0805-10UF,16V,10%,X6S,C953A!!!F2488!A!!!!
S!GND!C7E6!2!@baseboard_fab2_lib.baseboard_fab2(sch_1):page198_i53@mstr_discrete.cap(chips)!CAP_0805-10UF,16V,10%,X6S,C953A!!!F2488!B!!!!
S!P12V!C7E8!1!@baseboard_fab2_lib.baseboard_fab2(sch_1):page198_i50@mstr_discrete.cap(chips)!CAP_0805-10UF,16V,10%,X6S,C953A!!!F2487!A!!!!
S!GND!C7E8!2!@baseboard_fab2_lib.baseboard_fab2(sch_1):page198_i50@mstr_discrete.cap(chips)!CAP_0805-10UF,16V,10%,X6S,C953A!!!F2487!B!!!!
S!P3V3_STBY!C2U1!1!@baseboard_fab2_lib.baseboard_fab2(sch_1):page198_i44@mstr_discrete.cap(chips)!CAP_0805-10UF,16V,10%,X6S,C953A!!!F2547!A!!!!
S!GND!C2U1!2!@baseboard_fab2_lib.baseboard_fab2(sch_1):page198_i44@mstr_discrete.cap(chips)!CAP_0805-10UF,16V,10%,X6S,C953A!!!F2547!B!!!!
S!P3V3!C2U2!1!@baseboard_fab2_lib.baseboard_fab2(sch_1):page198_i47@mstr_discrete.cap(chips)!CAP_0805-10UF,16V,10%,X6S,C953A!!!F2546!A!!!!
S!GND!C2U2!2!@baseboard_fab2_lib.baseboard_fab2(sch_1):page198_i47@mstr_discrete.cap(chips)!CAP_0805-10UF,16V,10%,X6S,C953A!!!F2546!B!!!!
S!P5V_STBY!C8B12!1!@baseboard_fab2_lib.baseboard_fab2(sch_1):page198_i38@mstr_discrete.cap(chips)!CAP_0805-10UF,16V,10%,X6S,C953A!!!F2484!A!!!!
S!GND!C8B12!2!@baseboard_fab2_lib.baseboard_fab2(sch_1):page198_i38@mstr_discrete.cap(chips)!CAP_0805-10UF,16V,10%,X6S,C953A!!!F2484!B!!!!
S!P5V!C8B6!1!@baseboard_fab2_lib.baseboard_fab2(sch_1):page198_i40@mstr_discrete.cap(chips)!CAP_0805-10UF,16V,10%,X6S,C953A!!!F2485!A!!!!
S!GND!C8B6!2!@baseboard_fab2_lib.baseboard_fab2(sch_1):page198_i40@mstr_discrete.cap(chips)!CAP_0805-10UF,16V,10%,X6S,C953A!!!F2485!B!!!!
S!P12V_PSU!C9R5!1!@baseboard_fab2_lib.baseboard_fab2(sch_1):page195_i31@mstr_discrete.cap(chips)!CAP_0805-10UF,16V,10%,X6S,C953A!!!F2458!A!!!!
S!GND!C9R5!2!@baseboard_fab2_lib.baseboard_fab2(sch_1):page195_i31@mstr_discrete.cap(chips)!CAP_0805-10UF,16V,10%,X6S,C953A!!!F2458!B!!!!
S!P12V_PSU!C1E12!1!@baseboard_fab2_lib.baseboard_fab2(sch_1):page195_i32@mstr_discrete.cap(chips)!CAP_0805-10UF,16V,10%,X6S,C953A!!!F2555!A!!!!
S!GND!C1E12!2!@baseboard_fab2_lib.baseboard_fab2(sch_1):page195_i32@mstr_discrete.cap(chips)!CAP_0805-10UF,16V,10%,X6S,C953A!!!F2555!B!!!!
S!VR_FET_SW_P12V_STBY_PVCCIO_CPU0!C3N33!1!@baseboard_fab2_lib.baseboard_fab2(sch_1):page212_i41@mstr_discrete.cap(chips)!CAP_0805-10UF,16V,10%,X6S,C953A!!!F2530!A!!!!
S!GND!C3N33!2!@baseboard_fab2_lib.baseboard_fab2(sch_1):page212_i41@mstr_discrete.cap(chips)!CAP_0805-10UF,16V,10%,X6S,C953A!!!F2530!B!!!!
S!VR_FET_SW_P12V_STBY_PVCCIN_CPU1!C9N27!1!@baseboard_fab2_lib.baseboard_fab2(sch_1):page209_i5@mstr_discrete.cap(chips)!CAP_0805-10UF,16V,10%,X6S,C953A!!!F2462!A!!!!
S!GND!C9N27!2!@baseboard_fab2_lib.baseboard_fab2(sch_1):page209_i5@mstr_discrete.cap(chips)!CAP_0805-10UF,16V,10%,X6S,C953A!!!F2462!B!!!!
S!VR_FET_SW_P12V_STBY_PVCCIN_CPU1!C9N26!1!@baseboard_fab2_lib.baseboard_fab2(sch_1):page209_i7@mstr_discrete.cap(chips)!CAP_0805-10UF,16V,10%,X6S,C953A!!!F2463!A!!!!
S!GND!C9N26!2!@baseboard_fab2_lib.baseboard_fab2(sch_1):page209_i7@mstr_discrete.cap(chips)!CAP_0805-10UF,16V,10%,X6S,C953A!!!F2463!B!!!!
S!VR_FET_SW_P12V_STBY_PVCCIN_CPU1!C9N25!1!@baseboard_fab2_lib.baseboard_fab2(sch_1):page209_i8@mstr_discrete.cap(chips)!CAP_0805-10UF,16V,10%,X6S,C953A!!!F2464!A!!!!
S!GND!C9N25!2!@baseboard_fab2_lib.baseboard_fab2(sch_1):page209_i8@mstr_discrete.cap(chips)!CAP_0805-10UF,16V,10%,X6S,C953A!!!F2464!B!!!!
S!P12V_STBY!C1M27!1!@baseboard_fab2_lib.baseboard_fab2(sch_1):page186_i3@mstr_discrete.cap(chips)!CAP_0805-10UF,16V,10%,X6S,C953A!!!F2551!A!!!!
S!GND!C1M27!2!@baseboard_fab2_lib.baseboard_fab2(sch_1):page186_i3@mstr_discrete.cap(chips)!CAP_0805-10UF,16V,10%,X6S,C953A!!!F2551!B!!!!
S!P12V_STBY!C1M26!1!@baseboard_fab2_lib.baseboard_fab2(sch_1):page186_i6@mstr_discrete.cap(chips)!CAP_0805-10UF,16V,10%,X6S,C953A!!!F2552!A!!!!
S!GND!C1M26!2!@baseboard_fab2_lib.baseboard_fab2(sch_1):page186_i6@mstr_discrete.cap(chips)!CAP_0805-10UF,16V,10%,X6S,C953A!!!F2552!B!!!!
S!P1V538_BMC_STBY!C1U12!1!@baseboard_fab2_lib.baseboard_fab2(sch_1):page149_i88@mstr_discrete.cap(chips)!CAP_0805-10UF,16V,10%,X6S,C953A!!!F2549!A!!!!
S!GND!C1U12!2!@baseboard_fab2_lib.baseboard_fab2(sch_1):page149_i88@mstr_discrete.cap(chips)!CAP_0805-10UF,16V,10%,X6S,C953A!!!F2549!B!!!!
S!P1V26_BMC_STBY!C1U1!1!@baseboard_fab2_lib.baseboard_fab2(sch_1):page149_i84@mstr_discrete.cap(chips)!CAP_0805-10UF,16V,10%,X6S,C953A!!!F2550!A!!!!
S!GND!C1U1!2!@baseboard_fab2_lib.baseboard_fab2(sch_1):page149_i84@mstr_discrete.cap(chips)!CAP_0805-10UF,16V,10%,X6S,C953A!!!F2550!B!!!!
S!VR_FET_SW_P12V_STBY_PVCCIN_CPU0!C6P13!1!@baseboard_fab2_lib.baseboard_fab2(sch_1):page202_i38@mstr_discrete.cap(chips)!CAP_0805-10UF,16V,10%,X6S,C953A!!!F2506!A!!!!
S!GND!C6P13!2!@baseboard_fab2_lib.baseboard_fab2(sch_1):page202_i38@mstr_discrete.cap(chips)!CAP_0805-10UF,16V,10%,X6S,C953A!!!F2506!B!!!!
S!VR_FET_SW_P12V_STBY_PVCCIN_CPU0!C6P17!1!@baseboard_fab2_lib.baseboard_fab2(sch_1):page204_i38@mstr_discrete.cap(chips)!CAP_0805-10UF,16V,10%,X6S,C953A!!!F2504!A!!!!
S!GND!C6P17!2!@baseboard_fab2_lib.baseboard_fab2(sch_1):page204_i38@mstr_discrete.cap(chips)!CAP_0805-10UF,16V,10%,X6S,C953A!!!F2504!B!!!!
S!VR_FET_SW_P12V_STBY_PVCCIN_CPU0!C6N8!1!@baseboard_fab2_lib.baseboard_fab2(sch_1):page202_i51@mstr_discrete.cap(chips)!CAP_0805-10UF,16V,10%,X6S,C953A!!!F2510!A!!!!
S!GND!C6N8!2!@baseboard_fab2_lib.baseboard_fab2(sch_1):page202_i51@mstr_discrete.cap(chips)!CAP_0805-10UF,16V,10%,X6S,C953A!!!F2510!B!!!!
S!VR_FET_SW_P12V_STBY_PVCCIN_CPU0!C6R13!1!@baseboard_fab2_lib.baseboard_fab2(sch_1):page202_i42@mstr_discrete.cap(chips)!CAP_0805-10UF,16V,10%,X6S,C953A!!!F2494!A!!!!
S!GND!C6R13!2!@baseboard_fab2_lib.baseboard_fab2(sch_1):page202_i42@mstr_discrete.cap(chips)!CAP_0805-10UF,16V,10%,X6S,C953A!!!F2494!B!!!!
S!VR_FET_SW_P12V_STBY_PVCCIN_CPU0!C6P22!1!@baseboard_fab2_lib.baseboard_fab2(sch_1):page202_i49@mstr_discrete.cap(chips)!CAP_0805-10UF,16V,10%,X6S,C953A!!!F2501!A!!!!
S!GND!C6P22!2!@baseboard_fab2_lib.baseboard_fab2(sch_1):page202_i49@mstr_discrete.cap(chips)!CAP_0805-10UF,16V,10%,X6S,C953A!!!F2501!B!!!!
S!VR_FET_SW_P12V_STBY_PVCCIN_CPU0!C6R4!1!@baseboard_fab2_lib.baseboard_fab2(sch_1):page202_i48@mstr_discrete.cap(chips)!CAP_0805-10UF,16V,10%,X6S,C953A!!!F2499!A!!!!
S!GND!C6R4!2!@baseboard_fab2_lib.baseboard_fab2(sch_1):page202_i48@mstr_discrete.cap(chips)!CAP_0805-10UF,16V,10%,X6S,C953A!!!F2499!B!!!!
S!VR_FET_SW_P12V_STBY_PVCCIN_CPU0!C6R11!1!@baseboard_fab2_lib.baseboard_fab2(sch_1):page202_i37@mstr_discrete.cap(chips)!CAP_0805-10UF,16V,10%,X6S,C953A!!!F2495!A!!!!
S!GND!C6R11!2!@baseboard_fab2_lib.baseboard_fab2(sch_1):page202_i37@mstr_discrete.cap(chips)!CAP_0805-10UF,16V,10%,X6S,C953A!!!F2495!B!!!!
S!VR_FET_SW_P12V_STBY_PVDDQ_ABC!C3U2!1!@baseboard_fab2_lib.baseboard_fab2(sch_1):page216_i45@mstr_discrete.cap(chips)!CAP_0805-10UF,16V,10%,X6S,C953A!!!F2524!A!!!!
S!GND!C3U2!2!@baseboard_fab2_lib.baseboard_fab2(sch_1):page216_i45@mstr_discrete.cap(chips)!CAP_0805-10UF,16V,10%,X6S,C953A!!!F2524!B!!!!
S!VR_FET_SW_P12V_STBY_PVDDQ_ABC!C3U6!1!@baseboard_fab2_lib.baseboard_fab2(sch_1):page216_i84@mstr_discrete.cap(chips)!CAP_0805-10UF,16V,10%,X6S,C953A!!!F2521!A!!!!
S!GND!C3U6!2!@baseboard_fab2_lib.baseboard_fab2(sch_1):page216_i84@mstr_discrete.cap(chips)!CAP_0805-10UF,16V,10%,X6S,C953A!!!F2521!B!!!!
S!VR_FET_SW_P12V_STBY_PVDDQ_ABC!C3U3!1!@baseboard_fab2_lib.baseboard_fab2(sch_1):page216_i46@mstr_discrete.cap(chips)!CAP_0805-10UF,16V,10%,X6S,C953A!!!F2523!A!!!!
S!GND!C3U3!2!@baseboard_fab2_lib.baseboard_fab2(sch_1):page216_i46@mstr_discrete.cap(chips)!CAP_0805-10UF,16V,10%,X6S,C953A!!!F2523!B!!!!
S!VR_FET_SW_P12V_STBY_PVDDQ_ABC!C3U7!1!@baseboard_fab2_lib.baseboard_fab2(sch_1):page216_i81@mstr_discrete.cap(chips)!CAP_0805-10UF,16V,10%,X6S,C953A!!!F2520!A!!!!
S!GND!C3U7!2!@baseboard_fab2_lib.baseboard_fab2(sch_1):page216_i81@mstr_discrete.cap(chips)!CAP_0805-10UF,16V,10%,X6S,C953A!!!F2520!B!!!!
S!VR_FET_SW_P12V_STBY_PVDDQ_ABC!C3U4!1!@baseboard_fab2_lib.baseboard_fab2(sch_1):page216_i47@mstr_discrete.cap(chips)!CAP_0805-10UF,16V,10%,X6S,C953A!!!F2522!A!!!!
S!GND!C3U4!2!@baseboard_fab2_lib.baseboard_fab2(sch_1):page216_i47@mstr_discrete.cap(chips)!CAP_0805-10UF,16V,10%,X6S,C953A!!!F2522!B!!!!
S!VR_FET_SW_P12V_STBY_PVDDQ_ABC!C3U9!1!@baseboard_fab2_lib.baseboard_fab2(sch_1):page216_i80@mstr_discrete.cap(chips)!CAP_0805-10UF,16V,10%,X6S,C953A!!!F2519!A!!!!
S!GND!C3U9!2!@baseboard_fab2_lib.baseboard_fab2(sch_1):page216_i80@mstr_discrete.cap(chips)!CAP_0805-10UF,16V,10%,X6S,C953A!!!F2519!B!!!!
S!VR_FET_SW_P12V_STBY_PVCCIN_CPU0!C6N6!1!@baseboard_fab2_lib.baseboard_fab2(sch_1):page205_i35@mstr_discrete.cap(chips)!CAP_0805-10UF,16V,10%,X6S,C953A!!!F2511!A!!!!
S!GND!C6N6!2!@baseboard_fab2_lib.baseboard_fab2(sch_1):page205_i35@mstr_discrete.cap(chips)!CAP_0805-10UF,16V,10%,X6S,C953A!!!F2511!B!!!!
S!VR_FET_SW_P12V_STBY_PVCCIN_CPU0!C6N3!1!@baseboard_fab2_lib.baseboard_fab2(sch_1):page205_i34@mstr_discrete.cap(chips)!CAP_0805-10UF,16V,10%,X6S,C953A!!!F2512!A!!!!
S!GND!C6N3!2!@baseboard_fab2_lib.baseboard_fab2(sch_1):page205_i34@mstr_discrete.cap(chips)!CAP_0805-10UF,16V,10%,X6S,C953A!!!F2512!B!!!!
S!VR_FET_SW_P12V_STBY_PVCCIN_CPU0!C6N2!1!@baseboard_fab2_lib.baseboard_fab2(sch_1):page205_i33@mstr_discrete.cap(chips)!CAP_0805-10UF,16V,10%,X6S,C953A!!!F2513!A!!!!
S!GND!C6N2!2!@baseboard_fab2_lib.baseboard_fab2(sch_1):page205_i33@mstr_discrete.cap(chips)!CAP_0805-10UF,16V,10%,X6S,C953A!!!F2513!B!!!!
S!VR_FET_SW_P12V_STBY_PVDDQ_DEF!C3L2!1!@baseboard_fab2_lib.baseboard_fab2(sch_1):page219_i45@mstr_discrete.cap(chips)!CAP_0805-10UF,16V,10%,X6S,C953A!!!F2545!A!!!!
S!GND!C3L2!2!@baseboard_fab2_lib.baseboard_fab2(sch_1):page219_i45@mstr_discrete.cap(chips)!CAP_0805-10UF,16V,10%,X6S,C953A!!!F2545!B!!!!
S!VR_FET_SW_P12V_STBY_PVDDQ_DEF!C3L15!1!@baseboard_fab2_lib.baseboard_fab2(sch_1):page219_i84@mstr_discrete.cap(chips)!CAP_0805-10UF,16V,10%,X6S,C953A!!!F2536!A!!!!
S!GND!C3L15!2!@baseboard_fab2_lib.baseboard_fab2(sch_1):page219_i84@mstr_discrete.cap(chips)!CAP_0805-10UF,16V,10%,X6S,C953A!!!F2536!B!!!!
S!VR_FET_SW_P12V_STBY_PVDDQ_DEF!C3L4!1!@baseboard_fab2_lib.baseboard_fab2(sch_1):page219_i46@mstr_discrete.cap(chips)!CAP_0805-10UF,16V,10%,X6S,C953A!!!F2544!A!!!!
S!GND!C3L4!2!@baseboard_fab2_lib.baseboard_fab2(sch_1):page219_i46@mstr_discrete.cap(chips)!CAP_0805-10UF,16V,10%,X6S,C953A!!!F2544!B!!!!
S!VR_FET_SW_P12V_STBY_PVDDQ_DEF!C3L16!1!@baseboard_fab2_lib.baseboard_fab2(sch_1):page219_i81@mstr_discrete.cap(chips)!CAP_0805-10UF,16V,10%,X6S,C953A!!!F2535!A!!!!
S!GND!C3L16!2!@baseboard_fab2_lib.baseboard_fab2(sch_1):page219_i81@mstr_discrete.cap(chips)!CAP_0805-10UF,16V,10%,X6S,C953A!!!F2535!B!!!!
S!VR_FET_SW_P12V_STBY_PVDDQ_DEF!C3L13!1!@baseboard_fab2_lib.baseboard_fab2(sch_1):page219_i47@mstr_discrete.cap(chips)!CAP_0805-10UF,16V,10%,X6S,C953A!!!F2537!A!!!!
S!GND!C3L13!2!@baseboard_fab2_lib.baseboard_fab2(sch_1):page219_i47@mstr_discrete.cap(chips)!CAP_0805-10UF,16V,10%,X6S,C953A!!!F2537!B!!!!
S!VR_FET_SW_P12V_STBY_PVDDQ_DEF!C3L17!1!@baseboard_fab2_lib.baseboard_fab2(sch_1):page219_i80@mstr_discrete.cap(chips)!CAP_0805-10UF,16V,10%,X6S,C953A!!!F2534!A!!!!
S!GND!C3L17!2!@baseboard_fab2_lib.baseboard_fab2(sch_1):page219_i80@mstr_discrete.cap(chips)!CAP_0805-10UF,16V,10%,X6S,C953A!!!F2534!B!!!!
S!VR_FET_SW_P12V_STBY_PVDDQ_KLM!C9L11!1!@baseboard_fab2_lib.baseboard_fab2(sch_1):page227_i45@mstr_discrete.cap(chips)!CAP_0805-10UF,16V,10%,X6S,C953A!!!F2478!A!!!!
S!GND!C9L11!2!@baseboard_fab2_lib.baseboard_fab2(sch_1):page227_i45@mstr_discrete.cap(chips)!CAP_0805-10UF,16V,10%,X6S,C953A!!!F2478!B!!!!
S!VR_FET_SW_P12V_STBY_PVDDQ_KLM!C9L14!1!@baseboard_fab2_lib.baseboard_fab2(sch_1):page227_i84@mstr_discrete.cap(chips)!CAP_0805-10UF,16V,10%,X6S,C953A!!!F2476!A!!!!
S!GND!C9L14!2!@baseboard_fab2_lib.baseboard_fab2(sch_1):page227_i84@mstr_discrete.cap(chips)!CAP_0805-10UF,16V,10%,X6S,C953A!!!F2476!B!!!!
S!VR_FET_SW_P12V_STBY_PVDDQ_KLM!C9L10!1!@baseboard_fab2_lib.baseboard_fab2(sch_1):page227_i46@mstr_discrete.cap(chips)!CAP_0805-10UF,16V,10%,X6S,C953A!!!F2479!A!!!!
S!GND!C9L10!2!@baseboard_fab2_lib.baseboard_fab2(sch_1):page227_i46@mstr_discrete.cap(chips)!CAP_0805-10UF,16V,10%,X6S,C953A!!!F2479!B!!!!
S!VR_FET_SW_P12V_STBY_PVDDQ_KLM!C9L13!1!@baseboard_fab2_lib.baseboard_fab2(sch_1):page227_i81@mstr_discrete.cap(chips)!CAP_0805-10UF,16V,10%,X6S,C953A!!!F2477!A!!!!
S!GND!C9L13!2!@baseboard_fab2_lib.baseboard_fab2(sch_1):page227_i81@mstr_discrete.cap(chips)!CAP_0805-10UF,16V,10%,X6S,C953A!!!F2477!B!!!!
S!VR_FET_SW_P12V_STBY_PVDDQ_KLM!C9L6!1!@baseboard_fab2_lib.baseboard_fab2(sch_1):page227_i47@mstr_discrete.cap(chips)!CAP_0805-10UF,16V,10%,X6S,C953A!!!F2480!A!!!!
S!GND!C9L6!2!@baseboard_fab2_lib.baseboard_fab2(sch_1):page227_i47@mstr_discrete.cap(chips)!CAP_0805-10UF,16V,10%,X6S,C953A!!!F2480!B!!!!
S!VR_FET_SW_P12V_STBY_PVDDQ_KLM!C9L5!1!@baseboard_fab2_lib.baseboard_fab2(sch_1):page227_i80@mstr_discrete.cap(chips)!CAP_0805-10UF,16V,10%,X6S,C953A!!!F2481!A!!!!
S!GND!C9L5!2!@baseboard_fab2_lib.baseboard_fab2(sch_1):page227_i80@mstr_discrete.cap(chips)!CAP_0805-10UF,16V,10%,X6S,C953A!!!F2481!B!!!!
S!VR_FET_SW_P12V_STBY_PVDDQ_GHJ!C9U6!1!@baseboard_fab2_lib.baseboard_fab2(sch_1):page224_i45@mstr_discrete.cap(chips)!CAP_0805-10UF,16V,10%,X6S,C953A!!!F2449!A!!!!
S!GND!C9U6!2!@baseboard_fab2_lib.baseboard_fab2(sch_1):page224_i45@mstr_discrete.cap(chips)!CAP_0805-10UF,16V,10%,X6S,C953A!!!F2449!B!!!!
S!VR_FET_SW_P12V_STBY_PVDDQ_GHJ!C9T9!1!@baseboard_fab2_lib.baseboard_fab2(sch_1):page224_i84@mstr_discrete.cap(chips)!CAP_0805-10UF,16V,10%,X6S,C953A!!!F2452!A!!!!
S!GND!C9T9!2!@baseboard_fab2_lib.baseboard_fab2(sch_1):page224_i84@mstr_discrete.cap(chips)!CAP_0805-10UF,16V,10%,X6S,C953A!!!F2452!B!!!!
S!VR_FET_SW_P12V_STBY_PVDDQ_GHJ!C9U4!1!@baseboard_fab2_lib.baseboard_fab2(sch_1):page224_i46@mstr_discrete.cap(chips)!CAP_0805-10UF,16V,10%,X6S,C953A!!!F2450!A!!!!
S!GND!C9U4!2!@baseboard_fab2_lib.baseboard_fab2(sch_1):page224_i46@mstr_discrete.cap(chips)!CAP_0805-10UF,16V,10%,X6S,C953A!!!F2450!B!!!!
S!VR_FET_SW_P12V_STBY_PVDDQ_GHJ!C9T6!1!@baseboard_fab2_lib.baseboard_fab2(sch_1):page224_i81@mstr_discrete.cap(chips)!CAP_0805-10UF,16V,10%,X6S,C953A!!!F2453!A!!!!
S!GND!C9T6!2!@baseboard_fab2_lib.baseboard_fab2(sch_1):page224_i81@mstr_discrete.cap(chips)!CAP_0805-10UF,16V,10%,X6S,C953A!!!F2453!B!!!!
S!VR_FET_SW_P12V_STBY_PVDDQ_GHJ!C9T4!1!@baseboard_fab2_lib.baseboard_fab2(sch_1):page224_i47@mstr_discrete.cap(chips)!CAP_0805-10UF,16V,10%,X6S,C953A!!!F2454!A!!!!
S!GND!C9T4!2!@baseboard_fab2_lib.baseboard_fab2(sch_1):page224_i47@mstr_discrete.cap(chips)!CAP_0805-10UF,16V,10%,X6S,C953A!!!F2454!B!!!!
S!VR_FET_SW_P12V_STBY_PVDDQ_GHJ!C9U3!1!@baseboard_fab2_lib.baseboard_fab2(sch_1):page224_i80@mstr_discrete.cap(chips)!CAP_0805-10UF,16V,10%,X6S,C953A!!!F2451!A!!!!
S!GND!C9U3!2!@baseboard_fab2_lib.baseboard_fab2(sch_1):page224_i80@mstr_discrete.cap(chips)!CAP_0805-10UF,16V,10%,X6S,C953A!!!F2451!B!!!!
S!VR_FET_SW_P12V_STBY_PVCCIN_CPU1!C9P26!1!@baseboard_fab2_lib.baseboard_fab2(sch_1):page207_i54@mstr_discrete.cap(chips)!CAP_0805-10UF,16V,10%,X6S,C953A!!!F2459!A!!!!
S!GND!C9P26!2!@baseboard_fab2_lib.baseboard_fab2(sch_1):page207_i54@mstr_discrete.cap(chips)!CAP_0805-10UF,16V,10%,X6S,C953A!!!F2459!B!!!!
S!VR_FET_SW_P12V_STBY_PVCCIN_CPU1!C9R11!1!@baseboard_fab2_lib.baseboard_fab2(sch_1):page207_i48@mstr_discrete.cap(chips)!CAP_0805-10UF,16V,10%,X6S,C953A!!!F2455!A!!!!
S!GND!C9R11!2!@baseboard_fab2_lib.baseboard_fab2(sch_1):page207_i48@mstr_discrete.cap(chips)!CAP_0805-10UF,16V,10%,X6S,C953A!!!F2455!B!!!!
S!VR_FET_SW_P12V_STBY_PVCCIN_CPU1!C9P25!1!@baseboard_fab2_lib.baseboard_fab2(sch_1):page207_i51@mstr_discrete.cap(chips)!CAP_0805-10UF,16V,10%,X6S,C953A!!!F2460!A!!!!
S!GND!C9P25!2!@baseboard_fab2_lib.baseboard_fab2(sch_1):page207_i51@mstr_discrete.cap(chips)!CAP_0805-10UF,16V,10%,X6S,C953A!!!F2460!B!!!!
S!VR_FET_SW_P12V_STBY_PVCCIN_CPU1!C9R10!1!@baseboard_fab2_lib.baseboard_fab2(sch_1):page207_i44@mstr_discrete.cap(chips)!CAP_0805-10UF,16V,10%,X6S,C953A!!!F2456!A!!!!
S!GND!C9R10!2!@baseboard_fab2_lib.baseboard_fab2(sch_1):page207_i44@mstr_discrete.cap(chips)!CAP_0805-10UF,16V,10%,X6S,C953A!!!F2456!B!!!!
S!VR_FET_SW_P12V_STBY_PVCCIN_CPU1!C9P22!1!@baseboard_fab2_lib.baseboard_fab2(sch_1):page207_i50@mstr_discrete.cap(chips)!CAP_0805-10UF,16V,10%,X6S,C953A!!!F2461!A!!!!
S!GND!C9P22!2!@baseboard_fab2_lib.baseboard_fab2(sch_1):page207_i50@mstr_discrete.cap(chips)!CAP_0805-10UF,16V,10%,X6S,C953A!!!F2461!B!!!!
S!VR_FET_SW_P12V_STBY_PVCCIN_CPU1!C9R7!1!@baseboard_fab2_lib.baseboard_fab2(sch_1):page207_i43@mstr_discrete.cap(chips)!CAP_0805-10UF,16V,10%,X6S,C953A!!!F2457!A!!!!
S!GND!C9R7!2!@baseboard_fab2_lib.baseboard_fab2(sch_1):page207_i43@mstr_discrete.cap(chips)!CAP_0805-10UF,16V,10%,X6S,C953A!!!F2457!B!!!!
S!VR_FET_SW_P12V_STBY_PVCCIN_CPU1!C9P9!1!@baseboard_fab2_lib.baseboard_fab2(sch_1):page208_i55@mstr_discrete.cap(chips)!CAP_0805-10UF,16V,10%,X6S,C953A!!!F2465!A!!!!
S!GND!C9P9!2!@baseboard_fab2_lib.baseboard_fab2(sch_1):page208_i55@mstr_discrete.cap(chips)!CAP_0805-10UF,16V,10%,X6S,C953A!!!F2465!B!!!!
S!VR_FET_SW_P12V_STBY_PVCCIN_CPU1!C9P2!1!@baseboard_fab2_lib.baseboard_fab2(sch_1):page208_i60@mstr_discrete.cap(chips)!CAP_0805-10UF,16V,10%,X6S,C953A!!!F2468!A!!!!
S!GND!C9P2!2!@baseboard_fab2_lib.baseboard_fab2(sch_1):page208_i60@mstr_discrete.cap(chips)!CAP_0805-10UF,16V,10%,X6S,C953A!!!F2468!B!!!!
S!VR_FET_SW_P12V_STBY_PVCCIN_CPU1!C9P7!1!@baseboard_fab2_lib.baseboard_fab2(sch_1):page208_i54@mstr_discrete.cap(chips)!CAP_0805-10UF,16V,10%,X6S,C953A!!!F2466!A!!!!
S!GND!C9P7!2!@baseboard_fab2_lib.baseboard_fab2(sch_1):page208_i54@mstr_discrete.cap(chips)!CAP_0805-10UF,16V,10%,X6S,C953A!!!F2466!B!!!!
S!VR_FET_SW_P12V_STBY_PVCCIN_CPU1!C9P1!1!@baseboard_fab2_lib.baseboard_fab2(sch_1):page208_i59@mstr_discrete.cap(chips)!CAP_0805-10UF,16V,10%,X6S,C953A!!!F2469!A!!!!
S!GND!C9P1!2!@baseboard_fab2_lib.baseboard_fab2(sch_1):page208_i59@mstr_discrete.cap(chips)!CAP_0805-10UF,16V,10%,X6S,C953A!!!F2469!B!!!!
S!VR_FET_SW_P12V_STBY_PVCCIN_CPU1!C9P4!1!@baseboard_fab2_lib.baseboard_fab2(sch_1):page208_i53@mstr_discrete.cap(chips)!CAP_0805-10UF,16V,10%,X6S,C953A!!!F2467!A!!!!
S!GND!C9P4!2!@baseboard_fab2_lib.baseboard_fab2(sch_1):page208_i53@mstr_discrete.cap(chips)!CAP_0805-10UF,16V,10%,X6S,C953A!!!F2467!B!!!!
S!VR_FET_SW_P12V_STBY_PVCCIN_CPU1!C9P24!1!@baseboard_fab2_lib.baseboard_fab2(sch_1):page208_i58@mstr_discrete.cap(chips)!CAP_0805-10UF,16V,10%,X6S,C953A!!!F2470!A!!!!
S!GND!C9P24!2!@baseboard_fab2_lib.baseboard_fab2(sch_1):page208_i58@mstr_discrete.cap(chips)!CAP_0805-10UF,16V,10%,X6S,C953A!!!F2470!B!!!!
S!VR_FET_SW_P12V_STBY_PVCCIN_CPU1!C9N21!1!@baseboard_fab2_lib.baseboard_fab2(sch_1):page210_i38@mstr_discrete.cap(chips)!CAP_0805-10UF,16V,10%,X6S,C953A!!!F2471!A!!!!
S!GND!C9N21!2!@baseboard_fab2_lib.baseboard_fab2(sch_1):page210_i38@mstr_discrete.cap(chips)!CAP_0805-10UF,16V,10%,X6S,C953A!!!F2471!B!!!!
S!VR_FET_SW_P12V_STBY_PVCCIN_CPU1!C9N19!1!@baseboard_fab2_lib.baseboard_fab2(sch_1):page210_i36@mstr_discrete.cap(chips)!CAP_0805-10UF,16V,10%,X6S,C953A!!!F2472!A!!!!
S!GND!C9N19!2!@baseboard_fab2_lib.baseboard_fab2(sch_1):page210_i36@mstr_discrete.cap(chips)!CAP_0805-10UF,16V,10%,X6S,C953A!!!F2472!B!!!!
S!VR_FET_SW_P12V_STBY_PVCCIN_CPU1!C9N13!1!@baseboard_fab2_lib.baseboard_fab2(sch_1):page210_i35@mstr_discrete.cap(chips)!CAP_0805-10UF,16V,10%,X6S,C953A!!!F2473!A!!!!
S!GND!C9N13!2!@baseboard_fab2_lib.baseboard_fab2(sch_1):page210_i35@mstr_discrete.cap(chips)!CAP_0805-10UF,16V,10%,X6S,C953A!!!F2473!B!!!!
S!VR_FET_SW_P12V_STBY_PVCCIN_CPU0!C6N11!1!@baseboard_fab2_lib.baseboard_fab2(sch_1):page204_i42@mstr_discrete.cap(chips)!CAP_0805-10UF,16V,10%,X6S,C953A!!!F2508!A!!!!
S!GND!C6N11!2!@baseboard_fab2_lib.baseboard_fab2(sch_1):page204_i42@mstr_discrete.cap(chips)!CAP_0805-10UF,16V,10%,X6S,C953A!!!F2508!B!!!!
S!VR_FET_SW_P12V_STBY_PVCCIN_CPU0!C6N10!1!@baseboard_fab2_lib.baseboard_fab2(sch_1):page204_i37@mstr_discrete.cap(chips)!CAP_0805-10UF,16V,10%,X6S,C953A!!!F2509!A!!!!
S!GND!C6N10!2!@baseboard_fab2_lib.baseboard_fab2(sch_1):page204_i37@mstr_discrete.cap(chips)!CAP_0805-10UF,16V,10%,X6S,C953A!!!F2509!B!!!!
S!P12V_PSU!C1E15!1!@baseboard_fab2_lib.baseboard_fab2(sch_1):page195_i35@mstr_discrete.cap(chips)!CAP_0805-10UF,16V,10%,X6S,C953A!!!F2554!A!!!!
S!GND!C1E15!2!@baseboard_fab2_lib.baseboard_fab2(sch_1):page195_i35@mstr_discrete.cap(chips)!CAP_0805-10UF,16V,10%,X6S,C953A!!!F2554!B!!!!
S!P3V3_DB1200!C3D22!1!@baseboard_fab2_lib.baseboard_fab2(sch_1):page102_i10@mstr_discrete.cap(chips)!CAP_0805-10UF,16V,10%,X7R,G106A!!!F2444!A!!!!
S!GND!C3D22!2!@baseboard_fab2_lib.baseboard_fab2(sch_1):page102_i10@mstr_discrete.cap(chips)!CAP_0805-10UF,16V,10%,X7R,G106A!!!F2444!B!!!!
S!P3V3_FB_ADC128_VCC!C1U20!1!@baseboard_fab2_lib.baseboard_fab2(sch_1):page165_i67@mstr_discrete.cap(chips)!CAP_0805-10UF,16V,10%,X7R,G106A!!!F2445!A!!!!
S!GND!C1U20!2!@baseboard_fab2_lib.baseboard_fab2(sch_1):page165_i67@mstr_discrete.cap(chips)!CAP_0805-10UF,16V,10%,X7R,G106A!!!F2445!B!!!!
S!P12V_NVDIMM_ABC!C6U10!1!@baseboard_fab2_lib.baseboard_fab2(sch_1):page197_i65@mstr_discrete.cap(chips)!CAP_0805-10UF,16V,10%,X7R,G106A!!!F2439!A!!!!
S!GND!C6U10!2!@baseboard_fab2_lib.baseboard_fab2(sch_1):page197_i65@mstr_discrete.cap(chips)!CAP_0805-10UF,16V,10%,X7R,G106A!!!F2439!B!!!!
S!P12V_NVDIMM_ABC!C6T2!1!@baseboard_fab2_lib.baseboard_fab2(sch_1):page197_i54@mstr_discrete.cap(chips)!CAP_0805-10UF,16V,10%,X7R,G106A!!!F2440!A!!!!
S!GND!C6T2!2!@baseboard_fab2_lib.baseboard_fab2(sch_1):page197_i54@mstr_discrete.cap(chips)!CAP_0805-10UF,16V,10%,X7R,G106A!!!F2440!B!!!!
S!P12V_NVDIMM_ABC!C6U18!1!@baseboard_fab2_lib.baseboard_fab2(sch_1):page197_i52@mstr_discrete.cap(chips)!CAP_0805-10UF,16V,10%,X7R,G106A!!!F2438!A!!!!
S!GND!C6U18!2!@baseboard_fab2_lib.baseboard_fab2(sch_1):page197_i52@mstr_discrete.cap(chips)!CAP_0805-10UF,16V,10%,X7R,G106A!!!F2438!B!!!!
S!P12V_NVDIMM_DEF!C4A17!1!@baseboard_fab2_lib.baseboard_fab2(sch_1):page197_i67@mstr_discrete.cap(chips)!CAP_0805-10UF,16V,10%,X7R,G106A!!!F2442!A!!!!
S!GND!C4A17!2!@baseboard_fab2_lib.baseboard_fab2(sch_1):page197_i67@mstr_discrete.cap(chips)!CAP_0805-10UF,16V,10%,X7R,G106A!!!F2442!B!!!!
S!P12V_NVDIMM_DEF!C4A4!1!@baseboard_fab2_lib.baseboard_fab2(sch_1):page197_i62@mstr_discrete.cap(chips)!CAP_0805-10UF,16V,10%,X7R,G106A!!!F2443!A!!!!
S!GND!C4A4!2!@baseboard_fab2_lib.baseboard_fab2(sch_1):page197_i62@mstr_discrete.cap(chips)!CAP_0805-10UF,16V,10%,X7R,G106A!!!F2443!B!!!!
S!P12V_NVDIMM_DEF!C4B11!1!@baseboard_fab2_lib.baseboard_fab2(sch_1):page197_i59@mstr_discrete.cap(chips)!CAP_0805-10UF,16V,10%,X7R,G106A!!!F2441!A!!!!
S!GND!C4B11!2!@baseboard_fab2_lib.baseboard_fab2(sch_1):page197_i59@mstr_discrete.cap(chips)!CAP_0805-10UF,16V,10%,X7R,G106A!!!F2441!B!!!!
S!P12V_NVDIMM_GHJ!C9U8!1!@baseboard_fab2_lib.baseboard_fab2(sch_1):page197_i76@mstr_discrete.cap(chips)!CAP_0805-10UF,16V,10%,X7R,G106A!!!F2436!A!!!!
S!GND!C9U8!2!@baseboard_fab2_lib.baseboard_fab2(sch_1):page197_i76@mstr_discrete.cap(chips)!CAP_0805-10UF,16V,10%,X7R,G106A!!!F2436!B!!!!
S!P12V_NVDIMM_GHJ!C9U11!1!@baseboard_fab2_lib.baseboard_fab2(sch_1):page197_i73@mstr_discrete.cap(chips)!CAP_0805-10UF,16V,10%,X7R,G106A!!!F2435!A!!!!
S!GND!C9U11!2!@baseboard_fab2_lib.baseboard_fab2(sch_1):page197_i73@mstr_discrete.cap(chips)!CAP_0805-10UF,16V,10%,X7R,G106A!!!F2435!B!!!!
S!P12V_NVDIMM_GHJ!C9T8!1!@baseboard_fab2_lib.baseboard_fab2(sch_1):page197_i70@mstr_discrete.cap(chips)!CAP_0805-10UF,16V,10%,X7R,G106A!!!F2437!A!!!!
S!GND!C9T8!2!@baseboard_fab2_lib.baseboard_fab2(sch_1):page197_i70@mstr_discrete.cap(chips)!CAP_0805-10UF,16V,10%,X7R,G106A!!!F2437!B!!!!
S!P12V_NVDIMM_KLM!C1A16!1!@baseboard_fab2_lib.baseboard_fab2(sch_1):page197_i85@mstr_discrete.cap(chips)!CAP_0805-10UF,16V,10%,X7R,G106A!!!F2447!A!!!!
S!GND!C1A16!2!@baseboard_fab2_lib.baseboard_fab2(sch_1):page197_i85@mstr_discrete.cap(chips)!CAP_0805-10UF,16V,10%,X7R,G106A!!!F2447!B!!!!
S!P12V_NVDIMM_KLM!C1B7!1!@baseboard_fab2_lib.baseboard_fab2(sch_1):page197_i82@mstr_discrete.cap(chips)!CAP_0805-10UF,16V,10%,X7R,G106A!!!F2446!A!!!!
S!GND!C1B7!2!@baseboard_fab2_lib.baseboard_fab2(sch_1):page197_i82@mstr_discrete.cap(chips)!CAP_0805-10UF,16V,10%,X7R,G106A!!!F2446!B!!!!
S!P12V_NVDIMM_KLM!C1A4!1!@baseboard_fab2_lib.baseboard_fab2(sch_1):page197_i79@mstr_discrete.cap(chips)!CAP_0805-10UF,16V,10%,X7R,G106A!!!F2448!A!!!!
S!GND!C1A4!2!@baseboard_fab2_lib.baseboard_fab2(sch_1):page197_i79@mstr_discrete.cap(chips)!CAP_0805-10UF,16V,10%,X7R,G106A!!!F2448!B!!!!
S!P3V3_STBY!C2T7!1!@baseboard_fab2_lib.baseboard_fab2(sch_1):page240_i158@mstr_discrete.cap(chips)!CAP_0805-22UF,6.3V,20%,X6S,C95A!!!F2430!A!!!!
S!GND!C2T7!2!@baseboard_fab2_lib.baseboard_fab2(sch_1):page240_i158@mstr_discrete.cap(chips)!CAP_0805-22UF,6.3V,20%,X6S,C95A!!!F2430!B!!!!
S!P3V3_STBY!C2T6!1!@baseboard_fab2_lib.baseboard_fab2(sch_1):page240_i160@mstr_discrete.cap(chips)!CAP_0805-22UF,6.3V,20%,X6S,C95A!!!F2431!A!!!!
S!GND!C2T6!2!@baseboard_fab2_lib.baseboard_fab2(sch_1):page240_i160@mstr_discrete.cap(chips)!CAP_0805-22UF,6.3V,20%,X6S,C95A!!!F2431!B!!!!
S!P3V3_STBY!C2T9!1!@baseboard_fab2_lib.baseboard_fab2(sch_1):page240_i174@mstr_discrete.cap(chips)!CAP_0805-22UF,6.3V,20%,X6S,C95A!!!F2429!A!!!!
S!GND!C2T9!2!@baseboard_fab2_lib.baseboard_fab2(sch_1):page240_i174@mstr_discrete.cap(chips)!CAP_0805-22UF,6.3V,20%,X6S,C95A!!!F2429!B!!!!
S!P5V_STBY!C8E7!1!@baseboard_fab2_lib.baseboard_fab2(sch_1):page241_i3@mstr_discrete.cap(chips)!CAP_0805-22UF,6.3V,20%,X6S,C95A!!!F2427!A!!!!
S!GND!C8E7!2!@baseboard_fab2_lib.baseboard_fab2(sch_1):page241_i3@mstr_discrete.cap(chips)!CAP_0805-22UF,6.3V,20%,X6S,C95A!!!F2427!B!!!!
S!P5V_STBY!C8E9!1!@baseboard_fab2_lib.baseboard_fab2(sch_1):page241_i2@mstr_discrete.cap(chips)!CAP_0805-22UF,6.3V,20%,X6S,C95A!!!F2426!A!!!!
S!GND!C8E9!2!@baseboard_fab2_lib.baseboard_fab2(sch_1):page241_i2@mstr_discrete.cap(chips)!CAP_0805-22UF,6.3V,20%,X6S,C95A!!!F2426!B!!!!
S!P1V8_PCH_STBY!C8A14!1!@baseboard_fab2_lib.baseboard_fab2(sch_1):page237_i13@mstr_discrete.cap(chips)!CAP_0805-22UF,6.3V,20%,X6S,C95A!!!F2428!A!!!!
S!GND!C8A14!2!@baseboard_fab2_lib.baseboard_fab2(sch_1):page237_i13@mstr_discrete.cap(chips)!CAP_0805-22UF,6.3V,20%,X6S,C95A!!!F2428!B!!!!
S!P1V8_PCH_STBY!C2L45!1!@baseboard_fab2_lib.baseboard_fab2(sch_1):page237_i12@mstr_discrete.cap(chips)!CAP_0805-22UF,6.3V,20%,X6S,C95A!!!F2432!A!!!!
S!GND!C2L45!2!@baseboard_fab2_lib.baseboard_fab2(sch_1):page237_i12@mstr_discrete.cap(chips)!CAP_0805-22UF,6.3V,20%,X6S,C95A!!!F2432!B!!!!
S!P3V3_STBY!C1T13!1!@baseboard_fab2_lib.baseboard_fab2(sch_1):page149_i74@mstr_discrete.cap(chips)!CAP_0805-22UF,6.3V,20%,X6S,C95A!!!F2433!A!!!!
S!GND!C1T13!2!@baseboard_fab2_lib.baseboard_fab2(sch_1):page149_i74@mstr_discrete.cap(chips)!CAP_0805-22UF,6.3V,20%,X6S,C95A!!!F2433!B!!!!
S!P3V3_STBY!C1T9!1!@baseboard_fab2_lib.baseboard_fab2(sch_1):page149_i75@mstr_discrete.cap(chips)!CAP_0805-22UF,6.3V,20%,X6S,C95A!!!F2434!A!!!!
S!GND!C1T9!2!@baseboard_fab2_lib.baseboard_fab2(sch_1):page149_i75@mstr_discrete.cap(chips)!CAP_0805-22UF,6.3V,20%,X6S,C95A!!!F2434!B!!!!
S!PVCCIO_CPU1!C7P3!1!@baseboard_fab2_lib.baseboard_fab2(sch_1):page76_i52@mstr_discrete.cap(chips)!CAP_0805-47UF,4V,20%,X6S,C9533A!!!F2363!A!!!!
S!GND!C7P3!2!@baseboard_fab2_lib.baseboard_fab2(sch_1):page76_i52@mstr_discrete.cap(chips)!CAP_0805-47UF,4V,20%,X6S,C9533A!!!F2363!B!!!!
S!PVCCIO_CPU1!C7P18!1!@baseboard_fab2_lib.baseboard_fab2(sch_1):page76_i51@mstr_discrete.cap(chips)!CAP_0805-47UF,4V,20%,X6S,C9533A!!!F2350!A!!!!
S!GND!C7P18!2!@baseboard_fab2_lib.baseboard_fab2(sch_1):page76_i51@mstr_discrete.cap(chips)!CAP_0805-47UF,4V,20%,X6S,C9533A!!!F2350!B!!!!
S!PVCCIO_CPU1!C7P17!1!@baseboard_fab2_lib.baseboard_fab2(sch_1):page76_i29@mstr_discrete.cap(chips)!CAP_0805-47UF,4V,20%,X6S,C9533A!!!F2351!A!!!!
S!GND!C7P17!2!@baseboard_fab2_lib.baseboard_fab2(sch_1):page76_i29@mstr_discrete.cap(chips)!CAP_0805-47UF,4V,20%,X6S,C9533A!!!F2351!B!!!!
S!PVCCMCP_CPU0!C5P21!1!@baseboard_fab2_lib.baseboard_fab2(sch_1):page42_i184@mstr_discrete.cap(chips)!CAP_0805-47UF,4V,20%,X6S,C9533A!!!F2395!A!!!!
S!GND!C5P21!2!@baseboard_fab2_lib.baseboard_fab2(sch_1):page42_i184@mstr_discrete.cap(chips)!CAP_0805-47UF,4V,20%,X6S,C9533A!!!F2395!B!!!!
S!PVCCIN_CPU0!C5P44!1!@baseboard_fab2_lib.baseboard_fab2(sch_1):page42_i61@mstr_discrete.cap(chips)!CAP_0805-47UF,4V,20%,X6S,C9533A!!!F2374!A!!!!
S!GND!C5P44!2!@baseboard_fab2_lib.baseboard_fab2(sch_1):page42_i61@mstr_discrete.cap(chips)!CAP_0805-47UF,4V,20%,X6S,C9533A!!!F2374!B!!!!
S!PVCCIN_CPU0!C5P43!1!@baseboard_fab2_lib.baseboard_fab2(sch_1):page42_i60@mstr_discrete.cap(chips)!CAP_0805-47UF,4V,20%,X6S,C9533A!!!F2375!A!!!!
S!GND!C5P43!2!@baseboard_fab2_lib.baseboard_fab2(sch_1):page42_i60@mstr_discrete.cap(chips)!CAP_0805-47UF,4V,20%,X6S,C9533A!!!F2375!B!!!!
S!PVCCIN_CPU0!C5P42!1!@baseboard_fab2_lib.baseboard_fab2(sch_1):page42_i59@mstr_discrete.cap(chips)!CAP_0805-47UF,4V,20%,X6S,C9533A!!!F2376!A!!!!
S!GND!C5P42!2!@baseboard_fab2_lib.baseboard_fab2(sch_1):page42_i59@mstr_discrete.cap(chips)!CAP_0805-47UF,4V,20%,X6S,C9533A!!!F2376!B!!!!
S!PVCCIN_CPU0!C5P40!1!@baseboard_fab2_lib.baseboard_fab2(sch_1):page42_i57@mstr_discrete.cap(chips)!CAP_0805-47UF,4V,20%,X6S,C9533A!!!F2378!A!!!!
S!GND!C5P40!2!@baseboard_fab2_lib.baseboard_fab2(sch_1):page42_i57@mstr_discrete.cap(chips)!CAP_0805-47UF,4V,20%,X6S,C9533A!!!F2378!B!!!!
S!PVCCIN_CPU0!C5P41!1!@baseboard_fab2_lib.baseboard_fab2(sch_1):page42_i40@mstr_discrete.cap(chips)!CAP_0805-47UF,4V,20%,X6S,C9533A!!!F2377!A!!!!
S!GND!C5P41!2!@baseboard_fab2_lib.baseboard_fab2(sch_1):page42_i40@mstr_discrete.cap(chips)!CAP_0805-47UF,4V,20%,X6S,C9533A!!!F2377!B!!!!
S!PVCCIN_CPU0!C5P27!1!@baseboard_fab2_lib.baseboard_fab2(sch_1):page42_i44@mstr_discrete.cap(chips)!CAP_0805-47UF,4V,20%,X6S,C9533A!!!F2389!A!!!!
S!GND!C5P27!2!@baseboard_fab2_lib.baseboard_fab2(sch_1):page42_i44@mstr_discrete.cap(chips)!CAP_0805-47UF,4V,20%,X6S,C9533A!!!F2389!B!!!!
S!PVCCIN_CPU0!C5P26!1!@baseboard_fab2_lib.baseboard_fab2(sch_1):page42_i56@mstr_discrete.cap(chips)!CAP_0805-47UF,4V,20%,X6S,C9533A!!!F2390!A!!!!
S!GND!C5P26!2!@baseboard_fab2_lib.baseboard_fab2(sch_1):page42_i56@mstr_discrete.cap(chips)!CAP_0805-47UF,4V,20%,X6S,C9533A!!!F2390!B!!!!
S!PVCCIN_CPU0!C5P6!1!@baseboard_fab2_lib.baseboard_fab2(sch_1):page42_i38@mstr_discrete.cap(chips)!CAP_0805-47UF,4V,20%,X6S,C9533A!!!F2407!A!!!!
S!GND!C5P6!2!@baseboard_fab2_lib.baseboard_fab2(sch_1):page42_i38@mstr_discrete.cap(chips)!CAP_0805-47UF,4V,20%,X6S,C9533A!!!F2407!B!!!!
S!PVCCIN_CPU0!C5P5!1!@baseboard_fab2_lib.baseboard_fab2(sch_1):page42_i42@mstr_discrete.cap(chips)!CAP_0805-47UF,4V,20%,X6S,C9533A!!!F2408!A!!!!
S!GND!C5P5!2!@baseboard_fab2_lib.baseboard_fab2(sch_1):page42_i42@mstr_discrete.cap(chips)!CAP_0805-47UF,4V,20%,X6S,C9533A!!!F2408!B!!!!
S!PVCCIN_CPU0!C5P4!1!@baseboard_fab2_lib.baseboard_fab2(sch_1):page42_i27@mstr_discrete.cap(chips)!CAP_0805-47UF,4V,20%,X6S,C9533A!!!F2409!A!!!!
S!GND!C5P4!2!@baseboard_fab2_lib.baseboard_fab2(sch_1):page42_i27@mstr_discrete.cap(chips)!CAP_0805-47UF,4V,20%,X6S,C9533A!!!F2409!B!!!!
S!PVCCIN_CPU0!C5P17!1!@baseboard_fab2_lib.baseboard_fab2(sch_1):page42_i190@mstr_discrete.cap(chips)!CAP_0805-47UF,4V,20%,X6S,C9533A!!!F2399!A!!!!
S!GND!C5P17!2!@baseboard_fab2_lib.baseboard_fab2(sch_1):page42_i190@mstr_discrete.cap(chips)!CAP_0805-47UF,4V,20%,X6S,C9533A!!!F2399!B!!!!
S!PVCCIN_CPU0!C5P3!1!@baseboard_fab2_lib.baseboard_fab2(sch_1):page42_i189@mstr_discrete.cap(chips)!CAP_0805-47UF,4V,20%,X6S,C9533A!!!F2410!A!!!!
S!GND!C5P3!2!@baseboard_fab2_lib.baseboard_fab2(sch_1):page42_i189@mstr_discrete.cap(chips)!CAP_0805-47UF,4V,20%,X6S,C9533A!!!F2410!B!!!!
S!PVCCIN_CPU0!C5P16!1!@baseboard_fab2_lib.baseboard_fab2(sch_1):page42_i188@mstr_discrete.cap(chips)!CAP_0805-47UF,4V,20%,X6S,C9533A!!!F2400!A!!!!
S!GND!C5P16!2!@baseboard_fab2_lib.baseboard_fab2(sch_1):page42_i188@mstr_discrete.cap(chips)!CAP_0805-47UF,4V,20%,X6S,C9533A!!!F2400!B!!!!
S!PVCCIN_CPU0!C5P15!1!@baseboard_fab2_lib.baseboard_fab2(sch_1):page42_i187@mstr_discrete.cap(chips)!CAP_0805-47UF,4V,20%,X6S,C9533A!!!F2401!A!!!!
S!GND!C5P15!2!@baseboard_fab2_lib.baseboard_fab2(sch_1):page42_i187@mstr_discrete.cap(chips)!CAP_0805-47UF,4V,20%,X6S,C9533A!!!F2401!B!!!!
S!PVCCMCP_CPU0!C4P4!1!@baseboard_fab2_lib.baseboard_fab2(sch_1):page42_i14@mstr_discrete.cap(chips)!CAP_0805-47UF,4V,20%,X6S,C9533A!!!F2415!A!!!!
S!GND!C4P4!2!@baseboard_fab2_lib.baseboard_fab2(sch_1):page42_i14@mstr_discrete.cap(chips)!CAP_0805-47UF,4V,20%,X6S,C9533A!!!F2415!B!!!!
S!PVCCMCP_CPU0!C5P18!1!@baseboard_fab2_lib.baseboard_fab2(sch_1):page42_i2@mstr_discrete.cap(chips)!CAP_0805-47UF,4V,20%,X6S,C9533A!!!F2398!A!!!!
S!GND!C5P18!2!@baseboard_fab2_lib.baseboard_fab2(sch_1):page42_i2@mstr_discrete.cap(chips)!CAP_0805-47UF,4V,20%,X6S,C9533A!!!F2398!B!!!!
S!PVCCIN_CPU0!C5P22!1!@baseboard_fab2_lib.baseboard_fab2(sch_1):page42_i55@mstr_discrete.cap(chips)!CAP_0805-47UF,4V,20%,X6S,C9533A!!!F2394!A!!!!
S!GND!C5P22!2!@baseboard_fab2_lib.baseboard_fab2(sch_1):page42_i55@mstr_discrete.cap(chips)!CAP_0805-47UF,4V,20%,X6S,C9533A!!!F2394!B!!!!
S!PVCCIN_CPU0!C5P23!1!@baseboard_fab2_lib.baseboard_fab2(sch_1):page42_i28@mstr_discrete.cap(chips)!CAP_0805-47UF,4V,20%,X6S,C9533A!!!F2393!A!!!!
S!GND!C5P23!2!@baseboard_fab2_lib.baseboard_fab2(sch_1):page42_i28@mstr_discrete.cap(chips)!CAP_0805-47UF,4V,20%,X6S,C9533A!!!F2393!B!!!!
S!PVCCIN_CPU0!C5P24!1!@baseboard_fab2_lib.baseboard_fab2(sch_1):page42_i33@mstr_discrete.cap(chips)!CAP_0805-47UF,4V,20%,X6S,C9533A!!!F2392!A!!!!
S!GND!C5P24!2!@baseboard_fab2_lib.baseboard_fab2(sch_1):page42_i33@mstr_discrete.cap(chips)!CAP_0805-47UF,4V,20%,X6S,C9533A!!!F2392!B!!!!
S!PVCCIN_CPU0!C5P25!1!@baseboard_fab2_lib.baseboard_fab2(sch_1):page42_i37@mstr_discrete.cap(chips)!CAP_0805-47UF,4V,20%,X6S,C9533A!!!F2391!A!!!!
S!GND!C5P25!2!@baseboard_fab2_lib.baseboard_fab2(sch_1):page42_i37@mstr_discrete.cap(chips)!CAP_0805-47UF,4V,20%,X6S,C9533A!!!F2391!B!!!!
S!PVCCMCP_CPU0!C5P19!1!@baseboard_fab2_lib.baseboard_fab2(sch_1):page42_i13@mstr_discrete.cap(chips)!CAP_0805-47UF,4V,20%,X6S,C9533A!!!F2397!A!!!!
S!GND!C5P19!2!@baseboard_fab2_lib.baseboard_fab2(sch_1):page42_i13@mstr_discrete.cap(chips)!CAP_0805-47UF,4V,20%,X6S,C9533A!!!F2397!B!!!!
S!PVCCMCP_CPU0!C4P7!1!@baseboard_fab2_lib.baseboard_fab2(sch_1):page42_i9@mstr_discrete.cap(chips)!CAP_0805-47UF,4V,20%,X6S,C9533A!!!F2413!A!!!!
S!GND!C4P7!2!@baseboard_fab2_lib.baseboard_fab2(sch_1):page42_i9@mstr_discrete.cap(chips)!CAP_0805-47UF,4V,20%,X6S,C9533A!!!F2413!B!!!!
S!PVCCMCP_CPU0!C4P3!1!@baseboard_fab2_lib.baseboard_fab2(sch_1):page42_i8@mstr_discrete.cap(chips)!CAP_0805-47UF,4V,20%,X6S,C9533A!!!F2416!A!!!!
S!GND!C4P3!2!@baseboard_fab2_lib.baseboard_fab2(sch_1):page42_i8@mstr_discrete.cap(chips)!CAP_0805-47UF,4V,20%,X6S,C9533A!!!F2416!B!!!!
S!PVCCMCP_CPU0!C5P10!1!@baseboard_fab2_lib.baseboard_fab2(sch_1):page42_i6@mstr_discrete.cap(chips)!CAP_0805-47UF,4V,20%,X6S,C9533A!!!F2406!A!!!!
S!GND!C5P10!2!@baseboard_fab2_lib.baseboard_fab2(sch_1):page42_i6@mstr_discrete.cap(chips)!CAP_0805-47UF,4V,20%,X6S,C9533A!!!F2406!B!!!!
S!PVCCMCP_CPU0!C5P11!1!@baseboard_fab2_lib.baseboard_fab2(sch_1):page42_i4@mstr_discrete.cap(chips)!CAP_0805-47UF,4V,20%,X6S,C9533A!!!F2405!A!!!!
S!GND!C5P11!2!@baseboard_fab2_lib.baseboard_fab2(sch_1):page42_i4@mstr_discrete.cap(chips)!CAP_0805-47UF,4V,20%,X6S,C9533A!!!F2405!B!!!!
S!PVCCMCP_CPU0!C5P28!1!@baseboard_fab2_lib.baseboard_fab2(sch_1):page42_i3@mstr_discrete.cap(chips)!CAP_0805-47UF,4V,20%,X6S,C9533A!!!F2388!A!!!!
S!GND!C5P28!2!@baseboard_fab2_lib.baseboard_fab2(sch_1):page42_i3@mstr_discrete.cap(chips)!CAP_0805-47UF,4V,20%,X6S,C9533A!!!F2388!B!!!!
S!PVCCIN_CPU1!C8P11!1!@baseboard_fab2_lib.baseboard_fab2(sch_1):page76_i139@mstr_discrete.cap(chips)!CAP_0805-47UF,4V,20%,X6S,C9533A!!!F2338!A!!!!
S!GND!C8P11!2!@baseboard_fab2_lib.baseboard_fab2(sch_1):page76_i139@mstr_discrete.cap(chips)!CAP_0805-47UF,4V,20%,X6S,C9533A!!!F2338!B!!!!
S!PVCCMCP_CPU1!C8P9!1!@baseboard_fab2_lib.baseboard_fab2(sch_1):page76_i214@mstr_discrete.cap(chips)!CAP_0805-47UF,4V,20%,X6S,C9533A!!!F2340!A!!!!
S!GND!C8P9!2!@baseboard_fab2_lib.baseboard_fab2(sch_1):page76_i214@mstr_discrete.cap(chips)!CAP_0805-47UF,4V,20%,X6S,C9533A!!!F2340!B!!!!
S!PVCCIN_CPU1!C8P29!1!@baseboard_fab2_lib.baseboard_fab2(sch_1):page76_i125@mstr_discrete.cap(chips)!CAP_0805-47UF,4V,20%,X6S,C9533A!!!F2320!A!!!!
S!GND!C8P29!2!@baseboard_fab2_lib.baseboard_fab2(sch_1):page76_i125@mstr_discrete.cap(chips)!CAP_0805-47UF,4V,20%,X6S,C9533A!!!F2320!B!!!!
S!PVCCIN_CPU1!C8P28!1!@baseboard_fab2_lib.baseboard_fab2(sch_1):page76_i137@mstr_discrete.cap(chips)!CAP_0805-47UF,4V,20%,X6S,C9533A!!!F2321!A!!!!
S!GND!C8P28!2!@baseboard_fab2_lib.baseboard_fab2(sch_1):page76_i137@mstr_discrete.cap(chips)!CAP_0805-47UF,4V,20%,X6S,C9533A!!!F2321!B!!!!
S!PVCCIN_CPU1!C8P27!1!@baseboard_fab2_lib.baseboard_fab2(sch_1):page76_i141@mstr_discrete.cap(chips)!CAP_0805-47UF,4V,20%,X6S,C9533A!!!F2322!A!!!!
S!GND!C8P27!2!@baseboard_fab2_lib.baseboard_fab2(sch_1):page76_i141@mstr_discrete.cap(chips)!CAP_0805-47UF,4V,20%,X6S,C9533A!!!F2322!B!!!!
S!PVCCIN_CPU1!C8P26!1!@baseboard_fab2_lib.baseboard_fab2(sch_1):page76_i118@mstr_discrete.cap(chips)!CAP_0805-47UF,4V,20%,X6S,C9533A!!!F2323!A!!!!
S!GND!C8P26!2!@baseboard_fab2_lib.baseboard_fab2(sch_1):page76_i118@mstr_discrete.cap(chips)!CAP_0805-47UF,4V,20%,X6S,C9533A!!!F2323!B!!!!
S!PVCCIN_CPU1!C8P13!1!@baseboard_fab2_lib.baseboard_fab2(sch_1):page76_i132@mstr_discrete.cap(chips)!CAP_0805-47UF,4V,20%,X6S,C9533A!!!F2336!A!!!!
S!GND!C8P13!2!@baseboard_fab2_lib.baseboard_fab2(sch_1):page76_i132@mstr_discrete.cap(chips)!CAP_0805-47UF,4V,20%,X6S,C9533A!!!F2336!B!!!!
S!PVCCIN_CPU1!C8P25!1!@baseboard_fab2_lib.baseboard_fab2(sch_1):page76_i136@mstr_discrete.cap(chips)!CAP_0805-47UF,4V,20%,X6S,C9533A!!!F2324!A!!!!
S!GND!C8P25!2!@baseboard_fab2_lib.baseboard_fab2(sch_1):page76_i136@mstr_discrete.cap(chips)!CAP_0805-47UF,4V,20%,X6S,C9533A!!!F2324!B!!!!
S!PVCCMCP_CPU1!C8P15!1!@baseboard_fab2_lib.baseboard_fab2(sch_1):page76_i212@mstr_discrete.cap(chips)!CAP_0805-47UF,4V,20%,X6S,C9533A!!!F2334!A!!!!
S!GND!C8P15!2!@baseboard_fab2_lib.baseboard_fab2(sch_1):page76_i212@mstr_discrete.cap(chips)!CAP_0805-47UF,4V,20%,X6S,C9533A!!!F2334!B!!!!
S!PVCCIN_CPU1!C8P33!1!@baseboard_fab2_lib.baseboard_fab2(sch_1):page76_i131@mstr_discrete.cap(chips)!CAP_0805-47UF,4V,20%,X6S,C9533A!!!F2318!A!!!!
S!GND!C8P33!2!@baseboard_fab2_lib.baseboard_fab2(sch_1):page76_i131@mstr_discrete.cap(chips)!CAP_0805-47UF,4V,20%,X6S,C9533A!!!F2318!B!!!!
S!PVCCIN_CPU1!C8P21!1!@baseboard_fab2_lib.baseboard_fab2(sch_1):page76_i135@mstr_discrete.cap(chips)!CAP_0805-47UF,4V,20%,X6S,C9533A!!!F2328!A!!!!
S!GND!C8P21!2!@baseboard_fab2_lib.baseboard_fab2(sch_1):page76_i135@mstr_discrete.cap(chips)!CAP_0805-47UF,4V,20%,X6S,C9533A!!!F2328!B!!!!
S!PVCCMCP_CPU1!C8P8!1!@baseboard_fab2_lib.baseboard_fab2(sch_1):page76_i213@mstr_discrete.cap(chips)!CAP_0805-47UF,4V,20%,X6S,C9533A!!!F2341!A!!!!
S!GND!C8P8!2!@baseboard_fab2_lib.baseboard_fab2(sch_1):page76_i213@mstr_discrete.cap(chips)!CAP_0805-47UF,4V,20%,X6S,C9533A!!!F2341!B!!!!
S!PVCCIN_CPU1!C8P16!1!@baseboard_fab2_lib.baseboard_fab2(sch_1):page76_i129@mstr_discrete.cap(chips)!CAP_0805-47UF,4V,20%,X6S,C9533A!!!F2333!A!!!!
S!GND!C8P16!2!@baseboard_fab2_lib.baseboard_fab2(sch_1):page76_i129@mstr_discrete.cap(chips)!CAP_0805-47UF,4V,20%,X6S,C9533A!!!F2333!B!!!!
S!PVCCIN_CPU1!C8P17!1!@baseboard_fab2_lib.baseboard_fab2(sch_1):page76_i133@mstr_discrete.cap(chips)!CAP_0805-47UF,4V,20%,X6S,C9533A!!!F2332!A!!!!
S!GND!C8P17!2!@baseboard_fab2_lib.baseboard_fab2(sch_1):page76_i133@mstr_discrete.cap(chips)!CAP_0805-47UF,4V,20%,X6S,C9533A!!!F2332!B!!!!
S!PVCCIN_CPU1!C8P18!1!@baseboard_fab2_lib.baseboard_fab2(sch_1):page76_i92@mstr_discrete.cap(chips)!CAP_0805-47UF,4V,20%,X6S,C9533A!!!F2331!A!!!!
S!GND!C8P18!2!@baseboard_fab2_lib.baseboard_fab2(sch_1):page76_i92@mstr_discrete.cap(chips)!CAP_0805-47UF,4V,20%,X6S,C9533A!!!F2331!B!!!!
S!PVCCIN_CPU1!C8P19!1!@baseboard_fab2_lib.baseboard_fab2(sch_1):page76_i103@mstr_discrete.cap(chips)!CAP_0805-47UF,4V,20%,X6S,C9533A!!!F2330!A!!!!
S!GND!C8P19!2!@baseboard_fab2_lib.baseboard_fab2(sch_1):page76_i103@mstr_discrete.cap(chips)!CAP_0805-47UF,4V,20%,X6S,C9533A!!!F2330!B!!!!
S!PVCCIN_CPU1!C8P12!1!@baseboard_fab2_lib.baseboard_fab2(sch_1):page76_i107@mstr_discrete.cap(chips)!CAP_0805-47UF,4V,20%,X6S,C9533A!!!F2337!A!!!!
S!GND!C8P12!2!@baseboard_fab2_lib.baseboard_fab2(sch_1):page76_i107@mstr_discrete.cap(chips)!CAP_0805-47UF,4V,20%,X6S,C9533A!!!F2337!B!!!!
S!PVCCIN_CPU1!C8P20!1!@baseboard_fab2_lib.baseboard_fab2(sch_1):page76_i89@mstr_discrete.cap(chips)!CAP_0805-47UF,4V,20%,X6S,C9533A!!!F2329!A!!!!
S!GND!C8P20!2!@baseboard_fab2_lib.baseboard_fab2(sch_1):page76_i89@mstr_discrete.cap(chips)!CAP_0805-47UF,4V,20%,X6S,C9533A!!!F2329!B!!!!
S!PVCCIN_CPU1!C8P3!1!@baseboard_fab2_lib.baseboard_fab2(sch_1):page76_i101@mstr_discrete.cap(chips)!CAP_0805-47UF,4V,20%,X6S,C9533A!!!F2343!A!!!!
S!GND!C8P3!2!@baseboard_fab2_lib.baseboard_fab2(sch_1):page76_i101@mstr_discrete.cap(chips)!CAP_0805-47UF,4V,20%,X6S,C9533A!!!F2343!B!!!!
S!PVCCIN_CPU1!C8P34!1!@baseboard_fab2_lib.baseboard_fab2(sch_1):page76_i106@mstr_discrete.cap(chips)!CAP_0805-47UF,4V,20%,X6S,C9533A!!!F2317!A!!!!
S!GND!C8P34!2!@baseboard_fab2_lib.baseboard_fab2(sch_1):page76_i106@mstr_discrete.cap(chips)!CAP_0805-47UF,4V,20%,X6S,C9533A!!!F2317!B!!!!
S!PVCCIN_CPU1!C8P4!1!@baseboard_fab2_lib.baseboard_fab2(sch_1):page76_i88@mstr_discrete.cap(chips)!CAP_0805-47UF,4V,20%,X6S,C9533A!!!F2342!A!!!!
S!GND!C8P4!2!@baseboard_fab2_lib.baseboard_fab2(sch_1):page76_i88@mstr_discrete.cap(chips)!CAP_0805-47UF,4V,20%,X6S,C9533A!!!F2342!B!!!!
S!PVCCIN_CPU1!C7P2!1!@baseboard_fab2_lib.baseboard_fab2(sch_1):page76_i100@mstr_discrete.cap(chips)!CAP_0805-47UF,4V,20%,X6S,C9533A!!!F2364!A!!!!
S!GND!C7P2!2!@baseboard_fab2_lib.baseboard_fab2(sch_1):page76_i100@mstr_discrete.cap(chips)!CAP_0805-47UF,4V,20%,X6S,C9533A!!!F2364!B!!!!
S!PVCCIN_CPU1!C7P1!1!@baseboard_fab2_lib.baseboard_fab2(sch_1):page76_i105@mstr_discrete.cap(chips)!CAP_0805-47UF,4V,20%,X6S,C9533A!!!F2365!A!!!!
S!GND!C7P1!2!@baseboard_fab2_lib.baseboard_fab2(sch_1):page76_i105@mstr_discrete.cap(chips)!CAP_0805-47UF,4V,20%,X6S,C9533A!!!F2365!B!!!!
S!PVCCIN_CPU1!C8P24!1!@baseboard_fab2_lib.baseboard_fab2(sch_1):page76_i217@mstr_discrete.cap(chips)!CAP_0805-47UF,4V,20%,X6S,C9533A!!!F2325!A!!!!
S!GND!C8P24!2!@baseboard_fab2_lib.baseboard_fab2(sch_1):page76_i217@mstr_discrete.cap(chips)!CAP_0805-47UF,4V,20%,X6S,C9533A!!!F2325!B!!!!
S!PVCCIN_CPU1!C7P19!1!@baseboard_fab2_lib.baseboard_fab2(sch_1):page76_i215@mstr_discrete.cap(chips)!CAP_0805-47UF,4V,20%,X6S,C9533A!!!F2349!A!!!!
S!GND!C7P19!2!@baseboard_fab2_lib.baseboard_fab2(sch_1):page76_i215@mstr_discrete.cap(chips)!CAP_0805-47UF,4V,20%,X6S,C9533A!!!F2349!B!!!!
S!PVCCIN_CPU1!C7P20!1!@baseboard_fab2_lib.baseboard_fab2(sch_1):page76_i218@mstr_discrete.cap(chips)!CAP_0805-47UF,4V,20%,X6S,C9533A!!!F2348!A!!!!
S!GND!C7P20!2!@baseboard_fab2_lib.baseboard_fab2(sch_1):page76_i218@mstr_discrete.cap(chips)!CAP_0805-47UF,4V,20%,X6S,C9533A!!!F2348!B!!!!
S!PVCCIN_CPU1!C8P32!1!@baseboard_fab2_lib.baseboard_fab2(sch_1):page76_i216@mstr_discrete.cap(chips)!CAP_0805-47UF,4V,20%,X6S,C9533A!!!F2319!A!!!!
S!GND!C8P32!2!@baseboard_fab2_lib.baseboard_fab2(sch_1):page76_i216@mstr_discrete.cap(chips)!CAP_0805-47UF,4V,20%,X6S,C9533A!!!F2319!B!!!!
S!PVCCMCP_CPU1!C8P14!1!@baseboard_fab2_lib.baseboard_fab2(sch_1):page76_i211@mstr_discrete.cap(chips)!CAP_0805-47UF,4V,20%,X6S,C9533A!!!F2335!A!!!!
S!GND!C8P14!2!@baseboard_fab2_lib.baseboard_fab2(sch_1):page76_i211@mstr_discrete.cap(chips)!CAP_0805-47UF,4V,20%,X6S,C9533A!!!F2335!B!!!!
S!PVCCMCP_CPU1!C7P14!1!@baseboard_fab2_lib.baseboard_fab2(sch_1):page76_i49@mstr_discrete.cap(chips)!CAP_0805-47UF,4V,20%,X6S,C9533A!!!F2353!A!!!!
S!GND!C7P14!2!@baseboard_fab2_lib.baseboard_fab2(sch_1):page76_i49@mstr_discrete.cap(chips)!CAP_0805-47UF,4V,20%,X6S,C9533A!!!F2353!B!!!!
S!PVCCMCP_CPU1!C8P23!1!@baseboard_fab2_lib.baseboard_fab2(sch_1):page76_i48@mstr_discrete.cap(chips)!CAP_0805-47UF,4V,20%,X6S,C9533A!!!F2326!A!!!!
S!GND!C8P23!2!@baseboard_fab2_lib.baseboard_fab2(sch_1):page76_i48@mstr_discrete.cap(chips)!CAP_0805-47UF,4V,20%,X6S,C9533A!!!F2326!B!!!!
S!PVCCMCP_CPU1!C7P15!1!@baseboard_fab2_lib.baseboard_fab2(sch_1):page76_i45@mstr_discrete.cap(chips)!CAP_0805-47UF,4V,20%,X6S,C9533A!!!F2352!A!!!!
S!GND!C7P15!2!@baseboard_fab2_lib.baseboard_fab2(sch_1):page76_i45@mstr_discrete.cap(chips)!CAP_0805-47UF,4V,20%,X6S,C9533A!!!F2352!B!!!!
S!PVCCMCP_CPU1!C8P22!1!@baseboard_fab2_lib.baseboard_fab2(sch_1):page76_i28@mstr_discrete.cap(chips)!CAP_0805-47UF,4V,20%,X6S,C9533A!!!F2327!A!!!!
S!GND!C8P22!2!@baseboard_fab2_lib.baseboard_fab2(sch_1):page76_i28@mstr_discrete.cap(chips)!CAP_0805-47UF,4V,20%,X6S,C9533A!!!F2327!B!!!!
S!PVCCMCP_CPU1!C7P7!1!@baseboard_fab2_lib.baseboard_fab2(sch_1):page76_i27@mstr_discrete.cap(chips)!CAP_0805-47UF,4V,20%,X6S,C9533A!!!F2359!A!!!!
S!GND!C7P7!2!@baseboard_fab2_lib.baseboard_fab2(sch_1):page76_i27@mstr_discrete.cap(chips)!CAP_0805-47UF,4V,20%,X6S,C9533A!!!F2359!B!!!!
S!PVCCMCP_CPU1!C7P10!1!@baseboard_fab2_lib.baseboard_fab2(sch_1):page76_i26@mstr_discrete.cap(chips)!CAP_0805-47UF,4V,20%,X6S,C9533A!!!F2356!A!!!!
S!GND!C7P10!2!@baseboard_fab2_lib.baseboard_fab2(sch_1):page76_i26@mstr_discrete.cap(chips)!CAP_0805-47UF,4V,20%,X6S,C9533A!!!F2356!B!!!!
S!PVCCMCP_CPU1!C7P13!1!@baseboard_fab2_lib.baseboard_fab2(sch_1):page76_i25@mstr_discrete.cap(chips)!CAP_0805-47UF,4V,20%,X6S,C9533A!!!F2354!A!!!!
S!GND!C7P13!2!@baseboard_fab2_lib.baseboard_fab2(sch_1):page76_i25@mstr_discrete.cap(chips)!CAP_0805-47UF,4V,20%,X6S,C9533A!!!F2354!B!!!!
S!PVCCMCP_CPU1!C7P6!1!@baseboard_fab2_lib.baseboard_fab2(sch_1):page76_i23@mstr_discrete.cap(chips)!CAP_0805-47UF,4V,20%,X6S,C9533A!!!F2360!A!!!!
S!GND!C7P6!2!@baseboard_fab2_lib.baseboard_fab2(sch_1):page76_i23@mstr_discrete.cap(chips)!CAP_0805-47UF,4V,20%,X6S,C9533A!!!F2360!B!!!!
S!PVCCMCP_CPU1!C7P9!1!@baseboard_fab2_lib.baseboard_fab2(sch_1):page76_i181@mstr_discrete.cap(chips)!CAP_0805-47UF,4V,20%,X6S,C9533A!!!F2357!A!!!!
S!GND!C7P9!2!@baseboard_fab2_lib.baseboard_fab2(sch_1):page76_i181@mstr_discrete.cap(chips)!CAP_0805-47UF,4V,20%,X6S,C9533A!!!F2357!B!!!!
S!PVCCMCP_CPU1!C7P5!1!@baseboard_fab2_lib.baseboard_fab2(sch_1):page76_i182@mstr_discrete.cap(chips)!CAP_0805-47UF,4V,20%,X6S,C9533A!!!F2361!A!!!!
S!GND!C7P5!2!@baseboard_fab2_lib.baseboard_fab2(sch_1):page76_i182@mstr_discrete.cap(chips)!CAP_0805-47UF,4V,20%,X6S,C9533A!!!F2361!B!!!!
S!PVCCMCP_CPU1!C7P11!1!@baseboard_fab2_lib.baseboard_fab2(sch_1):page76_i183@mstr_discrete.cap(chips)!CAP_0805-47UF,4V,20%,X6S,C9533A!!!F2355!A!!!!
S!GND!C7P11!2!@baseboard_fab2_lib.baseboard_fab2(sch_1):page76_i183@mstr_discrete.cap(chips)!CAP_0805-47UF,4V,20%,X6S,C9533A!!!F2355!B!!!!
S!PVCCMCP_CPU1!C7P8!1!@baseboard_fab2_lib.baseboard_fab2(sch_1):page76_i184@mstr_discrete.cap(chips)!CAP_0805-47UF,4V,20%,X6S,C9533A!!!F2358!A!!!!
S!GND!C7P8!2!@baseboard_fab2_lib.baseboard_fab2(sch_1):page76_i184@mstr_discrete.cap(chips)!CAP_0805-47UF,4V,20%,X6S,C9533A!!!F2358!B!!!!
S!PVCCMCP_CPU1!C7P4!1!@baseboard_fab2_lib.baseboard_fab2(sch_1):page76_i195@mstr_discrete.cap(chips)!CAP_0805-47UF,4V,20%,X6S,C9533A!!!F2362!A!!!!
S!GND!C7P4!2!@baseboard_fab2_lib.baseboard_fab2(sch_1):page76_i195@mstr_discrete.cap(chips)!CAP_0805-47UF,4V,20%,X6S,C9533A!!!F2362!B!!!!
S!PVCCMCP_CPU0!C5P29!1!@baseboard_fab2_lib.baseboard_fab2(sch_1):page42_i149@mstr_discrete.cap(chips)!CAP_0805-47UF,4V,20%,X6S,C9533A!!!F2387!A!!!!
S!GND!C5P29!2!@baseboard_fab2_lib.baseboard_fab2(sch_1):page42_i149@mstr_discrete.cap(chips)!CAP_0805-47UF,4V,20%,X6S,C9533A!!!F2387!B!!!!
S!PVCCMCP_CPU0!C5P30!1!@baseboard_fab2_lib.baseboard_fab2(sch_1):page42_i148@mstr_discrete.cap(chips)!CAP_0805-47UF,4V,20%,X6S,C9533A!!!F2386!A!!!!
S!GND!C5P30!2!@baseboard_fab2_lib.baseboard_fab2(sch_1):page42_i148@mstr_discrete.cap(chips)!CAP_0805-47UF,4V,20%,X6S,C9533A!!!F2386!B!!!!
S!PVCCMCP_CPU0!C5P31!1!@baseboard_fab2_lib.baseboard_fab2(sch_1):page42_i162@mstr_discrete.cap(chips)!CAP_0805-47UF,4V,20%,X6S,C9533A!!!F2385!A!!!!
S!GND!C5P31!2!@baseboard_fab2_lib.baseboard_fab2(sch_1):page42_i162@mstr_discrete.cap(chips)!CAP_0805-47UF,4V,20%,X6S,C9533A!!!F2385!B!!!!
S!PVCCMCP_CPU0!C4P2!1!@baseboard_fab2_lib.baseboard_fab2(sch_1):page42_i163@mstr_discrete.cap(chips)!CAP_0805-47UF,4V,20%,X6S,C9533A!!!F2417!A!!!!
S!GND!C4P2!2!@baseboard_fab2_lib.baseboard_fab2(sch_1):page42_i163@mstr_discrete.cap(chips)!CAP_0805-47UF,4V,20%,X6S,C9533A!!!F2417!B!!!!
S!PVCCMCP_CPU0!C4P5!1!@baseboard_fab2_lib.baseboard_fab2(sch_1):page42_i172@mstr_discrete.cap(chips)!CAP_0805-47UF,4V,20%,X6S,C9533A!!!F2414!A!!!!
S!GND!C4P5!2!@baseboard_fab2_lib.baseboard_fab2(sch_1):page42_i172@mstr_discrete.cap(chips)!CAP_0805-47UF,4V,20%,X6S,C9533A!!!F2414!B!!!!
S!PVCCIN_CPU0!C5P37!1!@baseboard_fab2_lib.baseboard_fab2(sch_1):page42_i63@mstr_discrete.cap(chips)!CAP_0805-47UF,4V,20%,X6S,C9533A!!!F2379!A!!!!
S!GND!C5P37!2!@baseboard_fab2_lib.baseboard_fab2(sch_1):page42_i63@mstr_discrete.cap(chips)!CAP_0805-47UF,4V,20%,X6S,C9533A!!!F2379!B!!!!
S!PVCCIN_CPU0!C5P36!1!@baseboard_fab2_lib.baseboard_fab2(sch_1):page42_i65@mstr_discrete.cap(chips)!CAP_0805-47UF,4V,20%,X6S,C9533A!!!F2380!A!!!!
S!GND!C5P36!2!@baseboard_fab2_lib.baseboard_fab2(sch_1):page42_i65@mstr_discrete.cap(chips)!CAP_0805-47UF,4V,20%,X6S,C9533A!!!F2380!B!!!!
S!PVCCIN_CPU0!C5P35!1!@baseboard_fab2_lib.baseboard_fab2(sch_1):page42_i51@mstr_discrete.cap(chips)!CAP_0805-47UF,4V,20%,X6S,C9533A!!!F2381!A!!!!
S!GND!C5P35!2!@baseboard_fab2_lib.baseboard_fab2(sch_1):page42_i51@mstr_discrete.cap(chips)!CAP_0805-47UF,4V,20%,X6S,C9533A!!!F2381!B!!!!
S!PVCCIN_CPU0!C5P34!1!@baseboard_fab2_lib.baseboard_fab2(sch_1):page42_i54@mstr_discrete.cap(chips)!CAP_0805-47UF,4V,20%,X6S,C9533A!!!F2382!A!!!!
S!GND!C5P34!2!@baseboard_fab2_lib.baseboard_fab2(sch_1):page42_i54@mstr_discrete.cap(chips)!CAP_0805-47UF,4V,20%,X6S,C9533A!!!F2382!B!!!!
S!PVCCIN_CPU0!C5P33!1!@baseboard_fab2_lib.baseboard_fab2(sch_1):page42_i50@mstr_discrete.cap(chips)!CAP_0805-47UF,4V,20%,X6S,C9533A!!!F2383!A!!!!
S!GND!C5P33!2!@baseboard_fab2_lib.baseboard_fab2(sch_1):page42_i50@mstr_discrete.cap(chips)!CAP_0805-47UF,4V,20%,X6S,C9533A!!!F2383!B!!!!
S!PVCCIN_CPU0!C5P32!1!@baseboard_fab2_lib.baseboard_fab2(sch_1):page42_i53@mstr_discrete.cap(chips)!CAP_0805-47UF,4V,20%,X6S,C9533A!!!F2384!A!!!!
S!GND!C5P32!2!@baseboard_fab2_lib.baseboard_fab2(sch_1):page42_i53@mstr_discrete.cap(chips)!CAP_0805-47UF,4V,20%,X6S,C9533A!!!F2384!B!!!!
S!PVCCMCP_CPU0!C5P20!1!@baseboard_fab2_lib.baseboard_fab2(sch_1):page42_i185@mstr_discrete.cap(chips)!CAP_0805-47UF,4V,20%,X6S,C9533A!!!F2396!A!!!!
S!GND!C5P20!2!@baseboard_fab2_lib.baseboard_fab2(sch_1):page42_i185@mstr_discrete.cap(chips)!CAP_0805-47UF,4V,20%,X6S,C9533A!!!F2396!B!!!!
S!PVCCMCP_CPU0!C5P13!1!@baseboard_fab2_lib.baseboard_fab2(sch_1):page42_i186@mstr_discrete.cap(chips)!CAP_0805-47UF,4V,20%,X6S,C9533A!!!F2403!A!!!!
S!GND!C5P13!2!@baseboard_fab2_lib.baseboard_fab2(sch_1):page42_i186@mstr_discrete.cap(chips)!CAP_0805-47UF,4V,20%,X6S,C9533A!!!F2403!B!!!!
S!PVCCIN_CPU0!C5P14!1!@baseboard_fab2_lib.baseboard_fab2(sch_1):page42_i41@mstr_discrete.cap(chips)!CAP_0805-47UF,4V,20%,X6S,C9533A!!!F2402!A!!!!
S!GND!C5P14!2!@baseboard_fab2_lib.baseboard_fab2(sch_1):page42_i41@mstr_discrete.cap(chips)!CAP_0805-47UF,4V,20%,X6S,C9533A!!!F2402!B!!!!
S!PVCCMCP_CPU0!C5P12!1!@baseboard_fab2_lib.baseboard_fab2(sch_1):page42_i183@mstr_discrete.cap(chips)!CAP_0805-47UF,4V,20%,X6S,C9533A!!!F2404!A!!!!
S!GND!C5P12!2!@baseboard_fab2_lib.baseboard_fab2(sch_1):page42_i183@mstr_discrete.cap(chips)!CAP_0805-47UF,4V,20%,X6S,C9533A!!!F2404!B!!!!
S!PVCCIO_CPU0!C4P10!1!@baseboard_fab2_lib.baseboard_fab2(sch_1):page42_i17@mstr_discrete.cap(chips)!CAP_0805-47UF,4V,20%,X6S,C9533A!!!F2411!A!!!!
S!GND!C4P10!2!@baseboard_fab2_lib.baseboard_fab2(sch_1):page42_i17@mstr_discrete.cap(chips)!CAP_0805-47UF,4V,20%,X6S,C9533A!!!F2411!B!!!!
S!PVCCIO_CPU0!C4P9!1!@baseboard_fab2_lib.baseboard_fab2(sch_1):page42_i12@mstr_discrete.cap(chips)!CAP_0805-47UF,4V,20%,X6S,C9533A!!!F2412!A!!!!
S!GND!C4P9!2!@baseboard_fab2_lib.baseboard_fab2(sch_1):page42_i12@mstr_discrete.cap(chips)!CAP_0805-47UF,4V,20%,X6S,C9533A!!!F2412!B!!!!
S!PVCCIO_CPU0!C4P1!1!@baseboard_fab2_lib.baseboard_fab2(sch_1):page42_i10@mstr_discrete.cap(chips)!CAP_0805-47UF,4V,20%,X6S,C9533A!!!F2418!A!!!!
S!GND!C4P1!2!@baseboard_fab2_lib.baseboard_fab2(sch_1):page42_i10@mstr_discrete.cap(chips)!CAP_0805-47UF,4V,20%,X6S,C9533A!!!F2418!B!!!!
S!PVCCIN_CPU1!C8P10!1!@baseboard_fab2_lib.baseboard_fab2(sch_1):page76_i127@mstr_discrete.cap(chips)!CAP_0805-47UF,4V,20%,X6S,C9533A!!!F2339!A!!!!
S!GND!C8P10!2!@baseboard_fab2_lib.baseboard_fab2(sch_1):page76_i127@mstr_discrete.cap(chips)!CAP_0805-47UF,4V,20%,X6S,C9533A!!!F2339!B!!!!
S!P1V8_PCH_STBY!C8A12!1!@baseboard_fab2_lib.baseboard_fab2(sch_1):page237_i77@mstr_discrete.cap(chips)!CAP_0805-47UF,4V,20%,X6S,C9533A!!!F2347!A!!!!
S!GND!C8A12!2!@baseboard_fab2_lib.baseboard_fab2(sch_1):page237_i77@mstr_discrete.cap(chips)!CAP_0805-47UF,4V,20%,X6S,C9533A!!!F2347!B!!!!
S!P1V8_PCH_STBY!C2L32!1!@baseboard_fab2_lib.baseboard_fab2(sch_1):page237_i79@mstr_discrete.cap(chips)!CAP_0805-47UF,4V,20%,X6S,C9533A!!!F2425!A!!!!
S!GND!C2L32!2!@baseboard_fab2_lib.baseboard_fab2(sch_1):page237_i79@mstr_discrete.cap(chips)!CAP_0805-47UF,4V,20%,X6S,C9533A!!!F2425!B!!!!
S!PVPP_DEF!C6B3!1!@baseboard_fab2_lib.baseboard_fab2(sch_1):page232_i236@mstr_discrete.cap(chips)!CAP_0805-47UF,4V,20%,X6S,C9533A!!!F2373!A!!!!
S!GND!C6B3!2!@baseboard_fab2_lib.baseboard_fab2(sch_1):page232_i236@mstr_discrete.cap(chips)!CAP_0805-47UF,4V,20%,X6S,C9533A!!!F2373!B!!!!
S!PVPP_DEF!C7B7!1!@baseboard_fab2_lib.baseboard_fab2(sch_1):page232_i238@mstr_discrete.cap(chips)!CAP_0805-47UF,4V,20%,X6S,C9533A!!!F2366!A!!!!
S!GND!C7B7!2!@baseboard_fab2_lib.baseboard_fab2(sch_1):page232_i238@mstr_discrete.cap(chips)!CAP_0805-47UF,4V,20%,X6S,C9533A!!!F2366!B!!!!
S!PVPP_GHJ!C6U3!1!@baseboard_fab2_lib.baseboard_fab2(sch_1):page233_i221@mstr_discrete.cap(chips)!CAP_0805-47UF,4V,20%,X6S,C9533A!!!F2371!A!!!!
S!GND!C6U3!2!@baseboard_fab2_lib.baseboard_fab2(sch_1):page233_i221@mstr_discrete.cap(chips)!CAP_0805-47UF,4V,20%,X6S,C9533A!!!F2371!B!!!!
S!PVPP_GHJ!C6U2!1!@baseboard_fab2_lib.baseboard_fab2(sch_1):page233_i223@mstr_discrete.cap(chips)!CAP_0805-47UF,4V,20%,X6S,C9533A!!!F2372!A!!!!
S!GND!C6U2!2!@baseboard_fab2_lib.baseboard_fab2(sch_1):page233_i223@mstr_discrete.cap(chips)!CAP_0805-47UF,4V,20%,X6S,C9533A!!!F2372!B!!!!
S!PVPP_KLM!C4B3!1!@baseboard_fab2_lib.baseboard_fab2(sch_1):page234_i177@mstr_discrete.cap(chips)!CAP_0805-47UF,4V,20%,X6S,C9533A!!!F2419!A!!!!
S!GND!C4B3!2!@baseboard_fab2_lib.baseboard_fab2(sch_1):page234_i177@mstr_discrete.cap(chips)!CAP_0805-47UF,4V,20%,X6S,C9533A!!!F2419!B!!!!
S!PVPP_KLM!C4B2!1!@baseboard_fab2_lib.baseboard_fab2(sch_1):page234_i180@mstr_discrete.cap(chips)!CAP_0805-47UF,4V,20%,X6S,C9533A!!!F2420!A!!!!
S!GND!C4B2!2!@baseboard_fab2_lib.baseboard_fab2(sch_1):page234_i180@mstr_discrete.cap(chips)!CAP_0805-47UF,4V,20%,X6S,C9533A!!!F2420!B!!!!
S!PVPP_ABC!C3T7!1!@baseboard_fab2_lib.baseboard_fab2(sch_1):page231_i184@mstr_discrete.cap(chips)!CAP_0805-47UF,4V,20%,X6S,C9533A!!!F2422!A!!!!
S!GND!C3T7!2!@baseboard_fab2_lib.baseboard_fab2(sch_1):page231_i184@mstr_discrete.cap(chips)!CAP_0805-47UF,4V,20%,X6S,C9533A!!!F2422!B!!!!
S!PVPP_ABC!C3T9!1!@baseboard_fab2_lib.baseboard_fab2(sch_1):page231_i186@mstr_discrete.cap(chips)!CAP_0805-47UF,4V,20%,X6S,C9533A!!!F2421!A!!!!
S!GND!C3T9!2!@baseboard_fab2_lib.baseboard_fab2(sch_1):page231_i186@mstr_discrete.cap(chips)!CAP_0805-47UF,4V,20%,X6S,C9533A!!!F2421!B!!!!
S!PVNN_PCH_STBY!C7A31!1!@baseboard_fab2_lib.baseboard_fab2(sch_1):page132_i40@mstr_discrete.cap(chips)!CAP_0805-47UF,4V,20%,X6S,C9533A!!!F2370!A!!!!
S!GND!C7A31!2!@baseboard_fab2_lib.baseboard_fab2(sch_1):page132_i40@mstr_discrete.cap(chips)!CAP_0805-47UF,4V,20%,X6S,C9533A!!!F2370!B!!!!
S!PVNN_PCH_STBY!C7A32!1!@baseboard_fab2_lib.baseboard_fab2(sch_1):page132_i38@mstr_discrete.cap(chips)!CAP_0805-47UF,4V,20%,X6S,C9533A!!!F2369!A!!!!
S!GND!C7A32!2!@baseboard_fab2_lib.baseboard_fab2(sch_1):page132_i38@mstr_discrete.cap(chips)!CAP_0805-47UF,4V,20%,X6S,C9533A!!!F2369!B!!!!
S!PVNN_PCH_STBY!C7B4!1!@baseboard_fab2_lib.baseboard_fab2(sch_1):page132_i24@mstr_discrete.cap(chips)!CAP_0805-47UF,4V,20%,X6S,C9533A!!!F2367!A!!!!
S!GND!C7B4!2!@baseboard_fab2_lib.baseboard_fab2(sch_1):page132_i24@mstr_discrete.cap(chips)!CAP_0805-47UF,4V,20%,X6S,C9533A!!!F2367!B!!!!
S!PVNN_PCH_STBY!C7A33!1!@baseboard_fab2_lib.baseboard_fab2(sch_1):page132_i23@mstr_discrete.cap(chips)!CAP_0805-47UF,4V,20%,X6S,C9533A!!!F2368!A!!!!
S!GND!C7A33!2!@baseboard_fab2_lib.baseboard_fab2(sch_1):page132_i23@mstr_discrete.cap(chips)!CAP_0805-47UF,4V,20%,X6S,C9533A!!!F2368!B!!!!
S!P1V05_PCH_STBY!C8B15!1!@baseboard_fab2_lib.baseboard_fab2(sch_1):page131_i24@mstr_discrete.cap(chips)!CAP_0805-47UF,4V,20%,X6S,C9533A!!!F2345!A!!!!
S!GND!C8B15!2!@baseboard_fab2_lib.baseboard_fab2(sch_1):page131_i24@mstr_discrete.cap(chips)!CAP_0805-47UF,4V,20%,X6S,C9533A!!!F2345!B!!!!
S!P1V05_PCH_STBY!C8B16!1!@baseboard_fab2_lib.baseboard_fab2(sch_1):page131_i22@mstr_discrete.cap(chips)!CAP_0805-47UF,4V,20%,X6S,C9533A!!!F2344!A!!!!
S!GND!C8B16!2!@baseboard_fab2_lib.baseboard_fab2(sch_1):page131_i22@mstr_discrete.cap(chips)!CAP_0805-47UF,4V,20%,X6S,C9533A!!!F2344!B!!!!
S!P1V05_PCH_STBY!C8A13!1!@baseboard_fab2_lib.baseboard_fab2(sch_1):page131_i37@mstr_discrete.cap(chips)!CAP_0805-47UF,4V,20%,X6S,C9533A!!!F2346!A!!!!
S!GND!C8A13!2!@baseboard_fab2_lib.baseboard_fab2(sch_1):page131_i37@mstr_discrete.cap(chips)!CAP_0805-47UF,4V,20%,X6S,C9533A!!!F2346!B!!!!
S!P1V05_PCH_STBY!C2M11!1!@baseboard_fab2_lib.baseboard_fab2(sch_1):page131_i35@mstr_discrete.cap(chips)!CAP_0805-47UF,4V,20%,X6S,C9533A!!!F2424!A!!!!
S!GND!C2M11!2!@baseboard_fab2_lib.baseboard_fab2(sch_1):page131_i35@mstr_discrete.cap(chips)!CAP_0805-47UF,4V,20%,X6S,C9533A!!!F2424!B!!!!
S!P1V05_PCH_STBY!C2M17!1!@baseboard_fab2_lib.baseboard_fab2(sch_1):page131_i34@mstr_discrete.cap(chips)!CAP_0805-47UF,4V,20%,X6S,C9533A!!!F2423!A!!!!
S!GND!C2M17!2!@baseboard_fab2_lib.baseboard_fab2(sch_1):page131_i34@mstr_discrete.cap(chips)!CAP_0805-47UF,4V,20%,X6S,C9533A!!!F2423!B!!!!
S!PVNN_PCH_STBY!C7A30!1!@baseboard_fab2_lib.baseboard_fab2(sch_1):page236_i9@mstr_discrete.cap(chips)!CAP_0805LF-22UF,4V,20%,X6S,C95A!!!F2298!A!!!!
S!GND!C7A30!2!@baseboard_fab2_lib.baseboard_fab2(sch_1):page236_i9@mstr_discrete.cap(chips)!CAP_0805LF-22UF,4V,20%,X6S,C95A!!!F2298!B!!!!
S!P1V05_PCH_STBY!C8A16!1!@baseboard_fab2_lib.baseboard_fab2(sch_1):page236_i46@mstr_discrete.cap(chips)!CAP_0805LF-22UF,4V,20%,X6S,C95A!!!F2296!A!!!!
S!GND!C8A16!2!@baseboard_fab2_lib.baseboard_fab2(sch_1):page236_i46@mstr_discrete.cap(chips)!CAP_0805LF-22UF,4V,20%,X6S,C95A!!!F2296!B!!!!
S!PVDDQ_ABC!C5P39!1!@baseboard_fab2_lib.baseboard_fab2(sch_1):page217_i184@mstr_discrete.cap(chips)!CAP_0805LF-22UF,4V,20%,X6S,C95A!!!F2302!A!!!!
S!GND!C5P39!2!@baseboard_fab2_lib.baseboard_fab2(sch_1):page217_i184@mstr_discrete.cap(chips)!CAP_0805LF-22UF,4V,20%,X6S,C95A!!!F2302!B!!!!
S!PVDDQ_ABC!C5P38!1!@baseboard_fab2_lib.baseboard_fab2(sch_1):page217_i193@mstr_discrete.cap(chips)!CAP_0805LF-22UF,4V,20%,X6S,C95A!!!F2303!A!!!!
S!GND!C5P38!2!@baseboard_fab2_lib.baseboard_fab2(sch_1):page217_i193@mstr_discrete.cap(chips)!CAP_0805LF-22UF,4V,20%,X6S,C95A!!!F2303!B!!!!
S!PVDDQ_DEF!C5P2!1!@baseboard_fab2_lib.baseboard_fab2(sch_1):page220_i177@mstr_discrete.cap(chips)!CAP_0805LF-22UF,4V,20%,X6S,C95A!!!F2307!A!!!!
S!GND!C5P2!2!@baseboard_fab2_lib.baseboard_fab2(sch_1):page220_i177@mstr_discrete.cap(chips)!CAP_0805LF-22UF,4V,20%,X6S,C95A!!!F2307!B!!!!
S!PVDDQ_DEF!C5P1!1!@baseboard_fab2_lib.baseboard_fab2(sch_1):page220_i179@mstr_discrete.cap(chips)!CAP_0805LF-22UF,4V,20%,X6S,C95A!!!F2308!A!!!!
S!GND!C5P1!2!@baseboard_fab2_lib.baseboard_fab2(sch_1):page220_i179@mstr_discrete.cap(chips)!CAP_0805LF-22UF,4V,20%,X6S,C95A!!!F2308!B!!!!
S!PVDDQ_GHJ!C8P30!1!@baseboard_fab2_lib.baseboard_fab2(sch_1):page225_i184@mstr_discrete.cap(chips)!CAP_0805LF-22UF,4V,20%,X6S,C95A!!!F2290!A!!!!
S!GND!C8P30!2!@baseboard_fab2_lib.baseboard_fab2(sch_1):page225_i184@mstr_discrete.cap(chips)!CAP_0805LF-22UF,4V,20%,X6S,C95A!!!F2290!B!!!!
S!PVDDQ_GHJ!C8P31!1!@baseboard_fab2_lib.baseboard_fab2(sch_1):page225_i178@mstr_discrete.cap(chips)!CAP_0805LF-22UF,4V,20%,X6S,C95A!!!F2289!A!!!!
S!GND!C8P31!2!@baseboard_fab2_lib.baseboard_fab2(sch_1):page225_i178@mstr_discrete.cap(chips)!CAP_0805LF-22UF,4V,20%,X6S,C95A!!!F2289!B!!!!
S!PVDDQ_KLM!C8P2!1!@baseboard_fab2_lib.baseboard_fab2(sch_1):page228_i183@mstr_discrete.cap(chips)!CAP_0805LF-22UF,4V,20%,X6S,C95A!!!F2294!A!!!!
S!GND!C8P2!2!@baseboard_fab2_lib.baseboard_fab2(sch_1):page228_i183@mstr_discrete.cap(chips)!CAP_0805LF-22UF,4V,20%,X6S,C95A!!!F2294!B!!!!
S!PVDDQ_KLM!C8P1!1!@baseboard_fab2_lib.baseboard_fab2(sch_1):page228_i185@mstr_discrete.cap(chips)!CAP_0805LF-22UF,4V,20%,X6S,C95A!!!F2295!A!!!!
S!GND!C8P1!2!@baseboard_fab2_lib.baseboard_fab2(sch_1):page228_i185@mstr_discrete.cap(chips)!CAP_0805LF-22UF,4V,20%,X6S,C95A!!!F2295!B!!!!
S!PVTT_ABC!C4G24!1!@baseboard_fab2_lib.baseboard_fab2(sch_1):page221_i20@mstr_discrete.cap(chips)!CAP_0805LF-22UF,4V,20%,X6S,C95A!!!F2309!A!!!!
S!GND!C4G24!2!@baseboard_fab2_lib.baseboard_fab2(sch_1):page221_i20@mstr_discrete.cap(chips)!CAP_0805LF-22UF,4V,20%,X6S,C95A!!!F2309!B!!!!
S!PVTT_GHJ!C4G20!1!@baseboard_fab2_lib.baseboard_fab2(sch_1):page229_i17@mstr_discrete.cap(chips)!CAP_0805LF-22UF,4V,20%,X6S,C95A!!!F2310!A!!!!
S!GND!C4G20!2!@baseboard_fab2_lib.baseboard_fab2(sch_1):page229_i17@mstr_discrete.cap(chips)!CAP_0805LF-22UF,4V,20%,X6S,C95A!!!F2310!B!!!!
S!PVTT_DEF!C4A1!1!@baseboard_fab2_lib.baseboard_fab2(sch_1):page222_i16@mstr_discrete.cap(chips)!CAP_0805LF-22UF,4V,20%,X6S,C95A!!!F2312!A!!!!
S!GND!C4A1!2!@baseboard_fab2_lib.baseboard_fab2(sch_1):page222_i16@mstr_discrete.cap(chips)!CAP_0805LF-22UF,4V,20%,X6S,C95A!!!F2312!B!!!!
S!PVTT_KLM!C4A13!1!@baseboard_fab2_lib.baseboard_fab2(sch_1):page230_i18@mstr_discrete.cap(chips)!CAP_0805LF-22UF,4V,20%,X6S,C95A!!!F2311!A!!!!
S!GND!C4A13!2!@baseboard_fab2_lib.baseboard_fab2(sch_1):page230_i18@mstr_discrete.cap(chips)!CAP_0805LF-22UF,4V,20%,X6S,C95A!!!F2311!B!!!!
S!P1V26_BMC_STBY!C9F4!1!@baseboard_fab2_lib.baseboard_fab2(sch_1):page238_i30@mstr_discrete.cap(chips)!CAP_0805LF-22UF,4V,20%,X6S,C95A!!!F2288!A!!!!
S!GND!C9F4!2!@baseboard_fab2_lib.baseboard_fab2(sch_1):page238_i30@mstr_discrete.cap(chips)!CAP_0805LF-22UF,4V,20%,X6S,C95A!!!F2288!B!!!!
S!P1V538_BMC_STBY!C9F13!1!@baseboard_fab2_lib.baseboard_fab2(sch_1):page239_i7@mstr_discrete.cap(chips)!CAP_0805LF-22UF,4V,20%,X6S,C95A!!!F2287!A!!!!
S!GND!C9F13!2!@baseboard_fab2_lib.baseboard_fab2(sch_1):page239_i7@mstr_discrete.cap(chips)!CAP_0805LF-22UF,4V,20%,X6S,C95A!!!F2287!B!!!!
S!PVDDQ_ABC!C6G3!1!@baseboard_fab2_lib.baseboard_fab2(sch_1):page216_i6@mstr_discrete.cap(chips)!CAP_0805LF-22UF,4V,20%,X6S,C95A!!!F2299!A!!!!
S!GND!C6G3!2!@baseboard_fab2_lib.baseboard_fab2(sch_1):page216_i6@mstr_discrete.cap(chips)!CAP_0805LF-22UF,4V,20%,X6S,C95A!!!F2299!B!!!!
S!PVDDQ_ABC!C7G27!1!@baseboard_fab2_lib.baseboard_fab2(sch_1):page216_i68@mstr_discrete.cap(chips)!CAP_0805LF-22UF,4V,20%,X6S,C95A!!!F2297!A!!!!
S!GND!C7G27!2!@baseboard_fab2_lib.baseboard_fab2(sch_1):page216_i68@mstr_discrete.cap(chips)!CAP_0805LF-22UF,4V,20%,X6S,C95A!!!F2297!B!!!!
S!PVSA_CPU0!C5P7!1!@baseboard_fab2_lib.baseboard_fab2(sch_1):page42_i25@mstr_discrete.cap(chips)!CAP_0805LF-22UF,4V,20%,X6S,C95A!!!F2306!A!!!!
S!GND!C5P7!2!@baseboard_fab2_lib.baseboard_fab2(sch_1):page42_i25@mstr_discrete.cap(chips)!CAP_0805LF-22UF,4V,20%,X6S,C95A!!!F2306!B!!!!
S!PVDDQ_GHJ!C1G17!1!@baseboard_fab2_lib.baseboard_fab2(sch_1):page224_i6@mstr_discrete.cap(chips)!CAP_0805LF-22UF,4V,20%,X6S,C95A!!!F2314!A!!!!
S!GND!C1G17!2!@baseboard_fab2_lib.baseboard_fab2(sch_1):page224_i6@mstr_discrete.cap(chips)!CAP_0805LF-22UF,4V,20%,X6S,C95A!!!F2314!B!!!!
S!PVDDQ_DEF!C6A1!1!@baseboard_fab2_lib.baseboard_fab2(sch_1):page219_i87@mstr_discrete.cap(chips)!CAP_0805LF-22UF,4V,20%,X6S,C95A!!!F2301!A!!!!
S!GND!C6A1!2!@baseboard_fab2_lib.baseboard_fab2(sch_1):page219_i87@mstr_discrete.cap(chips)!CAP_0805LF-22UF,4V,20%,X6S,C95A!!!F2301!B!!!!
S!PVDDQ_DEF!C6A4!1!@baseboard_fab2_lib.baseboard_fab2(sch_1):page219_i68@mstr_discrete.cap(chips)!CAP_0805LF-22UF,4V,20%,X6S,C95A!!!F2300!A!!!!
S!GND!C6A4!2!@baseboard_fab2_lib.baseboard_fab2(sch_1):page219_i68@mstr_discrete.cap(chips)!CAP_0805LF-22UF,4V,20%,X6S,C95A!!!F2300!B!!!!
S!PVDDQ_KLM!C1A1!1!@baseboard_fab2_lib.baseboard_fab2(sch_1):page227_i68@mstr_discrete.cap(chips)!CAP_0805LF-22UF,4V,20%,X6S,C95A!!!F2316!A!!!!
S!GND!C1A1!2!@baseboard_fab2_lib.baseboard_fab2(sch_1):page227_i68@mstr_discrete.cap(chips)!CAP_0805LF-22UF,4V,20%,X6S,C95A!!!F2316!B!!!!
S!PVDDQ_GHJ!C1G20!1!@baseboard_fab2_lib.baseboard_fab2(sch_1):page224_i68@mstr_discrete.cap(chips)!CAP_0805LF-22UF,4V,20%,X6S,C95A!!!F2313!A!!!!
S!GND!C1G20!2!@baseboard_fab2_lib.baseboard_fab2(sch_1):page224_i68@mstr_discrete.cap(chips)!CAP_0805LF-22UF,4V,20%,X6S,C95A!!!F2313!B!!!!
S!PVDDQ_KLM!C1A12!1!@baseboard_fab2_lib.baseboard_fab2(sch_1):page227_i6@mstr_discrete.cap(chips)!CAP_0805LF-22UF,4V,20%,X6S,C95A!!!F2315!A!!!!
S!GND!C1A12!2!@baseboard_fab2_lib.baseboard_fab2(sch_1):page227_i6@mstr_discrete.cap(chips)!CAP_0805LF-22UF,4V,20%,X6S,C95A!!!F2315!B!!!!
S!PVSA_CPU0!C5P8!1!@baseboard_fab2_lib.baseboard_fab2(sch_1):page42_i19@mstr_discrete.cap(chips)!CAP_0805LF-22UF,4V,20%,X6S,C95A!!!F2305!A!!!!
S!GND!C5P8!2!@baseboard_fab2_lib.baseboard_fab2(sch_1):page42_i19@mstr_discrete.cap(chips)!CAP_0805LF-22UF,4V,20%,X6S,C95A!!!F2305!B!!!!
S!PVSA_CPU0!C5P9!1!@baseboard_fab2_lib.baseboard_fab2(sch_1):page42_i18@mstr_discrete.cap(chips)!CAP_0805LF-22UF,4V,20%,X6S,C95A!!!F2304!A!!!!
S!GND!C5P9!2!@baseboard_fab2_lib.baseboard_fab2(sch_1):page42_i18@mstr_discrete.cap(chips)!CAP_0805LF-22UF,4V,20%,X6S,C95A!!!F2304!B!!!!
S!PVSA_CPU1!C8P5!1!@baseboard_fab2_lib.baseboard_fab2(sch_1):page76_i58@mstr_discrete.cap(chips)!CAP_0805LF-22UF,4V,20%,X6S,C95A!!!F2293!A!!!!
S!GND!C8P5!2!@baseboard_fab2_lib.baseboard_fab2(sch_1):page76_i58@mstr_discrete.cap(chips)!CAP_0805LF-22UF,4V,20%,X6S,C95A!!!F2293!B!!!!
S!PVSA_CPU1!C8P6!1!@baseboard_fab2_lib.baseboard_fab2(sch_1):page76_i55@mstr_discrete.cap(chips)!CAP_0805LF-22UF,4V,20%,X6S,C95A!!!F2292!A!!!!
S!GND!C8P6!2!@baseboard_fab2_lib.baseboard_fab2(sch_1):page76_i55@mstr_discrete.cap(chips)!CAP_0805LF-22UF,4V,20%,X6S,C95A!!!F2292!B!!!!
S!PVSA_CPU1!C8P7!1!@baseboard_fab2_lib.baseboard_fab2(sch_1):page76_i50@mstr_discrete.cap(chips)!CAP_0805LF-22UF,4V,20%,X6S,C95A!!!F2291!A!!!!
S!GND!C8P7!2!@baseboard_fab2_lib.baseboard_fab2(sch_1):page76_i50@mstr_discrete.cap(chips)!CAP_0805LF-22UF,4V,20%,X6S,C95A!!!F2291!B!!!!
S!VR_FET_SW_P12V_STBY_PVPP_DEF!C7B8!1!@baseboard_fab2_lib.baseboard_fab2(sch_1):page232_i202@mstr_discrete.cap(chips)!CAP_1210-47UF,16V,20%,X6S,D384A!!!F2267!A!!!!
S!GND!C7B8!2!@baseboard_fab2_lib.baseboard_fab2(sch_1):page232_i202@mstr_discrete.cap(chips)!CAP_1210-47UF,16V,20%,X6S,D384A!!!F2267!B!!!!
S!VR_FET_SW_P12V_STBY_PVPP_GHJ!C4G5!1!@baseboard_fab2_lib.baseboard_fab2(sch_1):page233_i189@mstr_discrete.cap(chips)!CAP_1210-47UF,16V,20%,X6S,D384A!!!F2268!A!!!!
S!GND!C4G5!2!@baseboard_fab2_lib.baseboard_fab2(sch_1):page233_i189@mstr_discrete.cap(chips)!CAP_1210-47UF,16V,20%,X6S,D384A!!!F2268!B!!!!
S!VR_FET_SW_P12V_STBY_PVPP_KLM!C4B1!1!@baseboard_fab2_lib.baseboard_fab2(sch_1):page234_i130@mstr_discrete.cap(chips)!CAP_1210-47UF,16V,20%,X6S,D384A!!!F2269!A!!!!
S!GND!C4B1!2!@baseboard_fab2_lib.baseboard_fab2(sch_1):page234_i130@mstr_discrete.cap(chips)!CAP_1210-47UF,16V,20%,X6S,D384A!!!F2269!B!!!!
S!VR_FET_SW_P12V_STBY_PVPP_ABC!C7F7!1!@baseboard_fab2_lib.baseboard_fab2(sch_1):page231_i151@mstr_discrete.cap(chips)!CAP_1210-47UF,16V,20%,X6S,D384A!!!F2264!A!!!!
S!GND!C7F7!2!@baseboard_fab2_lib.baseboard_fab2(sch_1):page231_i151@mstr_discrete.cap(chips)!CAP_1210-47UF,16V,20%,X6S,D384A!!!F2264!B!!!!
S!VR_FET_SW_P12V_STBY_P3V3_STBY!C9F1!1!@baseboard_fab2_lib.baseboard_fab2(sch_1):page240_i134@mstr_discrete.cap(chips)!CAP_1210-47UF,16V,20%,X6S,D384A!!!F2262!A!!!!
S!GND!C9F1!2!@baseboard_fab2_lib.baseboard_fab2(sch_1):page240_i134@mstr_discrete.cap(chips)!CAP_1210-47UF,16V,20%,X6S,D384A!!!F2262!B!!!!
S!VR_FET_SW_P12V_STBY_P3V3_STBY!C8E11!1!@baseboard_fab2_lib.baseboard_fab2(sch_1):page240_i135@mstr_discrete.cap(chips)!CAP_1210-47UF,16V,20%,X6S,D384A!!!F2263!A!!!!
S!GND!C8E11!2!@baseboard_fab2_lib.baseboard_fab2(sch_1):page240_i135@mstr_discrete.cap(chips)!CAP_1210-47UF,16V,20%,X6S,D384A!!!F2263!B!!!!
S!VR_FET_SW_P12V_STBY_PVDDQ_GHJ!C1G15!1!@baseboard_fab2_lib.baseboard_fab2(sch_1):page225_i192@mstr_discrete.cap(chips)!CAP_1210-47UF,16V,20%,X6S,D384A!!!F2270!A!!!!
S!GND!C1G15!2!@baseboard_fab2_lib.baseboard_fab2(sch_1):page225_i192@mstr_discrete.cap(chips)!CAP_1210-47UF,16V,20%,X6S,D384A!!!F2270!B!!!!
S!VR_FET_SW_P12V_STBY_PVDDQ_GHJ!C1G12!1!@baseboard_fab2_lib.baseboard_fab2(sch_1):page225_i193@mstr_discrete.cap(chips)!CAP_1210-47UF,16V,20%,X6S,D384A!!!F2271!A!!!!
S!GND!C1G12!2!@baseboard_fab2_lib.baseboard_fab2(sch_1):page225_i193@mstr_discrete.cap(chips)!CAP_1210-47UF,16V,20%,X6S,D384A!!!F2271!B!!!!
S!VR_FET_SW_P12V_STBY_PVDDQ_GHJ!C1G2!1!@baseboard_fab2_lib.baseboard_fab2(sch_1):page225_i194@mstr_discrete.cap(chips)!CAP_1210-47UF,16V,20%,X6S,D384A!!!F2273!A!!!!
S!GND!C1G2!2!@baseboard_fab2_lib.baseboard_fab2(sch_1):page225_i194@mstr_discrete.cap(chips)!CAP_1210-47UF,16V,20%,X6S,D384A!!!F2273!B!!!!
S!VR_FET_SW_P12V_STBY_PVDDQ_GHJ!C1G7!1!@baseboard_fab2_lib.baseboard_fab2(sch_1):page225_i195@mstr_discrete.cap(chips)!CAP_1210-47UF,16V,20%,X6S,D384A!!!F2272!A!!!!
S!GND!C1G7!2!@baseboard_fab2_lib.baseboard_fab2(sch_1):page225_i195@mstr_discrete.cap(chips)!CAP_1210-47UF,16V,20%,X6S,D384A!!!F2272!B!!!!
S!VR_FET_SW_P5V_STBY_PVIN!C7E12!1!@baseboard_fab2_lib.baseboard_fab2(sch_1):page241_i47@mstr_discrete.cap(chips)!CAP_1210-47UF,16V,20%,X6S,D384A!!!F2266!A!!!!
S!GND!C7E12!2!@baseboard_fab2_lib.baseboard_fab2(sch_1):page241_i47@mstr_discrete.cap(chips)!CAP_1210-47UF,16V,20%,X6S,D384A!!!F2266!B!!!!
S!VR_FET_SW_P5V_STBY_PVIN!C7E13!1!@baseboard_fab2_lib.baseboard_fab2(sch_1):page241_i45@mstr_discrete.cap(chips)!CAP_1210-47UF,16V,20%,X6S,D384A!!!F2265!A!!!!
S!GND!C7E13!2!@baseboard_fab2_lib.baseboard_fab2(sch_1):page241_i45@mstr_discrete.cap(chips)!CAP_1210-47UF,16V,20%,X6S,D384A!!!F2265!B!!!!
S!USB2_P01_DN!L1M2!1!@baseboard_fab2_lib.baseboard_fab2(sch_1):page176_i30@mstr_discrete.choke_4pin(chips)!CHOKE_4PIN_SMLF-90 OHM,EMPTY,7A!!!F2261!A1!!!!
S!USB2_P01_DP!L1M2!2!@baseboard_fab2_lib.baseboard_fab2(sch_1):page176_i30@mstr_discrete.choke_4pin(chips)!CHOKE_4PIN_SMLF-90 OHM,EMPTY,7A!!!F2261!A2!!!!
S!USB2_P01_ESD_DP!L1M2!3!@baseboard_fab2_lib.baseboard_fab2(sch_1):page176_i30@mstr_discrete.choke_4pin(chips)!CHOKE_4PIN_SMLF-90 OHM,EMPTY,7A!!!F2261!B1!!!!
S!USB2_P01_ESD_DN!L1M2!4!@baseboard_fab2_lib.baseboard_fab2(sch_1):page176_i30@mstr_discrete.choke_4pin(chips)!CHOKE_4PIN_SMLF-90 OHM,EMPTY,7A!!!F2261!B2!!!!
S!P3V3_STBY!CR2U1!1!@baseboard_fab2_lib.baseboard_fab2(sch_1):page196_i53@mstr_discrete.diode2a_dual(chips)!DIODE2A_DUAL_SMLF-BAS70-05,DIOA!!!F2225!A1!!!!
S!A_P3V_BAT_R!CR2U1!2!@baseboard_fab2_lib.baseboard_fab2(sch_1):page196_i53@mstr_discrete.diode2a_dual(chips)!DIODE2A_DUAL_SMLF-BAS70-05,DIOA!!!F2225!A2!!!!
S!P3V3_RTC_STBY!CR2U1!3!@baseboard_fab2_lib.baseboard_fab2(sch_1):page196_i53@mstr_discrete.diode2a_dual(chips)!DIODE2A_DUAL_SMLF-BAS70-05,DIOA!!!F2225!C!!!!
S!USB2_P01_ESD_DP!CR1M2!1!@baseboard_fab2_lib.baseboard_fab2(sch_1):page176_i98@mstr_discrete.diodeac_dual_array(chips)!DIODEAC_DUAL_ARRAY_SM9-ESD3V3UA!!!F2223!AC0!!!!
S!USB2_P01_ESD_DN!CR1M2!2!@baseboard_fab2_lib.baseboard_fab2(sch_1):page176_i98@mstr_discrete.diodeac_dual_array(chips)!DIODEAC_DUAL_ARRAY_SM9-ESD3V3UA!!!F2223!AC1!!!!
S!TP_USB_ESD_AC2!CR1M2!4!@baseboard_fab2_lib.baseboard_fab2(sch_1):page176_i98@mstr_discrete.diodeac_dual_array(chips)!DIODEAC_DUAL_ARRAY_SM9-ESD3V3UA!!!F2223!AC2!!!!
S!TP_USB_ESD_AC3!CR1M2!5!@baseboard_fab2_lib.baseboard_fab2(sch_1):page176_i98@mstr_discrete.diodeac_dual_array(chips)!DIODEAC_DUAL_ARRAY_SM9-ESD3V3UA!!!F2223!AC3!!!!
S!GND!CR1M2!3!@baseboard_fab2_lib.baseboard_fab2(sch_1):page176_i98@mstr_discrete.diodeac_dual_array(chips)!DIODEAC_DUAL_ARRAY_SM9-ESD3V3UA!!!F2223!GND(0)!!!!
S!USB2_P01_ESD_DP!CR1M2!9!@baseboard_fab2_lib.baseboard_fab2(sch_1):page176_i98@mstr_discrete.diodeac_dual_array(chips)!DIODEAC_DUAL_ARRAY_SM9-ESD3V3UA!!!F2223!OUT0!!!!
S!USB2_P01_ESD_DN!CR1M2!8!@baseboard_fab2_lib.baseboard_fab2(sch_1):page176_i98@mstr_discrete.diodeac_dual_array(chips)!DIODEAC_DUAL_ARRAY_SM9-ESD3V3UA!!!F2223!OUT1!!!!
S!TP_USB_ESD_OUT2!CR1M2!7!@baseboard_fab2_lib.baseboard_fab2(sch_1):page176_i98@mstr_discrete.diodeac_dual_array(chips)!DIODEAC_DUAL_ARRAY_SM9-ESD3V3UA!!!F2223!OUT2!!!!
S!TP_USB_ESD_OUT3!CR1M2!6!@baseboard_fab2_lib.baseboard_fab2(sch_1):page176_i98@mstr_discrete.diodeac_dual_array(chips)!DIODEAC_DUAL_ARRAY_SM9-ESD3V3UA!!!F2223!OUT3!!!!
S!USB3_P01_FB_TXN!CR1M1!1!@baseboard_fab2_lib.baseboard_fab2(sch_1):page176_i52@mstr_discrete.diodeac_dual_array(chips)!DIODEAC_DUAL_ARRAY_SM9-ESD3V3UA!!!F2224!AC0!!!!
S!USB3_P01_FB_TXP!CR1M1!2!@baseboard_fab2_lib.baseboard_fab2(sch_1):page176_i52@mstr_discrete.diodeac_dual_array(chips)!DIODEAC_DUAL_ARRAY_SM9-ESD3V3UA!!!F2224!AC1!!!!
S!USB3_P01_FB_RXN!CR1M1!4!@baseboard_fab2_lib.baseboard_fab2(sch_1):page176_i52@mstr_discrete.diodeac_dual_array(chips)!DIODEAC_DUAL_ARRAY_SM9-ESD3V3UA!!!F2224!AC2!!!!
S!USB3_P01_FB_RXP!CR1M1!5!@baseboard_fab2_lib.baseboard_fab2(sch_1):page176_i52@mstr_discrete.diodeac_dual_array(chips)!DIODEAC_DUAL_ARRAY_SM9-ESD3V3UA!!!F2224!AC3!!!!
S!GND!CR1M1!3!@baseboard_fab2_lib.baseboard_fab2(sch_1):page176_i52@mstr_discrete.diodeac_dual_array(chips)!DIODEAC_DUAL_ARRAY_SM9-ESD3V3UA!!!F2224!GND(0)!!!!
S!USB3_P01_FB_TXN!CR1M1!9!@baseboard_fab2_lib.baseboard_fab2(sch_1):page176_i52@mstr_discrete.diodeac_dual_array(chips)!DIODEAC_DUAL_ARRAY_SM9-ESD3V3UA!!!F2224!OUT0!!!!
S!USB3_P01_FB_TXP!CR1M1!8!@baseboard_fab2_lib.baseboard_fab2(sch_1):page176_i52@mstr_discrete.diodeac_dual_array(chips)!DIODEAC_DUAL_ARRAY_SM9-ESD3V3UA!!!F2224!OUT1!!!!
S!USB3_P01_FB_RXN!CR1M1!7!@baseboard_fab2_lib.baseboard_fab2(sch_1):page176_i52@mstr_discrete.diodeac_dual_array(chips)!DIODEAC_DUAL_ARRAY_SM9-ESD3V3UA!!!F2224!OUT2!!!!
S!USB3_P01_FB_RXP!CR1M1!6!@baseboard_fab2_lib.baseboard_fab2(sch_1):page176_i52@mstr_discrete.diodeac_dual_array(chips)!DIODEAC_DUAL_ARRAY_SM9-ESD3V3UA!!!F2224!OUT3!!!!
S!P12V_STBY!FB7B1!1!@baseboard_fab2_lib.baseboard_fab2(sch_1):page232_i200@mstr_discrete.ferrite(chips)!FERRITE_SM-22,FB,656554-051!!!F2196!A!!!!
S!VR_FET_SW_P12V_STBY_PVPP_DEF!FB7B1!2!@baseboard_fab2_lib.baseboard_fab2(sch_1):page232_i200@mstr_discrete.ferrite(chips)!FERRITE_SM-22,FB,656554-051!!!F2196!B!!!!
S!P12V_STBY!FB4G1!1!@baseboard_fab2_lib.baseboard_fab2(sch_1):page233_i198@mstr_discrete.ferrite(chips)!FERRITE_SM-22,FB,656554-051!!!F2197!A!!!!
S!VR_FET_SW_P12V_STBY_PVPP_GHJ!FB4G1!2!@baseboard_fab2_lib.baseboard_fab2(sch_1):page233_i198@mstr_discrete.ferrite(chips)!FERRITE_SM-22,FB,656554-051!!!F2197!B!!!!
S!P12V_STBY!FB4A1!1!@baseboard_fab2_lib.baseboard_fab2(sch_1):page234_i154@mstr_discrete.ferrite(chips)!FERRITE_SM-22,FB,656554-051!!!F2198!A!!!!
S!VR_FET_SW_P12V_STBY_PVPP_KLM!FB4A1!2!@baseboard_fab2_lib.baseboard_fab2(sch_1):page234_i154@mstr_discrete.ferrite(chips)!FERRITE_SM-22,FB,656554-051!!!F2198!B!!!!
S!P12V_STBY!FB7F1!1!@baseboard_fab2_lib.baseboard_fab2(sch_1):page231_i162@mstr_discrete.ferrite(chips)!FERRITE_SM-22,FB,656554-051!!!F2194!A!!!!
S!VR_FET_SW_P12V_STBY_PVPP_ABC!FB7F1!2!@baseboard_fab2_lib.baseboard_fab2(sch_1):page231_i162@mstr_discrete.ferrite(chips)!FERRITE_SM-22,FB,656554-051!!!F2194!B!!!!
S!P12V_STBY!FB9E1!1!@baseboard_fab2_lib.baseboard_fab2(sch_1):page240_i132@mstr_discrete.ferrite(chips)!FERRITE_SM-22,FB,656554-051!!!F2193!A!!!!
S!VR_FET_SW_P12V_STBY_P3V3_STBY!FB9E1!2!@baseboard_fab2_lib.baseboard_fab2(sch_1):page240_i132@mstr_discrete.ferrite(chips)!FERRITE_SM-22,FB,656554-051!!!F2193!B!!!!
S!P12V_STBY!FB7E1!1!@baseboard_fab2_lib.baseboard_fab2(sch_1):page241_i82@mstr_discrete.ferrite(chips)!FERRITE_SM-22,FB,656554-051!!!F2195!A!!!!
S!VR_FET_SW_P5V_STBY_PVIN!FB7E1!2!@baseboard_fab2_lib.baseboard_fab2(sch_1):page241_i82@mstr_discrete.ferrite(chips)!FERRITE_SM-22,FB,656554-051!!!F2195!B!!!!
S!A_PVNN_STBY_PCH_SENSOR!FB1U4!1!@baseboard_fab2_lib.baseboard_fab2(sch_1):page169_i155@mstr_discrete.ferrite(chips)!FERRITE_SMLF-30,FB,693286-021!!!F2191!A!!!!
S!PVNN_PCH_STBY!FB1U4!2!@baseboard_fab2_lib.baseboard_fab2(sch_1):page169_i155@mstr_discrete.ferrite(chips)!FERRITE_SMLF-30,FB,693286-021!!!F2191!B!!!!
S!A_P1V05_STBY_PCH_SENSOR!FB1U3!1!@baseboard_fab2_lib.baseboard_fab2(sch_1):page169_i57@mstr_discrete.ferrite(chips)!FERRITE_SMLF-30,FB,693286-021!!!F2192!A!!!!
S!P1V05_PCH_STBY!FB1U3!2!@baseboard_fab2_lib.baseboard_fab2(sch_1):page169_i57@mstr_discrete.ferrite(chips)!FERRITE_SMLF-30,FB,693286-021!!!F2192!B!!!!
S!H_CPU_BMCINIT_R!Q4C1!6!@baseboard_fab2_lib.baseboard_fab2(sch_1):page156_i291@mstr_discrete.fet_n_dual(chips)!FET_N_DUAL_SMLF-NTJD4001N,FET,A!1!!F2164!DRAIN(0)!!!!
S!FM_BMC_CPU_INIT_N!Q4C1!2!@baseboard_fab2_lib.baseboard_fab2(sch_1):page156_i291@mstr_discrete.fet_n_dual(chips)!FET_N_DUAL_SMLF-NTJD4001N,FET,A!1!!F2164!GATE(0)!!!!
S!GND!Q4C1!1!@baseboard_fab2_lib.baseboard_fab2(sch_1):page156_i291@mstr_discrete.fet_n_dual(chips)!FET_N_DUAL_SMLF-NTJD4001N,FET,A!1!!F2164!SOURCE(0)!!!!
S!FM_BMC_CPU_INIT_N!Q4C1!3!@baseboard_fab2_lib.baseboard_fab2(sch_1):page156_i290@mstr_discrete.fet_n_dual(chips)!FET_N_DUAL_SMLF-NTJD4001N,FET,A!1!!F2163!DRAIN(0)!!!!
S!FM_CPU_BMC_INIT!Q4C1!5!@baseboard_fab2_lib.baseboard_fab2(sch_1):page156_i290@mstr_discrete.fet_n_dual(chips)!FET_N_DUAL_SMLF-NTJD4001N,FET,A!1!!F2163!GATE(0)!!!!
S!GND!Q4C1!4!@baseboard_fab2_lib.baseboard_fab2(sch_1):page156_i290@mstr_discrete.fet_n_dual(chips)!FET_N_DUAL_SMLF-NTJD4001N,FET,A!1!!F2163!SOURCE(0)!!!!
S!FM_BATTERY_SENSE_EN!Q9G1!6!@baseboard_fab2_lib.baseboard_fab2(sch_1):page169_i162@mstr_discrete.fet_n_dual(chips)!FET_N_DUAL_SMLF-NTJD4001N,FET,A!1!!F2146!DRAIN(0)!!!!
S!FM_BATTERY_SENSE_EN_N!Q9G1!2!@baseboard_fab2_lib.baseboard_fab2(sch_1):page169_i162@mstr_discrete.fet_n_dual(chips)!FET_N_DUAL_SMLF-NTJD4001N,FET,A!1!!F2146!GATE(0)!!!!
S!GND!Q9G1!1!@baseboard_fab2_lib.baseboard_fab2(sch_1):page169_i162@mstr_discrete.fet_n_dual(chips)!FET_N_DUAL_SMLF-NTJD4001N,FET,A!1!!F2146!SOURCE(0)!!!!
S!P3V_BAT_SOURCE_R!Q9G1!3!@baseboard_fab2_lib.baseboard_fab2(sch_1):page169_i157@mstr_discrete.fet_n_dual(chips)!FET_N_DUAL_SMLF-NTJD4001N,FET,A!1!!F2145!DRAIN(0)!!!!
S!FM_BATTERY_SENSE_EN!Q9G1!5!@baseboard_fab2_lib.baseboard_fab2(sch_1):page169_i157@mstr_discrete.fet_n_dual(chips)!FET_N_DUAL_SMLF-NTJD4001N,FET,A!1!!F2145!GATE(0)!!!!
S!A_P3V_BAT_SCALED!Q9G1!4!@baseboard_fab2_lib.baseboard_fab2(sch_1):page169_i157@mstr_discrete.fet_n_dual(chips)!FET_N_DUAL_SMLF-NTJD4001N,FET,A!1!!F2145!SOURCE(0)!!!!
S!P5V_STBY!Q1L2!6!@baseboard_fab2_lib.baseboard_fab2(sch_1):page155_i188@mstr_discrete.fet_n_dual(chips)!FET_N_DUAL_SMLF-NTJD4001N,FET,A!1!!F2176!DRAIN(0)!!!!
S!FM_CPLD_DBG_PWR_EN!Q1L2!2!@baseboard_fab2_lib.baseboard_fab2(sch_1):page155_i188@mstr_discrete.fet_n_dual(chips)!FET_N_DUAL_SMLF-NTJD4001N,FET,A!1!!F2176!GATE(0)!!!!
S!P5V_STBY_DBG!Q1L2!1!@baseboard_fab2_lib.baseboard_fab2(sch_1):page155_i188@mstr_discrete.fet_n_dual(chips)!FET_N_DUAL_SMLF-NTJD4001N,FET,A!1!!F2176!SOURCE(0)!!!!
S!FM_CPLD_DBG_PWR_EN!Q1L2!3!@baseboard_fab2_lib.baseboard_fab2(sch_1):page155_i187@mstr_discrete.fet_n_dual(chips)!FET_N_DUAL_SMLF-NTJD4001N,FET,A!1!!F2175!DRAIN(0)!!!!
S!FM_CPLD_DBG_PWR_EN_R_N!Q1L2!5!@baseboard_fab2_lib.baseboard_fab2(sch_1):page155_i187@mstr_discrete.fet_n_dual(chips)!FET_N_DUAL_SMLF-NTJD4001N,FET,A!1!!F2175!GATE(0)!!!!
S!GND!Q1L2!4!@baseboard_fab2_lib.baseboard_fab2(sch_1):page155_i187@mstr_discrete.fet_n_dual(chips)!FET_N_DUAL_SMLF-NTJD4001N,FET,A!1!!F2175!SOURCE(0)!!!!
S!FM_BMC_FAULT_LED!Q9F1!6!@baseboard_fab2_lib.baseboard_fab2(sch_1):page177_i80@mstr_discrete.fet_n_dual(chips)!FET_N_DUAL_SMLF-NTJD4001N,FET,A!1!!F2148!DRAIN(0)!!!!
S!FM_BMC_FAULT_LED_N!Q9F1!2!@baseboard_fab2_lib.baseboard_fab2(sch_1):page177_i80@mstr_discrete.fet_n_dual(chips)!FET_N_DUAL_SMLF-NTJD4001N,FET,A!1!!F2148!GATE(0)!!!!
S!GND!Q9F1!1!@baseboard_fab2_lib.baseboard_fab2(sch_1):page177_i80@mstr_discrete.fet_n_dual(chips)!FET_N_DUAL_SMLF-NTJD4001N,FET,A!1!!F2148!SOURCE(0)!!!!
S!FM_RED_LED_CATHODE!Q9F1!3!@baseboard_fab2_lib.baseboard_fab2(sch_1):page177_i79@mstr_discrete.fet_n_dual(chips)!FET_N_DUAL_SMLF-NTJD4001N,FET,A!1!!F2147!DRAIN(0)!!!!
S!FM_BMC_FAULT_LED!Q9F1!5!@baseboard_fab2_lib.baseboard_fab2(sch_1):page177_i79@mstr_discrete.fet_n_dual(chips)!FET_N_DUAL_SMLF-NTJD4001N,FET,A!1!!F2147!GATE(0)!!!!
S!GND!Q9F1!4!@baseboard_fab2_lib.baseboard_fab2(sch_1):page177_i79@mstr_discrete.fet_n_dual(chips)!FET_N_DUAL_SMLF-NTJD4001N,FET,A!1!!F2147!SOURCE(0)!!!!
S!FM_PWR_LED!Q9A2!6!@baseboard_fab2_lib.baseboard_fab2(sch_1):page119_i175@mstr_discrete.fet_n_dual(chips)!FET_N_DUAL_SMLF-NTJD4001N,FET,A!1!!F2152!DRAIN(0)!!!!
S!FM_PWR_LED_N!Q9A2!2!@baseboard_fab2_lib.baseboard_fab2(sch_1):page119_i175@mstr_discrete.fet_n_dual(chips)!FET_N_DUAL_SMLF-NTJD4001N,FET,A!1!!F2152!GATE(0)!!!!
S!GND!Q9A2!1!@baseboard_fab2_lib.baseboard_fab2(sch_1):page119_i175@mstr_discrete.fet_n_dual(chips)!FET_N_DUAL_SMLF-NTJD4001N,FET,A!1!!F2152!SOURCE(0)!!!!
S!FM_PWR_LED_K!Q9A2!3!@baseboard_fab2_lib.baseboard_fab2(sch_1):page119_i180@mstr_discrete.fet_n_dual(chips)!FET_N_DUAL_SMLF-NTJD4001N,FET,A!1!!F2151!DRAIN(0)!!!!
S!FM_PWR_LED!Q9A2!5!@baseboard_fab2_lib.baseboard_fab2(sch_1):page119_i180@mstr_discrete.fet_n_dual(chips)!FET_N_DUAL_SMLF-NTJD4001N,FET,A!1!!F2151!GATE(0)!!!!
S!GND!Q9A2!4!@baseboard_fab2_lib.baseboard_fab2(sch_1):page119_i180@mstr_discrete.fet_n_dual(chips)!FET_N_DUAL_SMLF-NTJD4001N,FET,A!1!!F2151!SOURCE(0)!!!!
S!FM_HEARTBEAT_LED!Q9E1!6!@baseboard_fab2_lib.baseboard_fab2(sch_1):page147_i135@mstr_discrete.fet_n_dual(chips)!FET_N_DUAL_SMLF-NTJD4001N,FET,A!1!!F2150!DRAIN(0)!!!!
S!FM_BMC_HEARTBEAT_N!Q9E1!2!@baseboard_fab2_lib.baseboard_fab2(sch_1):page147_i135@mstr_discrete.fet_n_dual(chips)!FET_N_DUAL_SMLF-NTJD4001N,FET,A!1!!F2150!GATE(0)!!!!
S!GND!Q9E1!1!@baseboard_fab2_lib.baseboard_fab2(sch_1):page147_i135@mstr_discrete.fet_n_dual(chips)!FET_N_DUAL_SMLF-NTJD4001N,FET,A!1!!F2150!SOURCE(0)!!!!
S!FM_HEARTBEAT_LED_K!Q9E1!3!@baseboard_fab2_lib.baseboard_fab2(sch_1):page147_i55@mstr_discrete.fet_n_dual(chips)!FET_N_DUAL_SMLF-NTJD4001N,FET,A!1!!F2149!DRAIN(0)!!!!
S!FM_HEARTBEAT_LED!Q9E1!5!@baseboard_fab2_lib.baseboard_fab2(sch_1):page147_i55@mstr_discrete.fet_n_dual(chips)!FET_N_DUAL_SMLF-NTJD4001N,FET,A!1!!F2149!GATE(0)!!!!
S!GND!Q9E1!4!@baseboard_fab2_lib.baseboard_fab2(sch_1):page147_i55@mstr_discrete.fet_n_dual(chips)!FET_N_DUAL_SMLF-NTJD4001N,FET,A!1!!F2149!SOURCE(0)!!!!
S!IRQ_CPU0_VRHOT!Q7E5!6!@baseboard_fab2_lib.baseboard_fab2(sch_1):page95_i111@mstr_discrete.fet_n_dual(chips)!FET_N_DUAL_SMLF-NTJD4001N,FET,A!1!!F2156!DRAIN(0)!!!!
S!IRQ_CPU0_PROCHOT_G_N!Q7E5!2!@baseboard_fab2_lib.baseboard_fab2(sch_1):page95_i111@mstr_discrete.fet_n_dual(chips)!FET_N_DUAL_SMLF-NTJD4001N,FET,A!1!!F2156!GATE(0)!!!!
S!GND!Q7E5!1!@baseboard_fab2_lib.baseboard_fab2(sch_1):page95_i111@mstr_discrete.fet_n_dual(chips)!FET_N_DUAL_SMLF-NTJD4001N,FET,A!1!!F2156!SOURCE(0)!!!!
S!H_CPU0_PROCHOT_G_N!Q7E5!3!@baseboard_fab2_lib.baseboard_fab2(sch_1):page95_i59@mstr_discrete.fet_n_dual(chips)!FET_N_DUAL_SMLF-NTJD4001N,FET,A!1!!F2155!DRAIN(0)!!!!
S!IRQ_CPU0_VRHOT!Q7E5!5!@baseboard_fab2_lib.baseboard_fab2(sch_1):page95_i59@mstr_discrete.fet_n_dual(chips)!FET_N_DUAL_SMLF-NTJD4001N,FET,A!1!!F2155!GATE(0)!!!!
S!GND!Q7E5!4!@baseboard_fab2_lib.baseboard_fab2(sch_1):page95_i59@mstr_discrete.fet_n_dual(chips)!FET_N_DUAL_SMLF-NTJD4001N,FET,A!1!!F2155!SOURCE(0)!!!!
S!IRQ_CPU1_VRHOT!Q7E6!6!@baseboard_fab2_lib.baseboard_fab2(sch_1):page95_i112@mstr_discrete.fet_n_dual(chips)!FET_N_DUAL_SMLF-NTJD4001N,FET,A!1!!F2154!DRAIN(0)!!!!
S!IRQ_CPU1_PROCHOT_G_N!Q7E6!2!@baseboard_fab2_lib.baseboard_fab2(sch_1):page95_i112@mstr_discrete.fet_n_dual(chips)!FET_N_DUAL_SMLF-NTJD4001N,FET,A!1!!F2154!GATE(0)!!!!
S!GND!Q7E6!1!@baseboard_fab2_lib.baseboard_fab2(sch_1):page95_i112@mstr_discrete.fet_n_dual(chips)!FET_N_DUAL_SMLF-NTJD4001N,FET,A!1!!F2154!SOURCE(0)!!!!
S!H_CPU1_PROCHOT_G_N!Q7E6!3!@baseboard_fab2_lib.baseboard_fab2(sch_1):page95_i69@mstr_discrete.fet_n_dual(chips)!FET_N_DUAL_SMLF-NTJD4001N,FET,A!1!!F2153!DRAIN(0)!!!!
S!IRQ_CPU1_VRHOT!Q7E6!5!@baseboard_fab2_lib.baseboard_fab2(sch_1):page95_i69@mstr_discrete.fet_n_dual(chips)!FET_N_DUAL_SMLF-NTJD4001N,FET,A!1!!F2153!GATE(0)!!!!
S!GND!Q7E6!4!@baseboard_fab2_lib.baseboard_fab2(sch_1):page95_i69@mstr_discrete.fet_n_dual(chips)!FET_N_DUAL_SMLF-NTJD4001N,FET,A!1!!F2153!SOURCE(0)!!!!
S!H_CPU1_MEMGHJ_MEMHOT_G_N!Q4B2!6!@baseboard_fab2_lib.baseboard_fab2(sch_1):page95_i32@mstr_discrete.fet_n_dual(chips)!FET_N_DUAL_SMLF-NTJD4001N,FET,A!1!!F2168!DRAIN(0)!!!!
S!FM_SYS_THROTTLE_LVC3!Q4B2!2!@baseboard_fab2_lib.baseboard_fab2(sch_1):page95_i32@mstr_discrete.fet_n_dual(chips)!FET_N_DUAL_SMLF-NTJD4001N,FET,A!1!!F2168!GATE(0)!!!!
S!GND!Q4B2!1!@baseboard_fab2_lib.baseboard_fab2(sch_1):page95_i32@mstr_discrete.fet_n_dual(chips)!FET_N_DUAL_SMLF-NTJD4001N,FET,A!1!!F2168!SOURCE(0)!!!!
S!H_CPU1_MEMKLM_MEMHOT_G_N!Q4B2!3!@baseboard_fab2_lib.baseboard_fab2(sch_1):page95_i33@mstr_discrete.fet_n_dual(chips)!FET_N_DUAL_SMLF-NTJD4001N,FET,A!1!!F2167!DRAIN(0)!!!!
S!FM_SYS_THROTTLE_LVC3!Q4B2!5!@baseboard_fab2_lib.baseboard_fab2(sch_1):page95_i33@mstr_discrete.fet_n_dual(chips)!FET_N_DUAL_SMLF-NTJD4001N,FET,A!1!!F2167!GATE(0)!!!!
S!GND!Q4B2!4!@baseboard_fab2_lib.baseboard_fab2(sch_1):page95_i33@mstr_discrete.fet_n_dual(chips)!FET_N_DUAL_SMLF-NTJD4001N,FET,A!1!!F2167!SOURCE(0)!!!!
S!FM_DIMM_EVENT_FET!Q4U1!6!@baseboard_fab2_lib.baseboard_fab2(sch_1):page94_i98@mstr_discrete.fet_n_dual(chips)!FET_N_DUAL_SMLF-NTJD4001N,FET,A!1!!F2166!DRAIN(0)!!!!
S!FM_DIMM_EVENT_COD_N!Q4U1!2!@baseboard_fab2_lib.baseboard_fab2(sch_1):page94_i98@mstr_discrete.fet_n_dual(chips)!FET_N_DUAL_SMLF-NTJD4001N,FET,A!1!!F2166!GATE(0)!!!!
S!GND!Q4U1!1!@baseboard_fab2_lib.baseboard_fab2(sch_1):page94_i98@mstr_discrete.fet_n_dual(chips)!FET_N_DUAL_SMLF-NTJD4001N,FET,A!1!!F2166!SOURCE(0)!!!!
S!FM_MEM_THERM_EVENT_LVT3_N!Q4U1!3!@baseboard_fab2_lib.baseboard_fab2(sch_1):page94_i102@mstr_discrete.fet_n_dual(chips)!FET_N_DUAL_SMLF-NTJD4001N,FET,A!1!!F2165!DRAIN(0)!!!!
S!FM_DIMM_EVENT_FET!Q4U1!5!@baseboard_fab2_lib.baseboard_fab2(sch_1):page94_i102@mstr_discrete.fet_n_dual(chips)!FET_N_DUAL_SMLF-NTJD4001N,FET,A!1!!F2165!GATE(0)!!!!
S!GND!Q4U1!4!@baseboard_fab2_lib.baseboard_fab2(sch_1):page94_i102@mstr_discrete.fet_n_dual(chips)!FET_N_DUAL_SMLF-NTJD4001N,FET,A!1!!F2165!SOURCE(0)!!!!
S!H_CPU0_MEMABC_MEMHOT_G_N!Q2U1!6!@baseboard_fab2_lib.baseboard_fab2(sch_1):page95_i28@mstr_discrete.fet_n_dual(chips)!FET_N_DUAL_SMLF-NTJD4001N,FET,A!1!!F2174!DRAIN(0)!!!!
S!FM_SYS_THROTTLE_LVC3!Q2U1!2!@baseboard_fab2_lib.baseboard_fab2(sch_1):page95_i28@mstr_discrete.fet_n_dual(chips)!FET_N_DUAL_SMLF-NTJD4001N,FET,A!1!!F2174!GATE(0)!!!!
S!GND!Q2U1!1!@baseboard_fab2_lib.baseboard_fab2(sch_1):page95_i28@mstr_discrete.fet_n_dual(chips)!FET_N_DUAL_SMLF-NTJD4001N,FET,A!1!!F2174!SOURCE(0)!!!!
S!H_CPU0_MEMDEF_MEMHOT_G_N!Q2U1!3!@baseboard_fab2_lib.baseboard_fab2(sch_1):page95_i113@mstr_discrete.fet_n_dual(chips)!FET_N_DUAL_SMLF-NTJD4001N,FET,A!1!!F2173!DRAIN(0)!!!!
S!FM_SYS_THROTTLE_LVC3!Q2U1!5!@baseboard_fab2_lib.baseboard_fab2(sch_1):page95_i113@mstr_discrete.fet_n_dual(chips)!FET_N_DUAL_SMLF-NTJD4001N,FET,A!1!!F2173!GATE(0)!!!!
S!GND!Q2U1!4!@baseboard_fab2_lib.baseboard_fab2(sch_1):page95_i113@mstr_discrete.fet_n_dual(chips)!FET_N_DUAL_SMLF-NTJD4001N,FET,A!1!!F2173!SOURCE(0)!!!!
S!H_CPU0_MEMABC_MEMHOT!Q3U1!6!@baseboard_fab2_lib.baseboard_fab2(sch_1):page94_i49@mstr_discrete.fet_n_dual(chips)!FET_N_DUAL_SMLF-NTJD4001N,FET,A!1!!F2172!DRAIN(0)!!!!
S!IRQ_PVDDQ_ABC_VRHOT_LVT3_N!Q3U1!2!@baseboard_fab2_lib.baseboard_fab2(sch_1):page94_i49@mstr_discrete.fet_n_dual(chips)!FET_N_DUAL_SMLF-NTJD4001N,FET,A!1!!F2172!GATE(0)!!!!
S!GND!Q3U1!1!@baseboard_fab2_lib.baseboard_fab2(sch_1):page94_i49@mstr_discrete.fet_n_dual(chips)!FET_N_DUAL_SMLF-NTJD4001N,FET,A!1!!F2172!SOURCE(0)!!!!
S!H_CPU0_MEMABC_MEMHOT_G_N!Q3U1!3!@baseboard_fab2_lib.baseboard_fab2(sch_1):page94_i89@mstr_discrete.fet_n_dual(chips)!FET_N_DUAL_SMLF-NTJD4001N,FET,A!1!!F2171!DRAIN(0)!!!!
S!H_CPU0_MEMABC_MEMHOT!Q3U1!5!@baseboard_fab2_lib.baseboard_fab2(sch_1):page94_i89@mstr_discrete.fet_n_dual(chips)!FET_N_DUAL_SMLF-NTJD4001N,FET,A!1!!F2171!GATE(0)!!!!
S!GND!Q3U1!4!@baseboard_fab2_lib.baseboard_fab2(sch_1):page94_i89@mstr_discrete.fet_n_dual(chips)!FET_N_DUAL_SMLF-NTJD4001N,FET,A!1!!F2171!SOURCE(0)!!!!
S!H_CPU0_MEMDEF_MEMHOT!Q7E1!6!@baseboard_fab2_lib.baseboard_fab2(sch_1):page94_i60@mstr_discrete.fet_n_dual(chips)!FET_N_DUAL_SMLF-NTJD4001N,FET,A!1!!F2162!DRAIN(0)!!!!
S!IRQ_PVDDQ_DEF_VRHOT_LVT3_N!Q7E1!2!@baseboard_fab2_lib.baseboard_fab2(sch_1):page94_i60@mstr_discrete.fet_n_dual(chips)!FET_N_DUAL_SMLF-NTJD4001N,FET,A!1!!F2162!GATE(0)!!!!
S!GND!Q7E1!1!@baseboard_fab2_lib.baseboard_fab2(sch_1):page94_i60@mstr_discrete.fet_n_dual(chips)!FET_N_DUAL_SMLF-NTJD4001N,FET,A!1!!F2162!SOURCE(0)!!!!
S!H_CPU0_MEMDEF_MEMHOT_G_N!Q7E1!3!@baseboard_fab2_lib.baseboard_fab2(sch_1):page94_i64@mstr_discrete.fet_n_dual(chips)!FET_N_DUAL_SMLF-NTJD4001N,FET,A!1!!F2161!DRAIN(0)!!!!
S!H_CPU0_MEMDEF_MEMHOT!Q7E1!5!@baseboard_fab2_lib.baseboard_fab2(sch_1):page94_i64@mstr_discrete.fet_n_dual(chips)!FET_N_DUAL_SMLF-NTJD4001N,FET,A!1!!F2161!GATE(0)!!!!
S!GND!Q7E1!4!@baseboard_fab2_lib.baseboard_fab2(sch_1):page94_i64@mstr_discrete.fet_n_dual(chips)!FET_N_DUAL_SMLF-NTJD4001N,FET,A!1!!F2161!SOURCE(0)!!!!
S!H_CPU1_MEMGHJ_MEMHOT!Q7E2!6!@baseboard_fab2_lib.baseboard_fab2(sch_1):page94_i69@mstr_discrete.fet_n_dual(chips)!FET_N_DUAL_SMLF-NTJD4001N,FET,A!1!!F2160!DRAIN(0)!!!!
S!IRQ_PVDDQ_GHJ_VRHOT_LVT3_N!Q7E2!2!@baseboard_fab2_lib.baseboard_fab2(sch_1):page94_i69@mstr_discrete.fet_n_dual(chips)!FET_N_DUAL_SMLF-NTJD4001N,FET,A!1!!F2160!GATE(0)!!!!
S!GND!Q7E2!1!@baseboard_fab2_lib.baseboard_fab2(sch_1):page94_i69@mstr_discrete.fet_n_dual(chips)!FET_N_DUAL_SMLF-NTJD4001N,FET,A!1!!F2160!SOURCE(0)!!!!
S!H_CPU1_MEMGHJ_MEMHOT_G_N!Q7E2!3!@baseboard_fab2_lib.baseboard_fab2(sch_1):page94_i75@mstr_discrete.fet_n_dual(chips)!FET_N_DUAL_SMLF-NTJD4001N,FET,A!1!!F2159!DRAIN(0)!!!!
S!H_CPU1_MEMGHJ_MEMHOT!Q7E2!5!@baseboard_fab2_lib.baseboard_fab2(sch_1):page94_i75@mstr_discrete.fet_n_dual(chips)!FET_N_DUAL_SMLF-NTJD4001N,FET,A!1!!F2159!GATE(0)!!!!
S!GND!Q7E2!4!@baseboard_fab2_lib.baseboard_fab2(sch_1):page94_i75@mstr_discrete.fet_n_dual(chips)!FET_N_DUAL_SMLF-NTJD4001N,FET,A!1!!F2159!SOURCE(0)!!!!
S!H_CPU1_MEMKLM_MEMHOT!Q4B1!6!@baseboard_fab2_lib.baseboard_fab2(sch_1):page94_i84@mstr_discrete.fet_n_dual(chips)!FET_N_DUAL_SMLF-NTJD4001N,FET,A!1!!F2170!DRAIN(0)!!!!
S!IRQ_PVDDQ_KLM_VRHOT_LVT3_N!Q4B1!2!@baseboard_fab2_lib.baseboard_fab2(sch_1):page94_i84@mstr_discrete.fet_n_dual(chips)!FET_N_DUAL_SMLF-NTJD4001N,FET,A!1!!F2170!GATE(0)!!!!
S!GND!Q4B1!1!@baseboard_fab2_lib.baseboard_fab2(sch_1):page94_i84@mstr_discrete.fet_n_dual(chips)!FET_N_DUAL_SMLF-NTJD4001N,FET,A!1!!F2170!SOURCE(0)!!!!
S!H_CPU1_MEMKLM_MEMHOT_G_N!Q4B1!3!@baseboard_fab2_lib.baseboard_fab2(sch_1):page94_i77@mstr_discrete.fet_n_dual(chips)!FET_N_DUAL_SMLF-NTJD4001N,FET,A!1!!F2169!DRAIN(0)!!!!
S!H_CPU1_MEMKLM_MEMHOT!Q4B1!5!@baseboard_fab2_lib.baseboard_fab2(sch_1):page94_i77@mstr_discrete.fet_n_dual(chips)!FET_N_DUAL_SMLF-NTJD4001N,FET,A!1!!F2169!GATE(0)!!!!
S!GND!Q4B1!4!@baseboard_fab2_lib.baseboard_fab2(sch_1):page94_i77@mstr_discrete.fet_n_dual(chips)!FET_N_DUAL_SMLF-NTJD4001N,FET,A!1!!F2169!SOURCE(0)!!!!
S!H_CPU0_PROCHOT_G_N!Q7E3!6!@baseboard_fab2_lib.baseboard_fab2(sch_1):page95_i52@mstr_discrete.fet_n_dual(chips)!FET_N_DUAL_SMLF-NTJD4001N,FET,A!1!!F2158!DRAIN(0)!!!!
S!FM_SYS_THROTTLE_LVC3!Q7E3!2!@baseboard_fab2_lib.baseboard_fab2(sch_1):page95_i52@mstr_discrete.fet_n_dual(chips)!FET_N_DUAL_SMLF-NTJD4001N,FET,A!1!!F2158!GATE(0)!!!!
S!GND!Q7E3!1!@baseboard_fab2_lib.baseboard_fab2(sch_1):page95_i52@mstr_discrete.fet_n_dual(chips)!FET_N_DUAL_SMLF-NTJD4001N,FET,A!1!!F2158!SOURCE(0)!!!!
S!H_CPU1_PROCHOT_G_N!Q7E3!3!@baseboard_fab2_lib.baseboard_fab2(sch_1):page95_i51@mstr_discrete.fet_n_dual(chips)!FET_N_DUAL_SMLF-NTJD4001N,FET,A!1!!F2157!DRAIN(0)!!!!
S!FM_SYS_THROTTLE_LVC3!Q7E3!5!@baseboard_fab2_lib.baseboard_fab2(sch_1):page95_i51@mstr_discrete.fet_n_dual(chips)!FET_N_DUAL_SMLF-NTJD4001N,FET,A!1!!F2157!GATE(0)!!!!
S!GND!Q7E3!4!@baseboard_fab2_lib.baseboard_fab2(sch_1):page95_i51@mstr_discrete.fet_n_dual(chips)!FET_N_DUAL_SMLF-NTJD4001N,FET,A!1!!F2157!SOURCE(0)!!!!
S!IRQ_SML0_ALERT_N!Q8E2!3!@baseboard_fab2_lib.baseboard_fab2(sch_1):page126_i13@mstr_discrete.fet_n(chips)!FET_N_SOT23LF-2N7002,FET,C7925A!!!F2135!DRN!!!!
S!RST_RSMRST_DLY!Q8E2!1!@baseboard_fab2_lib.baseboard_fab2(sch_1):page126_i13@mstr_discrete.fet_n(chips)!FET_N_SOT23LF-2N7002,FET,C7925A!!!F2135!GATE!!!!
S!GND!Q8E2!2!@baseboard_fab2_lib.baseboard_fab2(sch_1):page126_i13@mstr_discrete.fet_n(chips)!FET_N_SOT23LF-2N7002,FET,C7925A!!!F2135!SRC!!!!
S!FM_OC_DETECT_EN!Q1D2!3!@baseboard_fab2_lib.baseboard_fab2(sch_1):page200_i203@mstr_discrete.fet_n(chips)!FET_N_SOT23LF-2N7002,FET,C7925A!!!F2138!DRN!!!!
S!FM_OC_DETECT_EN_N!Q1D2!1!@baseboard_fab2_lib.baseboard_fab2(sch_1):page200_i203@mstr_discrete.fet_n(chips)!FET_N_SOT23LF-2N7002,FET,C7925A!!!F2138!GATE!!!!
S!GND!Q1D2!2!@baseboard_fab2_lib.baseboard_fab2(sch_1):page200_i203@mstr_discrete.fet_n(chips)!FET_N_SOT23LF-2N7002,FET,C7925A!!!F2138!SRC!!!!
S!RST_PLTRST_TOP_SWAP!Q8E1!3!@baseboard_fab2_lib.baseboard_fab2(sch_1):page136_i134@mstr_discrete.fet_n(chips)!FET_N_SOT23LF-2N7002,FET,C7925A!!!F2134!DRN!!!!
S!RST_PLTRST_N!Q8E1!1!@baseboard_fab2_lib.baseboard_fab2(sch_1):page136_i134@mstr_discrete.fet_n(chips)!FET_N_SOT23LF-2N7002,FET,C7925A!!!F2134!GATE!!!!
S!GND!Q8E1!2!@baseboard_fab2_lib.baseboard_fab2(sch_1):page136_i134@mstr_discrete.fet_n(chips)!FET_N_SOT23LF-2N7002,FET,C7925A!!!F2134!SRC!!!!
S!FM_PMBUS_ALERT_BUF_EN!Q2P1!3!@baseboard_fab2_lib.baseboard_fab2(sch_1):page170_i58@mstr_discrete.fet_n(chips)!FET_N_SOT23LF-2N7002,FET,C7925A!!!F2137!DRN!!!!
S!FM_PMBUS_ALERT_BUF_EN_N!Q2P1!1!@baseboard_fab2_lib.baseboard_fab2(sch_1):page170_i58@mstr_discrete.fet_n(chips)!FET_N_SOT23LF-2N7002,FET,C7925A!!!F2137!GATE!!!!
S!GND!Q2P1!2!@baseboard_fab2_lib.baseboard_fab2(sch_1):page170_i58@mstr_discrete.fet_n(chips)!FET_N_SOT23LF-2N7002,FET,C7925A!!!F2137!SRC!!!!
S!FM_FAST_PROCHOT_EN!Q8F2!3!@baseboard_fab2_lib.baseboard_fab2(sch_1):page170_i67@mstr_discrete.fet_n(chips)!FET_N_SOT23LF-2N7002,FET,C7925A!!!F2132!DRN!!!!
S!FM_FAST_PROCHOT_EN_N!Q8F2!1!@baseboard_fab2_lib.baseboard_fab2(sch_1):page170_i67@mstr_discrete.fet_n(chips)!FET_N_SOT23LF-2N7002,FET,C7925A!!!F2132!GATE!!!!
S!GND!Q8F2!2!@baseboard_fab2_lib.baseboard_fab2(sch_1):page170_i67@mstr_discrete.fet_n(chips)!FET_N_SOT23LF-2N7002,FET,C7925A!!!F2132!SRC!!!!
S!H_CPU0_FAST_WAKE_LVT3_N!Q2T2!3!@baseboard_fab2_lib.baseboard_fab2(sch_1):page157_i340@mstr_discrete.fet_n(chips)!FET_N_SOT23LF-2N7002,FET,C7925A!!!F2136!DRN!!!!
S!H_CPU0_FAST_WAKE!Q2T2!1!@baseboard_fab2_lib.baseboard_fab2(sch_1):page157_i340@mstr_discrete.fet_n(chips)!FET_N_SOT23LF-2N7002,FET,C7925A!!!F2136!GATE!!!!
S!GND!Q2T2!2!@baseboard_fab2_lib.baseboard_fab2(sch_1):page157_i340@mstr_discrete.fet_n(chips)!FET_N_SOT23LF-2N7002,FET,C7925A!!!F2136!SRC!!!!
S!FM_SPEAKER_PCH_N!Q9A3!3!@baseboard_fab2_lib.baseboard_fab2(sch_1):page175_i49@mstr_discrete.fet_n(chips)!FET_N_SOT23LF-2N7002,FET,C7925A!!!F2131!DRN!!!!
S!FM_BIOS_TOP_SWAP_SPKR!Q9A3!1!@baseboard_fab2_lib.baseboard_fab2(sch_1):page175_i49@mstr_discrete.fet_n(chips)!FET_N_SOT23LF-2N7002,FET,C7925A!!!F2131!GATE!!!!
S!GND!Q9A3!2!@baseboard_fab2_lib.baseboard_fab2(sch_1):page175_i49@mstr_discrete.fet_n(chips)!FET_N_SOT23LF-2N7002,FET,C7925A!!!F2131!SRC!!!!
S!FM_DUAL_BIOS_SEL_N!Q8F1!3!@baseboard_fab2_lib.baseboard_fab2(sch_1):page154_i126@mstr_discrete.fet_n(chips)!FET_N_SOT23LF-2N7002,FET,C7925A!!!F2133!DRN!!!!
S!FM_BACKUP_BIOS_SEL_N!Q8F1!1!@baseboard_fab2_lib.baseboard_fab2(sch_1):page154_i126@mstr_discrete.fet_n(chips)!FET_N_SOT23LF-2N7002,FET,C7925A!!!F2133!GATE!!!!
S!GND!Q8F1!2!@baseboard_fab2_lib.baseboard_fab2(sch_1):page154_i126@mstr_discrete.fet_n(chips)!FET_N_SOT23LF-2N7002,FET,C7925A!!!F2133!SRC!!!!
S!H_CPU1_KLM_MEMHOT_LVT3_R_N!U9G1!13!@baseboard_fab2_lib.baseboard_fab2(sch_1):page152_i1@mstr_digital.gtl2014(chips)!GTL2014_SM-IC,D66151-001!!!F2120!A0!!!!
S!H_CPU1_GHJ_MEMHOT_LVT3_R_N!U9G1!12!@baseboard_fab2_lib.baseboard_fab2(sch_1):page152_i1@mstr_digital.gtl2014(chips)!GTL2014_SM-IC,D66151-001!!!F2120!A1!!!!
S!H_CPU0_DEF_MEMHOT_LVT3_R_N!U9G1!10!@baseboard_fab2_lib.baseboard_fab2(sch_1):page152_i1@mstr_digital.gtl2014(chips)!GTL2014_SM-IC,D66151-001!!!F2120!A2!!!!
S!H_CPU0_ABC_MEMHOT_LVT3_R_N!U9G1!9!@baseboard_fab2_lib.baseboard_fab2(sch_1):page152_i1@mstr_digital.gtl2014(chips)!GTL2014_SM-IC,D66151-001!!!F2120!A3!!!!
S!H_CPU1_MEMKLM_MEMHOT_G_R_N!U9G1!2!@baseboard_fab2_lib.baseboard_fab2(sch_1):page152_i1@mstr_digital.gtl2014(chips)!GTL2014_SM-IC,D66151-001!!!F2120!B0!!!!
S!H_CPU1_MEMGHJ_MEMHOT_G_R_N!U9G1!3!@baseboard_fab2_lib.baseboard_fab2(sch_1):page152_i1@mstr_digital.gtl2014(chips)!GTL2014_SM-IC,D66151-001!!!F2120!B1!!!!
S!H_CPU0_MEMDEF_MEMHOT_G_R_N!U9G1!5!@baseboard_fab2_lib.baseboard_fab2(sch_1):page152_i1@mstr_digital.gtl2014(chips)!GTL2014_SM-IC,D66151-001!!!F2120!B2!!!!
S!H_CPU0_MEMABC_MEMHOT_G_R_N!U9G1!6!@baseboard_fab2_lib.baseboard_fab2(sch_1):page152_i1@mstr_digital.gtl2014(chips)!GTL2014_SM-IC,D66151-001!!!F2120!B3!!!!
S!PD_DIR_2!U9G1!1!@baseboard_fab2_lib.baseboard_fab2(sch_1):page152_i1@mstr_digital.gtl2014(chips)!GTL2014_SM-IC,D66151-001!!!F2120!DIR!!!!
S!GND!U9G1!7!@baseboard_fab2_lib.baseboard_fab2(sch_1):page152_i1@mstr_digital.gtl2014(chips)!GTL2014_SM-IC,D66151-001!!!F2120!GND(0)!!!!
S!GND!U9G1!8!@baseboard_fab2_lib.baseboard_fab2(sch_1):page152_i1@mstr_digital.gtl2014(chips)!GTL2014_SM-IC,D66151-001!!!F2120!GND(1)!!!!
S!GND!U9G1!11!@baseboard_fab2_lib.baseboard_fab2(sch_1):page152_i1@mstr_digital.gtl2014(chips)!GTL2014_SM-IC,D66151-001!!!F2120!GND(2)!!!!
S!P3V3!U9G1!14!@baseboard_fab2_lib.baseboard_fab2(sch_1):page152_i1@mstr_digital.gtl2014(chips)!GTL2014_SM-IC,D66151-001!!!F2120!VCC!!!!
S!P0V7_GTL2014_2!U9G1!4!@baseboard_fab2_lib.baseboard_fab2(sch_1):page152_i1@mstr_digital.gtl2014(chips)!GTL2014_SM-IC,D66151-001!!!F2120!VREF!!!!
S!FM_CPU1_PROCHOT_LVT3_R_N!U2T4!13!@baseboard_fab2_lib.baseboard_fab2(sch_1):page93_i30@mstr_digital.gtl2014(chips)!GTL2014_SM-IC,D66151-001!!!F2125!A0!!!!
S!FM_CPU0_PROCHOT_LVT3_R_N!U2T4!12!@baseboard_fab2_lib.baseboard_fab2(sch_1):page93_i30@mstr_digital.gtl2014(chips)!GTL2014_SM-IC,D66151-001!!!F2125!A1!!!!
S!FM_CPU_ERR1_LVT3_R_N!U2T4!10!@baseboard_fab2_lib.baseboard_fab2(sch_1):page93_i30@mstr_digital.gtl2014(chips)!GTL2014_SM-IC,D66151-001!!!F2125!A2!!!!
S!FM_CPU_ERR0_LVT3_R_N!U2T4!9!@baseboard_fab2_lib.baseboard_fab2(sch_1):page93_i30@mstr_digital.gtl2014(chips)!GTL2014_SM-IC,D66151-001!!!F2125!A3!!!!
S!H_CPU1_PROCHOT_G_R_N!U2T4!2!@baseboard_fab2_lib.baseboard_fab2(sch_1):page93_i30@mstr_digital.gtl2014(chips)!GTL2014_SM-IC,D66151-001!!!F2125!B0!!!!
S!H_CPU0_PROCHOT_G_R_N!U2T4!3!@baseboard_fab2_lib.baseboard_fab2(sch_1):page93_i30@mstr_digital.gtl2014(chips)!GTL2014_SM-IC,D66151-001!!!F2125!B1!!!!
S!H_CPU_ERR1_GTL_N!U2T4!5!@baseboard_fab2_lib.baseboard_fab2(sch_1):page93_i30@mstr_digital.gtl2014(chips)!GTL2014_SM-IC,D66151-001!!!F2125!B2!!!!
S!H_CPU_ERR0_GTL_N!U2T4!6!@baseboard_fab2_lib.baseboard_fab2(sch_1):page93_i30@mstr_digital.gtl2014(chips)!GTL2014_SM-IC,D66151-001!!!F2125!B3!!!!
S!PD_GTL2104_4_DIR!U2T4!1!@baseboard_fab2_lib.baseboard_fab2(sch_1):page93_i30@mstr_digital.gtl2014(chips)!GTL2014_SM-IC,D66151-001!!!F2125!DIR!!!!
S!GND!U2T4!7!@baseboard_fab2_lib.baseboard_fab2(sch_1):page93_i30@mstr_digital.gtl2014(chips)!GTL2014_SM-IC,D66151-001!!!F2125!GND(0)!!!!
S!GND!U2T4!8!@baseboard_fab2_lib.baseboard_fab2(sch_1):page93_i30@mstr_digital.gtl2014(chips)!GTL2014_SM-IC,D66151-001!!!F2125!GND(1)!!!!
S!GND!U2T4!11!@baseboard_fab2_lib.baseboard_fab2(sch_1):page93_i30@mstr_digital.gtl2014(chips)!GTL2014_SM-IC,D66151-001!!!F2125!GND(2)!!!!
S!P3V3!U2T4!14!@baseboard_fab2_lib.baseboard_fab2(sch_1):page93_i30@mstr_digital.gtl2014(chips)!GTL2014_SM-IC,D66151-001!!!F2125!VCC!!!!
S!P0V7_GTL2104_5_VREF!U2T4!4!@baseboard_fab2_lib.baseboard_fab2(sch_1):page93_i30@mstr_digital.gtl2014(chips)!GTL2014_SM-IC,D66151-001!!!F2125!VREF!!!!
S!PWRGD_DRAMPWRGD!U3P1!13!@baseboard_fab2_lib.baseboard_fab2(sch_1):page96_i42@mstr_digital.gtl2014(chips)!GTL2014_SM-IC,D66151-001!!!F2124!A0!!!!
S!PWRGD_DRAMPWRGD!U3P1!12!@baseboard_fab2_lib.baseboard_fab2(sch_1):page96_i42@mstr_digital.gtl2014(chips)!GTL2014_SM-IC,D66151-001!!!F2124!A1!!!!
S!RST_CPU0_LVC3_N!U3P1!10!@baseboard_fab2_lib.baseboard_fab2(sch_1):page96_i42@mstr_digital.gtl2014(chips)!GTL2014_SM-IC,D66151-001!!!F2124!A2!!!!
S!PWRGD_CPU0_LVC3!U3P1!9!@baseboard_fab2_lib.baseboard_fab2(sch_1):page96_i42@mstr_digital.gtl2014(chips)!GTL2014_SM-IC,D66151-001!!!F2124!A3!!!!
S!PWRGD_CPU0_DRAMPWROK_DEF_G!U3P1!2!@baseboard_fab2_lib.baseboard_fab2(sch_1):page96_i42@mstr_digital.gtl2014(chips)!GTL2014_SM-IC,D66151-001!!!F2124!B0!!!!
S!PWRGD_CPU0_DRAMPWROK_ABC_G!U3P1!3!@baseboard_fab2_lib.baseboard_fab2(sch_1):page96_i42@mstr_digital.gtl2014(chips)!GTL2014_SM-IC,D66151-001!!!F2124!B1!!!!
S!RST_CPU0_G_N!U3P1!5!@baseboard_fab2_lib.baseboard_fab2(sch_1):page96_i42@mstr_digital.gtl2014(chips)!GTL2014_SM-IC,D66151-001!!!F2124!B2!!!!
S!PWRGD_CPU0_G!U3P1!6!@baseboard_fab2_lib.baseboard_fab2(sch_1):page96_i42@mstr_digital.gtl2014(chips)!GTL2014_SM-IC,D66151-001!!!F2124!B3!!!!
S!PU_GTL2014_1_DIR!U3P1!1!@baseboard_fab2_lib.baseboard_fab2(sch_1):page96_i42@mstr_digital.gtl2014(chips)!GTL2014_SM-IC,D66151-001!!!F2124!DIR!!!!
S!GND!U3P1!7!@baseboard_fab2_lib.baseboard_fab2(sch_1):page96_i42@mstr_digital.gtl2014(chips)!GTL2014_SM-IC,D66151-001!!!F2124!GND(0)!!!!
S!GND!U3P1!8!@baseboard_fab2_lib.baseboard_fab2(sch_1):page96_i42@mstr_digital.gtl2014(chips)!GTL2014_SM-IC,D66151-001!!!F2124!GND(1)!!!!
S!GND!U3P1!11!@baseboard_fab2_lib.baseboard_fab2(sch_1):page96_i42@mstr_digital.gtl2014(chips)!GTL2014_SM-IC,D66151-001!!!F2124!GND(2)!!!!
S!P3V3_STBY!U3P1!14!@baseboard_fab2_lib.baseboard_fab2(sch_1):page96_i42@mstr_digital.gtl2014(chips)!GTL2014_SM-IC,D66151-001!!!F2124!VCC!!!!
S!PD_GTL2014_1_VREF!U3P1!4!@baseboard_fab2_lib.baseboard_fab2(sch_1):page96_i42@mstr_digital.gtl2014(chips)!GTL2014_SM-IC,D66151-001!!!F2124!VREF!!!!
S!PWRGD_DRAMPWRGD!U4C2!13!@baseboard_fab2_lib.baseboard_fab2(sch_1):page96_i46@mstr_digital.gtl2014(chips)!GTL2014_SM-IC,D66151-001!!!F2122!A0!!!!
S!PWRGD_DRAMPWRGD!U4C2!12!@baseboard_fab2_lib.baseboard_fab2(sch_1):page96_i46@mstr_digital.gtl2014(chips)!GTL2014_SM-IC,D66151-001!!!F2122!A1!!!!
S!RST_CPU1_LVC3_N!U4C2!10!@baseboard_fab2_lib.baseboard_fab2(sch_1):page96_i46@mstr_digital.gtl2014(chips)!GTL2014_SM-IC,D66151-001!!!F2122!A2!!!!
S!PWRGD_CPU1_LVC3!U4C2!9!@baseboard_fab2_lib.baseboard_fab2(sch_1):page96_i46@mstr_digital.gtl2014(chips)!GTL2014_SM-IC,D66151-001!!!F2122!A3!!!!
S!PWRGD_CPU1_DRAMPWROK_KLM_G!U4C2!2!@baseboard_fab2_lib.baseboard_fab2(sch_1):page96_i46@mstr_digital.gtl2014(chips)!GTL2014_SM-IC,D66151-001!!!F2122!B0!!!!
S!PWRGD_CPU1_DRAMPWROK_GHJ_G!U4C2!3!@baseboard_fab2_lib.baseboard_fab2(sch_1):page96_i46@mstr_digital.gtl2014(chips)!GTL2014_SM-IC,D66151-001!!!F2122!B1!!!!
S!RST_CPU1_G_N!U4C2!5!@baseboard_fab2_lib.baseboard_fab2(sch_1):page96_i46@mstr_digital.gtl2014(chips)!GTL2014_SM-IC,D66151-001!!!F2122!B2!!!!
S!PWRGD_CPU1_G!U4C2!6!@baseboard_fab2_lib.baseboard_fab2(sch_1):page96_i46@mstr_digital.gtl2014(chips)!GTL2014_SM-IC,D66151-001!!!F2122!B3!!!!
S!PU_GTL2014_2_DIR!U4C2!1!@baseboard_fab2_lib.baseboard_fab2(sch_1):page96_i46@mstr_digital.gtl2014(chips)!GTL2014_SM-IC,D66151-001!!!F2122!DIR!!!!
S!GND!U4C2!7!@baseboard_fab2_lib.baseboard_fab2(sch_1):page96_i46@mstr_digital.gtl2014(chips)!GTL2014_SM-IC,D66151-001!!!F2122!GND(0)!!!!
S!GND!U4C2!8!@baseboard_fab2_lib.baseboard_fab2(sch_1):page96_i46@mstr_digital.gtl2014(chips)!GTL2014_SM-IC,D66151-001!!!F2122!GND(1)!!!!
S!GND!U4C2!11!@baseboard_fab2_lib.baseboard_fab2(sch_1):page96_i46@mstr_digital.gtl2014(chips)!GTL2014_SM-IC,D66151-001!!!F2122!GND(2)!!!!
S!P3V3_STBY!U4C2!14!@baseboard_fab2_lib.baseboard_fab2(sch_1):page96_i46@mstr_digital.gtl2014(chips)!GTL2014_SM-IC,D66151-001!!!F2122!VCC!!!!
S!PD_GTL2014_2_VREF!U4C2!4!@baseboard_fab2_lib.baseboard_fab2(sch_1):page96_i46@mstr_digital.gtl2014(chips)!GTL2014_SM-IC,D66151-001!!!F2122!VREF!!!!
S!PWRGD_CPUPWRGD_R1!U3P2!13!@baseboard_fab2_lib.baseboard_fab2(sch_1):page92_i1@mstr_digital.gtl2014(chips)!GTL2014_SM-IC,D66151-001!!!F2123!A0!!!!
S!FM_CPU1_FIVR_FAULT_LVT3_R1_N!U3P2!12!@baseboard_fab2_lib.baseboard_fab2(sch_1):page92_i1@mstr_digital.gtl2014(chips)!GTL2014_SM-IC,D66151-001!!!F2123!A1!!!!
S!FM_CPU_CATERR_LVT3_R2_N!U3P2!10!@baseboard_fab2_lib.baseboard_fab2(sch_1):page92_i1@mstr_digital.gtl2014(chips)!GTL2014_SM-IC,D66151-001!!!F2123!A2!!!!
S!FM_CPU1_THERMTRIP_LVT3_R_N!U3P2!9!@baseboard_fab2_lib.baseboard_fab2(sch_1):page92_i1@mstr_digital.gtl2014(chips)!GTL2014_SM-IC,D66151-001!!!F2123!A3!!!!
S!PWRGD_CPUPWRGD_GTL!U3P2!2!@baseboard_fab2_lib.baseboard_fab2(sch_1):page92_i1@mstr_digital.gtl2014(chips)!GTL2014_SM-IC,D66151-001!!!F2123!B0!!!!
S!H_CPU1_FIVR_FAULT_G!U3P2!3!@baseboard_fab2_lib.baseboard_fab2(sch_1):page92_i1@mstr_digital.gtl2014(chips)!GTL2014_SM-IC,D66151-001!!!F2123!B1!!!!
S!H_CPU_CATERR_G_N!U3P2!5!@baseboard_fab2_lib.baseboard_fab2(sch_1):page92_i1@mstr_digital.gtl2014(chips)!GTL2014_SM-IC,D66151-001!!!F2123!B2!!!!
S!H_CPU1_THERMTRIP_G_N!U3P2!6!@baseboard_fab2_lib.baseboard_fab2(sch_1):page92_i1@mstr_digital.gtl2014(chips)!GTL2014_SM-IC,D66151-001!!!F2123!B3!!!!
S!PD_GTL2104_DIR_1!U3P2!1!@baseboard_fab2_lib.baseboard_fab2(sch_1):page92_i1@mstr_digital.gtl2014(chips)!GTL2014_SM-IC,D66151-001!!!F2123!DIR!!!!
S!GND!U3P2!7!@baseboard_fab2_lib.baseboard_fab2(sch_1):page92_i1@mstr_digital.gtl2014(chips)!GTL2014_SM-IC,D66151-001!!!F2123!GND(0)!!!!
S!GND!U3P2!8!@baseboard_fab2_lib.baseboard_fab2(sch_1):page92_i1@mstr_digital.gtl2014(chips)!GTL2014_SM-IC,D66151-001!!!F2123!GND(1)!!!!
S!GND!U3P2!11!@baseboard_fab2_lib.baseboard_fab2(sch_1):page92_i1@mstr_digital.gtl2014(chips)!GTL2014_SM-IC,D66151-001!!!F2123!GND(2)!!!!
S!P3V3!U3P2!14!@baseboard_fab2_lib.baseboard_fab2(sch_1):page92_i1@mstr_digital.gtl2014(chips)!GTL2014_SM-IC,D66151-001!!!F2123!VCC!!!!
S!P0V7_GTL2104_VREF_1!U3P2!4!@baseboard_fab2_lib.baseboard_fab2(sch_1):page92_i1@mstr_digital.gtl2014(chips)!GTL2014_SM-IC,D66151-001!!!F2123!VREF!!!!
S!FM_CPU_MSMI_LVT3_R_N!U7D2!13!@baseboard_fab2_lib.baseboard_fab2(sch_1):page92_i32@mstr_digital.gtl2014(chips)!GTL2014_SM-IC,D66151-001!!!F2121!A0!!!!
S!FM_CPU0_FIVR_FAULT_LVT3_R2_N!U7D2!12!@baseboard_fab2_lib.baseboard_fab2(sch_1):page92_i32@mstr_digital.gtl2014(chips)!GTL2014_SM-IC,D66151-001!!!F2121!A1!!!!
S!FM_CPU_ERR2_LVT3_R_N!U7D2!10!@baseboard_fab2_lib.baseboard_fab2(sch_1):page92_i32@mstr_digital.gtl2014(chips)!GTL2014_SM-IC,D66151-001!!!F2121!A2!!!!
S!FM_CPU0_THERMTRIP_LVT3_R_N!U7D2!9!@baseboard_fab2_lib.baseboard_fab2(sch_1):page92_i32@mstr_digital.gtl2014(chips)!GTL2014_SM-IC,D66151-001!!!F2121!A3!!!!
S!H_CPU_MSMI_G_N!U7D2!2!@baseboard_fab2_lib.baseboard_fab2(sch_1):page92_i32@mstr_digital.gtl2014(chips)!GTL2014_SM-IC,D66151-001!!!F2121!B0!!!!
S!H_CPU0_FIVR_FAULT_G!U7D2!3!@baseboard_fab2_lib.baseboard_fab2(sch_1):page92_i32@mstr_digital.gtl2014(chips)!GTL2014_SM-IC,D66151-001!!!F2121!B1!!!!
S!H_CPU_ERR2_GTL_N!U7D2!5!@baseboard_fab2_lib.baseboard_fab2(sch_1):page92_i32@mstr_digital.gtl2014(chips)!GTL2014_SM-IC,D66151-001!!!F2121!B2!!!!
S!H_CPU0_THERMTRIP_G_N!U7D2!6!@baseboard_fab2_lib.baseboard_fab2(sch_1):page92_i32@mstr_digital.gtl2014(chips)!GTL2014_SM-IC,D66151-001!!!F2121!B3!!!!
S!PD_GTL2104_DIR_0!U7D2!1!@baseboard_fab2_lib.baseboard_fab2(sch_1):page92_i32@mstr_digital.gtl2014(chips)!GTL2014_SM-IC,D66151-001!!!F2121!DIR!!!!
S!GND!U7D2!7!@baseboard_fab2_lib.baseboard_fab2(sch_1):page92_i32@mstr_digital.gtl2014(chips)!GTL2014_SM-IC,D66151-001!!!F2121!GND(0)!!!!
S!GND!U7D2!8!@baseboard_fab2_lib.baseboard_fab2(sch_1):page92_i32@mstr_digital.gtl2014(chips)!GTL2014_SM-IC,D66151-001!!!F2121!GND(1)!!!!
S!GND!U7D2!11!@baseboard_fab2_lib.baseboard_fab2(sch_1):page92_i32@mstr_digital.gtl2014(chips)!GTL2014_SM-IC,D66151-001!!!F2121!GND(2)!!!!
S!P3V3!U7D2!14!@baseboard_fab2_lib.baseboard_fab2(sch_1):page92_i32@mstr_digital.gtl2014(chips)!GTL2014_SM-IC,D66151-001!!!F2121!VCC!!!!
S!P0V7_GTL2104_VREF_0!U7D2!4!@baseboard_fab2_lib.baseboard_fab2(sch_1):page92_i32@mstr_digital.gtl2014(chips)!GTL2014_SM-IC,D66151-001!!!F2121!VREF!!!!
S!LED_P5V_STBY!DS9A6!1!@baseboard_fab2_lib.baseboard_fab2(sch_1):page177_i31@mstr_discrete.led(chips)!LED_A1LF-GREEN,IC,C97278-010!!!F2033!A!!!!
S!GND!DS9A6!2!@baseboard_fab2_lib.baseboard_fab2(sch_1):page177_i31@mstr_discrete.led(chips)!LED_A1LF-GREEN,IC,C97278-010!!!F2033!C!!!!
S!FM_PWR_LED_A!DS9A5!1!@baseboard_fab2_lib.baseboard_fab2(sch_1):page119_i179@mstr_discrete.led(chips)!LED_A1LF-GREEN,IC,C97278-010!!!F2034!A!!!!
S!FM_PWR_LED_K!DS9A5!2!@baseboard_fab2_lib.baseboard_fab2(sch_1):page119_i179@mstr_discrete.led(chips)!LED_A1LF-GREEN,IC,C97278-010!!!F2034!C!!!!
S!FM_HEARTBEAT_LED_A!DS9E1!1!@baseboard_fab2_lib.baseboard_fab2(sch_1):page147_i56@mstr_discrete.led(chips)!LED_A1LF-GREEN,IC,C97278-010!!!F2032!A!!!!
S!FM_HEARTBEAT_LED_K!DS9E1!2!@baseboard_fab2_lib.baseboard_fab2(sch_1):page147_i56@mstr_discrete.led(chips)!LED_A1LF-GREEN,IC,C97278-010!!!F2032!C!!!!
S!P12V_MB0_SW!EU1E3!5!@baseboard_fab2_lib.baseboard_fab2(sch_1):page200_i54@mstr_discrete.mosfetn_1d3s(chips)!MOSFETN_1D3S_SOT5-IC,G68777-001!!!F2019!D!!!!
S!A_HSC_GATE1_R!EU1E3!4!@baseboard_fab2_lib.baseboard_fab2(sch_1):page200_i54@mstr_discrete.mosfetn_1d3s(chips)!MOSFETN_1D3S_SOT5-IC,G68777-001!!!F2019!G!!!!
S!P12V_STBY!EU1E3!1!@baseboard_fab2_lib.baseboard_fab2(sch_1):page200_i54@mstr_discrete.mosfetn_1d3s(chips)!MOSFETN_1D3S_SOT5-IC,G68777-001!!!F2019!S1!!!!
S!P12V_STBY!EU1E3!2!@baseboard_fab2_lib.baseboard_fab2(sch_1):page200_i54@mstr_discrete.mosfetn_1d3s(chips)!MOSFETN_1D3S_SOT5-IC,G68777-001!!!F2019!S2!!!!
S!P12V_STBY!EU1E3!3!@baseboard_fab2_lib.baseboard_fab2(sch_1):page200_i54@mstr_discrete.mosfetn_1d3s(chips)!MOSFETN_1D3S_SOT5-IC,G68777-001!!!F2019!S3!!!!
S!P12V_MB0_SW!EU9R1!5!@baseboard_fab2_lib.baseboard_fab2(sch_1):page200_i57@mstr_discrete.mosfetn_1d3s(chips)!MOSFETN_1D3S_SOT5-IC,G68777-001!!!F2018!D!!!!
S!A_HSC_GATE2_R!EU9R1!4!@baseboard_fab2_lib.baseboard_fab2(sch_1):page200_i57@mstr_discrete.mosfetn_1d3s(chips)!MOSFETN_1D3S_SOT5-IC,G68777-001!!!F2018!G!!!!
S!P12V_STBY!EU9R1!1!@baseboard_fab2_lib.baseboard_fab2(sch_1):page200_i57@mstr_discrete.mosfetn_1d3s(chips)!MOSFETN_1D3S_SOT5-IC,G68777-001!!!F2018!S1!!!!
S!P12V_STBY!EU9R1!2!@baseboard_fab2_lib.baseboard_fab2(sch_1):page200_i57@mstr_discrete.mosfetn_1d3s(chips)!MOSFETN_1D3S_SOT5-IC,G68777-001!!!F2018!S2!!!!
S!P12V_STBY!EU9R1!3!@baseboard_fab2_lib.baseboard_fab2(sch_1):page200_i57@mstr_discrete.mosfetn_1d3s(chips)!MOSFETN_1D3S_SOT5-IC,G68777-001!!!F2018!S3!!!!
S!P12V_MB0_SW!EU1E1!5!@baseboard_fab2_lib.baseboard_fab2(sch_1):page200_i59@mstr_discrete.mosfetn_1d3s(chips)!MOSFETN_1D3S_SOT5-IC,G68777-001!!!F2020!D!!!!
S!A_HSC_GATE3_R!EU1E1!4!@baseboard_fab2_lib.baseboard_fab2(sch_1):page200_i59@mstr_discrete.mosfetn_1d3s(chips)!MOSFETN_1D3S_SOT5-IC,G68777-001!!!F2020!G!!!!
S!P12V_STBY!EU1E1!1!@baseboard_fab2_lib.baseboard_fab2(sch_1):page200_i59@mstr_discrete.mosfetn_1d3s(chips)!MOSFETN_1D3S_SOT5-IC,G68777-001!!!F2020!S1!!!!
S!P12V_STBY!EU1E1!2!@baseboard_fab2_lib.baseboard_fab2(sch_1):page200_i59@mstr_discrete.mosfetn_1d3s(chips)!MOSFETN_1D3S_SOT5-IC,G68777-001!!!F2020!S2!!!!
S!P12V_STBY!EU1E1!3!@baseboard_fab2_lib.baseboard_fab2(sch_1):page200_i59@mstr_discrete.mosfetn_1d3s(chips)!MOSFETN_1D3S_SOT5-IC,G68777-001!!!F2020!S3!!!!
S!FP_NMI_BTN_OUT_R_N!R2R9!1!@baseboard_fab2_lib.baseboard_fab2(sch_1):page157_i352@mstr_discrete.res(chips)!RES_0402-200.0,1%,1/16W,CHIP,GA!!!F897!A!!!!
S!FP_NMI_BTN_OUT_N!R2R9!2!@baseboard_fab2_lib.baseboard_fab2(sch_1):page157_i352@mstr_discrete.res(chips)!RES_0402-200.0,1%,1/16W,CHIP,GA!!!F897!B!!!!
S!PVCCIO_CPU0!R2T19!1!@baseboard_fab2_lib.baseboard_fab2(sch_1):page93_i63@mstr_discrete.res(chips)!RES_0402-200.0,1%,1/16W,CHIP,GA!!!F895!A!!!!
S!H_CPU_ERR0_GTL_R_N!R2T19!2!@baseboard_fab2_lib.baseboard_fab2(sch_1):page93_i63@mstr_discrete.res(chips)!RES_0402-200.0,1%,1/16W,CHIP,GA!!!F895!B!!!!
S!PVCCIO_CPU0!R2T26!1!@baseboard_fab2_lib.baseboard_fab2(sch_1):page93_i87@mstr_discrete.res(chips)!RES_0402-200.0,1%,1/16W,CHIP,GA!!!F894!A!!!!
S!H_CPU_ERR1_GTL_R_N!R2T26!2!@baseboard_fab2_lib.baseboard_fab2(sch_1):page93_i87@mstr_discrete.res(chips)!RES_0402-200.0,1%,1/16W,CHIP,GA!!!F894!B!!!!
S!FP_PWR_BTN_R_N!R1L31!1!@baseboard_fab2_lib.baseboard_fab2(sch_1):page175_i4@mstr_discrete.res(chips)!RES_0402-200.0,1%,1/16W,CHIP,GA!!!F899!A!!!!
S!FP_PWR_BTN_R1_N!R1L31!2!@baseboard_fab2_lib.baseboard_fab2(sch_1):page175_i4@mstr_discrete.res(chips)!RES_0402-200.0,1%,1/16W,CHIP,GA!!!F899!B!!!!
S!FM_DEBUG_RST_BTN_N!R1L22!1!@baseboard_fab2_lib.baseboard_fab2(sch_1):page175_i22@mstr_discrete.res(chips)!RES_0402-200.0,1%,1/16W,CHIP,GA!!!F900!A!!!!
S!FP_RST_BTN_R_N!R1L22!2!@baseboard_fab2_lib.baseboard_fab2(sch_1):page175_i22@mstr_discrete.res(chips)!RES_0402-200.0,1%,1/16W,CHIP,GA!!!F900!B!!!!
S!SPI_CS0_PRIMARY_N!R2T13!1!@baseboard_fab2_lib.baseboard_fab2(sch_1):page154_i101@mstr_discrete.res(chips)!RES_0402-200.0,1%,1/16W,CHIP,GA!!!F896!A!!!!
S!SPI_CS0_PRIMARY_R_N!R2T13!2!@baseboard_fab2_lib.baseboard_fab2(sch_1):page154_i101@mstr_discrete.res(chips)!RES_0402-200.0,1%,1/16W,CHIP,GA!!!F896!B!!!!
S!RST_PCIE_CPU_DEV3_R_N!R9E12!1!@baseboard_fab2_lib.baseboard_fab2(sch_1):page187_i153@mstr_discrete.res(chips)!RES_0402-200.0,1%,1/16W,CHIP,GA!!!F890!A!!!!
S!RST_PCIE_CPU_DEV3_N!R9E12!2!@baseboard_fab2_lib.baseboard_fab2(sch_1):page187_i153@mstr_discrete.res(chips)!RES_0402-200.0,1%,1/16W,CHIP,GA!!!F890!B!!!!
S!RST_PCIE_CPU_DEV2_R_N!R9E11!1!@baseboard_fab2_lib.baseboard_fab2(sch_1):page187_i150@mstr_discrete.res(chips)!RES_0402-200.0,1%,1/16W,CHIP,GA!!!F891!A!!!!
S!RST_PCIE_CPU_DEV2_N!R9E11!2!@baseboard_fab2_lib.baseboard_fab2(sch_1):page187_i150@mstr_discrete.res(chips)!RES_0402-200.0,1%,1/16W,CHIP,GA!!!F891!B!!!!
S!RST_PCIE_CPU_DEV1_R_N!R9E10!1!@baseboard_fab2_lib.baseboard_fab2(sch_1):page187_i145@mstr_discrete.res(chips)!RES_0402-200.0,1%,1/16W,CHIP,GA!!!F892!A!!!!
S!RST_PCIE_CPU_DEV1_N!R9E10!2!@baseboard_fab2_lib.baseboard_fab2(sch_1):page187_i145@mstr_discrete.res(chips)!RES_0402-200.0,1%,1/16W,CHIP,GA!!!F892!B!!!!
S!PVCCIO_CPU0!R2T37!1!@baseboard_fab2_lib.baseboard_fab2(sch_1):page92_i94@mstr_discrete.res(chips)!RES_0402-200.0,1%,1/16W,CHIP,GA!!!F893!A!!!!
S!H_CPU_ERR2_G_R_N!R2T37!2!@baseboard_fab2_lib.baseboard_fab2(sch_1):page92_i94@mstr_discrete.res(chips)!RES_0402-200.0,1%,1/16W,CHIP,GA!!!F893!B!!!!
S!RST_PCIE_CPU_DEV0_N!R1M14!1!@baseboard_fab2_lib.baseboard_fab2(sch_1):page186_i220@mstr_discrete.res(chips)!RES_0402-200.0,1%,1/16W,CHIP,GA!!!F898!A!!!!
S!RST_PCIE_CPU_DEV0_R_N!R1M14!2!@baseboard_fab2_lib.baseboard_fab2(sch_1):page186_i220@mstr_discrete.res(chips)!RES_0402-200.0,1%,1/16W,CHIP,GA!!!F898!B!!!!
S!VR_FET_SW_P12V_PVCCIN_CPU1_R!R1B20!1!@baseboard_fab2_lib.baseboard_fab2(sch_1):page209_i39@mstr_discrete.res(chips)!RES_2010-0.001,1%,1W,CHIP,E309A!!!F250!A!!!!
S!VR_FET_SW_P12V_STBY_PVCCIN_CPU1!R1B20!2!@baseboard_fab2_lib.baseboard_fab2(sch_1):page209_i39@mstr_discrete.res(chips)!RES_2010-0.001,1%,1W,CHIP,E309A!!!F250!B!!!!
S!VR_FET_SW_P12V_PVCCIN_CPU0_R!R4C6!1!@baseboard_fab2_lib.baseboard_fab2(sch_1):page204_i45@mstr_discrete.res(chips)!RES_2010-0.001,1%,1W,CHIP,E309A!!!F249!A!!!!
S!VR_FET_SW_P12V_STBY_PVCCIN_CPU0!R4C6!2!@baseboard_fab2_lib.baseboard_fab2(sch_1):page204_i45@mstr_discrete.res(chips)!RES_2010-0.001,1%,1W,CHIP,E309A!!!F249!B!!!!
S!P12V_PSU!R1D49!1!@baseboard_fab2_lib.baseboard_fab2(sch_1):page200_i50@mstr_discrete.res_pwr(chips)!RES_PWR_6PAD-0.001,1%,3W,CHIP,A!!!F248!\1\!!!!
S!P12V_MB0_SW!R1D49!2!@baseboard_fab2_lib.baseboard_fab2(sch_1):page200_i50@mstr_discrete.res_pwr(chips)!RES_PWR_6PAD-0.001,1%,3W,CHIP,A!!!F248!\2\!!!!
S!P12V_HSC_SENP0!R1D49!3!@baseboard_fab2_lib.baseboard_fab2(sch_1):page200_i50@mstr_discrete.res_pwr(chips)!RES_PWR_6PAD-0.001,1%,3W,CHIP,A!!!F248!\3\!!!!
S!P12V_HSC_SENN0!R1D49!4!@baseboard_fab2_lib.baseboard_fab2(sch_1):page200_i50@mstr_discrete.res_pwr(chips)!RES_PWR_6PAD-0.001,1%,3W,CHIP,A!!!F248!\4\!!!!
S!P12V_PSU!R1D49!5!@baseboard_fab2_lib.baseboard_fab2(sch_1):page200_i50@mstr_discrete.res_pwr(chips)!RES_PWR_6PAD-0.001,1%,3W,CHIP,A!!!F248!\5\!!!!
S!P12V_MB0_SW!R1D49!6!@baseboard_fab2_lib.baseboard_fab2(sch_1):page200_i50@mstr_discrete.res_pwr(chips)!RES_PWR_6PAD-0.001,1%,3W,CHIP,A!!!F248!\6\!!!!
S!P12V_PSU!R9R1!1!@baseboard_fab2_lib.baseboard_fab2(sch_1):page200_i49@mstr_discrete.res_pwr(chips)!RES_PWR_6PAD-0.001,1%,3W,CHIP,A!!!F247!\1\!!!!
S!P12V_MB0_SW!R9R1!2!@baseboard_fab2_lib.baseboard_fab2(sch_1):page200_i49@mstr_discrete.res_pwr(chips)!RES_PWR_6PAD-0.001,1%,3W,CHIP,A!!!F247!\2\!!!!
S!P12V_HSC_SENP1!R9R1!3!@baseboard_fab2_lib.baseboard_fab2(sch_1):page200_i49@mstr_discrete.res_pwr(chips)!RES_PWR_6PAD-0.001,1%,3W,CHIP,A!!!F247!\3\!!!!
S!P12V_HSC_SENN1!R9R1!4!@baseboard_fab2_lib.baseboard_fab2(sch_1):page200_i49@mstr_discrete.res_pwr(chips)!RES_PWR_6PAD-0.001,1%,3W,CHIP,A!!!F247!\4\!!!!
S!P12V_PSU!R9R1!5!@baseboard_fab2_lib.baseboard_fab2(sch_1):page200_i49@mstr_discrete.res_pwr(chips)!RES_PWR_6PAD-0.001,1%,3W,CHIP,A!!!F247!\5\!!!!
S!P12V_MB0_SW!R9R1!6!@baseboard_fab2_lib.baseboard_fab2(sch_1):page200_i49@mstr_discrete.res_pwr(chips)!RES_PWR_6PAD-0.001,1%,3W,CHIP,A!!!F247!\6\!!!!
